FILE_TYPE=EXPANDEDPARTLIST;
{ Packager-XL run on 05-Sep-2022 AT 15:23:30 }
DIRECTIVES
 PST_VERSION='PST_HDL_CENTRIC_VERSION_0';
 ROOT_DRAWING='TIMECARD';
 POST_TIME='05-Sep-2022 AT 15:23:30';
 SOURCE_TOOL='PACKAGER_XL';
END_DIRECTIVES;

PART_NAME
 C1 'CAPACITOR-G105-0B104-EK,0.1UF,A':;

SECTION_NUMBER 1
 '@TIMECARD_LIB.TIMECARD(SCH_1):PAGE5_I171@PASSIVE.CAPACITOR(CHIPS)':
 C_PATH='@timecard_lib.timecard(sch_1):page5_i171@passive.capacitor(chips)',
 P_PATH='@timecard_lib.timecard(sch_1):page16_i171@passive.capacitor(chips)',
 PATH='I171',
 DRAWING='@TIMECARD_LIB.TIMECARD(SCH_1):PAGE5',
 PACKAGE='0402',
 PHYS_PAGE='16',
 XY='(-1850,4250)',
 ROT='0',
 VER='2',
 CDS_LIB='passive',
 CDS_PART_NAME='CAPACITOR-G105-0B104-EK,0.1UF,A',
 TOLERANCE='10%',
 CLS_PN='G105-0B104-EK',
 VOLTAGE='25V',
 VALUE='0.1UF',
 PRIM_FILE='./archive_libs/passive/capacitor/chips/chips.prt';

PART_NAME
 C2 'CAPACITOR-G105-0B104-EK,0.1UF,A':;

SECTION_NUMBER 1
 '@TIMECARD_LIB.TIMECARD(SCH_1):PAGE15_I160@PASSIVE.CAPACITOR(CHIPS)':
 C_PATH='@timecard_lib.timecard(sch_1):page15_i160@passive.capacitor(chips)',
 P_PATH='@timecard_lib.timecard(sch_1):page27_i160@passive.capacitor(chips)',
 PATH='I160',
 DRAWING='@TIMECARD_LIB.TIMECARD(SCH_1):PAGE15',
 PACKAGE='0402',
 PHYS_PAGE='27',
 XY='(-8950,9000)',
 ROT='0',
 VER='2',
 CDS_LIB='passive',
 CDS_PART_NAME='CAPACITOR-G105-0B104-EK,0.1UF,A',
 TOLERANCE='10%',
 CLS_PN='G105-0B104-EK',
 VOLTAGE='25V',
 VALUE='0.1UF',
 PRIM_FILE='./archive_libs/passive/capacitor/chips/chips.prt';

PART_NAME
 C3 'CAPACITOR-G105-0B104-EK,0.1UF,A':;

SECTION_NUMBER 1
 '@TIMECARD_LIB.TIMECARD(SCH_1):PAGE15_I156@PASSIVE.CAPACITOR(CHIPS)':
 C_PATH='@timecard_lib.timecard(sch_1):page15_i156@passive.capacitor(chips)',
 P_PATH='@timecard_lib.timecard(sch_1):page27_i156@passive.capacitor(chips)',
 PATH='I156',
 DRAWING='@TIMECARD_LIB.TIMECARD(SCH_1):PAGE15',
 PACKAGE='0402',
 PHYS_PAGE='27',
 XY='(-9000,7400)',
 ROT='0',
 VER='2',
 CDS_LIB='passive',
 CDS_PART_NAME='CAPACITOR-G105-0B104-EK,0.1UF,A',
 TOLERANCE='10%',
 CLS_PN='G105-0B104-EK',
 VOLTAGE='25V',
 VALUE='0.1UF',
 PRIM_FILE='./archive_libs/passive/capacitor/chips/chips.prt';

PART_NAME
 C4 'CAPACITOR-G104-0F224-BK,0.22UFA':;

SECTION_NUMBER 1
 '@TIMECARD_LIB.TIMECARD(SCH_1):PAGE15_I172@PASSIVE.CAPACITOR(CHIPS)':
 C_PATH='@timecard_lib.timecard(sch_1):page15_i172@passive.capacitor(chips)',
 P_PATH='@timecard_lib.timecard(sch_1):page27_i172@passive.capacitor(chips)',
 PATH='I172',
 DRAWING='@TIMECARD_LIB.TIMECARD(SCH_1):PAGE15',
 PACKAGE='0201',
 PHYS_PAGE='27',
 XY='(-7550,7700)',
 ROT='0',
 VER='1',
 CDS_LIB='passive',
 CDS_PART_NAME='CAPACITOR-G104-0F224-BK,0.22UFA',
 TOLERANCE='10%',
 CLS_PN='G104-0F224-BK',
 VOLTAGE='6.3V',
 VALUE='0.22UF',
 PRIM_FILE='./archive_libs/passive/capacitor/chips/chips.prt';

PART_NAME
 C5 'CAPACITOR-G105-0B104-EK,0.1UF,A':;

SECTION_NUMBER 1
 '@TIMECARD_LIB.TIMECARD(SCH_1):PAGE15_I211@PASSIVE.CAPACITOR(CHIPS)':
 C_PATH='@timecard_lib.timecard(sch_1):page15_i211@passive.capacitor(chips)',
 P_PATH='@timecard_lib.timecard(sch_1):page27_i211@passive.capacitor(chips)',
 PATH='I211',
 DRAWING='@TIMECARD_LIB.TIMECARD(SCH_1):PAGE15',
 PACKAGE='0402',
 PHYS_PAGE='27',
 XY='(-5200,6900)',
 ROT='0',
 VER='2',
 CDS_LIB='passive',
 CDS_PART_NAME='CAPACITOR-G105-0B104-EK,0.1UF,A',
 TOLERANCE='10%',
 CLS_PN='G105-0B104-EK',
 VOLTAGE='25V',
 VALUE='0.1UF',
 PRIM_FILE='./archive_libs/passive/capacitor/chips/chips.prt';

PART_NAME
 C6 'CAPACITOR-G107-0F106-EM,10UF,2A':;

SECTION_NUMBER 1
 '@TIMECARD_LIB.TIMECARD(SCH_1):PAGE15_I196@PASSIVE.CAPACITOR(CHIPS)':
 C_PATH='@timecard_lib.timecard(sch_1):page15_i196@passive.capacitor(chips)',
 P_PATH='@timecard_lib.timecard(sch_1):page27_i196@passive.capacitor(chips)',
 PATH='I196',
 DRAWING='@TIMECARD_LIB.TIMECARD(SCH_1):PAGE15',
 PACKAGE='0402',
 PHYS_PAGE='27',
 XY='(-5000,8250)',
 ROT='0',
 VER='2',
 CDS_LIB='passive',
 CDS_PART_NAME='CAPACITOR-G107-0F106-EM,10UF,2A',
 TOLERANCE='20%',
 CLS_PN='G107-0F106-EM',
 VOLTAGE='25V',
 VALUE='10UF',
 PRIM_FILE='./archive_libs/passive/capacitor/chips/chips.prt';

PART_NAME
 C7 'CAPACITOR-G105-0B104-EK,0.1UF,A':;

SECTION_NUMBER 1
 '@TIMECARD_LIB.TIMECARD(SCH_1):PAGE15_I185@PASSIVE.CAPACITOR(CHIPS)':
 C_PATH='@timecard_lib.timecard(sch_1):page15_i185@passive.capacitor(chips)',
 P_PATH='@timecard_lib.timecard(sch_1):page27_i185@passive.capacitor(chips)',
 PATH='I185',
 DRAWING='@TIMECARD_LIB.TIMECARD(SCH_1):PAGE15',
 PACKAGE='0402',
 PHYS_PAGE='27',
 XY='(-4250,6950)',
 ROT='0',
 VER='2',
 CDS_LIB='passive',
 CDS_PART_NAME='CAPACITOR-G105-0B104-EK,0.1UF,A',
 TOLERANCE='10%',
 CLS_PN='G105-0B104-EK',
 VOLTAGE='25V',
 VALUE='0.1UF',
 PRIM_FILE='./archive_libs/passive/capacitor/chips/chips.prt';

PART_NAME
 C8 'CAPACITOR-G104-0B103-EK,0.01UFA':;

SECTION_NUMBER 1
 '@TIMECARD_LIB.TIMECARD(SCH_1):PAGE15_I201@PASSIVE.CAPACITOR(CHIPS)':
 C_PATH='@timecard_lib.timecard(sch_1):page15_i201@passive.capacitor(chips)',
 P_PATH='@timecard_lib.timecard(sch_1):page27_i201@passive.capacitor(chips)',
 PATH='I201',
 DRAWING='@TIMECARD_LIB.TIMECARD(SCH_1):PAGE15',
 PACKAGE='0402',
 PHYS_PAGE='27',
 XY='(-4000,8250)',
 ROT='0',
 VER='2',
 CDS_LIB='passive',
 CDS_PART_NAME='CAPACITOR-G104-0B103-EK,0.01UFA',
 TOLERANCE='10%',
 CLS_PN='G104-0B103-EK',
 VOLTAGE='25V',
 VALUE='0.01UF',
 PRIM_FILE='./archive_libs/passive/capacitor/chips/chips.prt';

PART_NAME
 C9 'CAPACITOR-G107-0F106-EM,10UF,2A':;

SECTION_NUMBER 1
 '@TIMECARD_LIB.TIMECARD(SCH_1):PAGE15_I206@PASSIVE.CAPACITOR(CHIPS)':
 C_PATH='@timecard_lib.timecard(sch_1):page15_i206@passive.capacitor(chips)',
 P_PATH='@timecard_lib.timecard(sch_1):page27_i206@passive.capacitor(chips)',
 PATH='I206',
 DRAWING='@TIMECARD_LIB.TIMECARD(SCH_1):PAGE15',
 PACKAGE='0805',
 PHYS_PAGE='27',
 XY='(-1800,8650)',
 ROT='0',
 VER='2',
 CDS_LIB='passive',
 CDS_PART_NAME='CAPACITOR-G107-0F106-EM,10UF,2A',
 TOLERANCE='20%',
 CLS_PN='G107-0F106-EM',
 VOLTAGE='25V',
 VALUE='10UF',
 PRIM_FILE='./archive_libs/passive/capacitor/chips/chips.prt';

PART_NAME
 C10 'CAPACITOR-G107-0F106-EM,10UF,2A':;

SECTION_NUMBER 1
 '@TIMECARD_LIB.TIMECARD(SCH_1):PAGE15_I207@PASSIVE.CAPACITOR(CHIPS)':
 C_PATH='@timecard_lib.timecard(sch_1):page15_i207@passive.capacitor(chips)',
 P_PATH='@timecard_lib.timecard(sch_1):page27_i207@passive.capacitor(chips)',
 PATH='I207',
 DRAWING='@TIMECARD_LIB.TIMECARD(SCH_1):PAGE15',
 PACKAGE='0805',
 PHYS_PAGE='27',
 XY='(-1300,8650)',
 ROT='0',
 VER='2',
 CDS_LIB='passive',
 CDS_PART_NAME='CAPACITOR-G107-0F106-EM,10UF,2A',
 TOLERANCE='20%',
 CLS_PN='G107-0F106-EM',
 VOLTAGE='25V',
 VALUE='10UF',
 PRIM_FILE='./archive_libs/passive/capacitor/chips/chips.prt';

PART_NAME
 C11 'CAPACITOR-G104-0B101-FK,100PF,A':;

SECTION_NUMBER 1
 '@TIMECARD_LIB.TIMECARD(SCH_1):PAGE516_I29@PASSIVE.CAPACITOR(CHIPS)':
 C_PATH='@timecard_lib.timecard(sch_1):page516_i29@passive.capacitor(chips)',
 P_PATH='@timecard_lib.timecard(sch_1):page32_i29@passive.capacitor(chips)',
 PATH='I29',
 DRAWING='@TIMECARD_LIB.TIMECARD(SCH_1):PAGE516',
 PACKAGE='0201',
 PHYS_PAGE='32',
 XY='(-4000,6100)',
 ROT='0',
 VER='2',
 CDS_LIB='passive',
 CDS_PART_NAME='CAPACITOR-G104-0B101-FK,100PF,A',
 TOLERANCE='10%',
 CLS_PN='G104-0B101-FK',
 VOLTAGE='50V',
 VALUE='100PF',
 PRIM_FILE='./archive_libs/passive/capacitor/chips/chips.prt';

PART_NAME
 C12 'CAPACITOR-G105-0B104-CK,0.1UF,A':;

SECTION_NUMBER 1
 '@TIMECARD_LIB.TIMECARD(SCH_1):PAGE516_I32@PASSIVE.CAPACITOR(CHIPS)':
 C_PATH='@timecard_lib.timecard(sch_1):page516_i32@passive.capacitor(chips)',
 P_PATH='@timecard_lib.timecard(sch_1):page32_i32@passive.capacitor(chips)',
 PATH='I32',
 DRAWING='@TIMECARD_LIB.TIMECARD(SCH_1):PAGE516',
 PACKAGE='0402',
 PHYS_PAGE='32',
 XY='(-2700,6750)',
 ROT='0',
 VER='2',
 CDS_LIB='passive',
 CDS_PART_NAME='CAPACITOR-G105-0B104-CK,0.1UF,A',
 TOLERANCE='10%',
 CLS_PN='G105-0B104-CK',
 VOLTAGE='10V',
 VALUE='0.1UF',
 PRIM_FILE='./archive_libs/passive/capacitor/chips/chips.prt';

PART_NAME
 C13 'CAPACITOR-G107-0F226-CM,22UF,2A':;

SECTION_NUMBER 1
 '@TIMECARD_LIB.TIMECARD(SCH_1):PAGE516_I33@PASSIVE.CAPACITOR(CHIPS)':
 C_PATH='@timecard_lib.timecard(sch_1):page516_i33@passive.capacitor(chips)',
 P_PATH='@timecard_lib.timecard(sch_1):page32_i33@passive.capacitor(chips)',
 PATH='I33',
 DRAWING='@TIMECARD_LIB.TIMECARD(SCH_1):PAGE516',
 PACKAGE='0805',
 PHYS_PAGE='32',
 XY='(-2150,6750)',
 ROT='0',
 VER='2',
 CDS_LIB='passive',
 CDS_PART_NAME='CAPACITOR-G107-0F226-CM,22UF,2A',
 TOLERANCE='20%',
 CLS_PN='G107-0F226-CM',
 VOLTAGE='10V',
 VALUE='22UF',
 PRIM_FILE='./archive_libs/passive/capacitor/chips/chips.prt';

PART_NAME
 C14 'CAPACITOR-G107-0F226-CM,22UF,2A':;

SECTION_NUMBER 1
 '@TIMECARD_LIB.TIMECARD(SCH_1):PAGE516_I35@PASSIVE.CAPACITOR(CHIPS)':
 C_PATH='@timecard_lib.timecard(sch_1):page516_i35@passive.capacitor(chips)',
 P_PATH='@timecard_lib.timecard(sch_1):page32_i35@passive.capacitor(chips)',
 PATH='I35',
 DRAWING='@TIMECARD_LIB.TIMECARD(SCH_1):PAGE516',
 PACKAGE='0805',
 PHYS_PAGE='32',
 XY='(-1650,6750)',
 ROT='0',
 VER='2',
 CDS_LIB='passive',
 CDS_PART_NAME='CAPACITOR-G107-0F226-CM,22UF,2A',
 TOLERANCE='20%',
 CLS_PN='G107-0F226-CM',
 VOLTAGE='10V',
 VALUE='22UF',
 PRIM_FILE='./archive_libs/passive/capacitor/chips/chips.prt';

PART_NAME
 C15 'CAPACITOR-G107-0F226-CM,22UF,2A':;

SECTION_NUMBER 1
 '@TIMECARD_LIB.TIMECARD(SCH_1):PAGE516_I40@PASSIVE.CAPACITOR(CHIPS)':
 C_PATH='@timecard_lib.timecard(sch_1):page516_i40@passive.capacitor(chips)',
 P_PATH='@timecard_lib.timecard(sch_1):page32_i40@passive.capacitor(chips)',
 PATH='I40',
 DRAWING='@TIMECARD_LIB.TIMECARD(SCH_1):PAGE516',
 PACKAGE='0805',
 PHYS_PAGE='32',
 XY='(-1150,6750)',
 ROT='0',
 VER='2',
 CDS_LIB='passive',
 CDS_PART_NAME='CAPACITOR-G107-0F226-CM,22UF,2A',
 TOLERANCE='20%',
 CLS_PN='G107-0F226-CM',
 VOLTAGE='10V',
 VALUE='22UF',
 PRIM_FILE='./archive_libs/passive/capacitor/chips/chips.prt';

PART_NAME
 C16 'CAPACITOR-G104-0B101-FK,100PF,A':;

SECTION_NUMBER 1
 '@TIMECARD_LIB.TIMECARD(SCH_1):PAGE517_I30@PASSIVE.CAPACITOR(CHIPS)':
 C_PATH='@timecard_lib.timecard(sch_1):page517_i30@passive.capacitor(chips)',
 P_PATH='@timecard_lib.timecard(sch_1):page28_i30@passive.capacitor(chips)',
 PATH='I30',
 DRAWING='@TIMECARD_LIB.TIMECARD(SCH_1):PAGE517',
 PACKAGE='0201',
 PHYS_PAGE='28',
 XY='(-3750,5300)',
 ROT='0',
 VER='2',
 CDS_LIB='passive',
 CDS_PART_NAME='CAPACITOR-G104-0B101-FK,100PF,A',
 TOLERANCE='10%',
 CLS_PN='G104-0B101-FK',
 VOLTAGE='50V',
 VALUE='100PF',
 PRIM_FILE='./archive_libs/passive/capacitor/chips/chips.prt';

PART_NAME
 C17 'CAPACITOR-G105-0B104-CK,0.1UF,A':;

SECTION_NUMBER 1
 '@TIMECARD_LIB.TIMECARD(SCH_1):PAGE3_I92@PASSIVE.CAPACITOR(CHIPS)':
 C_PATH='@timecard_lib.timecard(sch_1):page3_i92@passive.capacitor(chips)',
 P_PATH='@timecard_lib.timecard(sch_1):page9_i92@passive.capacitor(chips)',
 PATH='I92',
 DRAWING='@TIMECARD_LIB.TIMECARD(SCH_1):PAGE3',
 PACKAGE='0402',
 PHYS_PAGE='9',
 XY='(-7900,2700)',
 ROT='0',
 VER='2',
 CDS_LIB='passive',
 CDS_PART_NAME='CAPACITOR-G105-0B104-CK,0.1UF,A',
 NO_ASSY='TRUE',
 TOLERANCE='10%',
 CLS_PN='G105-0B104-CK',
 VALUE='0.1UF',
 PRIM_FILE='./archive_libs/passive/capacitor/chips/chips.prt';

PART_NAME
 C18 'CAPACITOR-G105-0B104-CK,0.1UF,A':;

SECTION_NUMBER 1
 '@TIMECARD_LIB.TIMECARD(SCH_1):PAGE517_I36@PASSIVE.CAPACITOR(CHIPS)':
 C_PATH='@timecard_lib.timecard(sch_1):page517_i36@passive.capacitor(chips)',
 P_PATH='@timecard_lib.timecard(sch_1):page28_i36@passive.capacitor(chips)',
 PATH='I36',
 DRAWING='@TIMECARD_LIB.TIMECARD(SCH_1):PAGE517',
 PACKAGE='0402',
 PHYS_PAGE='28',
 XY='(-2500,5950)',
 ROT='0',
 VER='2',
 CDS_LIB='passive',
 CDS_PART_NAME='CAPACITOR-G105-0B104-CK,0.1UF,A',
 TOLERANCE='10%',
 CLS_PN='G105-0B104-CK',
 VOLTAGE='10V',
 VALUE='0.1UF',
 PRIM_FILE='./archive_libs/passive/capacitor/chips/chips.prt';

PART_NAME
 C19 'CAPACITOR-G105-0B104-CK,0.1UF,A':
 SIGNAL_MODEL='DEFAULT_CAPACITOR_100000pF_1_2';

SECTION_NUMBER 1
 '@TIMECARD_LIB.TIMECARD(SCH_1):PAGE3_I36@PASSIVE.CAPACITOR(CHIPS)':
 C_PATH='@timecard_lib.timecard(sch_1):page3_i36@passive.capacitor(chips)',
 P_PATH='@timecard_lib.timecard(sch_1):page9_i36@passive.capacitor(chips)',
 PATH='I36',
 DRAWING='@TIMECARD_LIB.TIMECARD(SCH_1):PAGE3',
 PACKAGE='0402',
 PHYS_PAGE='9',
 XY='(-4000,6850)',
 ROT='0',
 VER='1',
 CDS_LIB='passive',
 CDS_PART_NAME='CAPACITOR-G105-0B104-CK,0.1UF,A',
 TOLERANCE='10%',
 CLS_PN='G105-0B104-CK',
 SIGNAL_MODEL='DEFAULT_CAPACITOR_100000pF_1_2',
 VALUE='0.1UF',
 PRIM_FILE='./archive_libs/passive/capacitor/chips/chips.prt';

PART_NAME
 C20 'CAPACITOR-G107-0F226-CM,22UF,2A':;

SECTION_NUMBER 1
 '@TIMECARD_LIB.TIMECARD(SCH_1):PAGE517_I37@PASSIVE.CAPACITOR(CHIPS)':
 C_PATH='@timecard_lib.timecard(sch_1):page517_i37@passive.capacitor(chips)',
 P_PATH='@timecard_lib.timecard(sch_1):page28_i37@passive.capacitor(chips)',
 PATH='I37',
 DRAWING='@TIMECARD_LIB.TIMECARD(SCH_1):PAGE517',
 PACKAGE='0805',
 PHYS_PAGE='28',
 XY='(-2000,5950)',
 ROT='0',
 VER='2',
 CDS_LIB='passive',
 CDS_PART_NAME='CAPACITOR-G107-0F226-CM,22UF,2A',
 TOLERANCE='20%',
 CLS_PN='G107-0F226-CM',
 VOLTAGE='10V',
 VALUE='22UF',
 PRIM_FILE='./archive_libs/passive/capacitor/chips/chips.prt';

PART_NAME
 C21 'CAPACITOR-G107-0F226-CM,22UF,2A':;

SECTION_NUMBER 1
 '@TIMECARD_LIB.TIMECARD(SCH_1):PAGE517_I38@PASSIVE.CAPACITOR(CHIPS)':
 C_PATH='@timecard_lib.timecard(sch_1):page517_i38@passive.capacitor(chips)',
 P_PATH='@timecard_lib.timecard(sch_1):page28_i38@passive.capacitor(chips)',
 PATH='I38',
 DRAWING='@TIMECARD_LIB.TIMECARD(SCH_1):PAGE517',
 PACKAGE='0805',
 PHYS_PAGE='28',
 XY='(-1500,5950)',
 ROT='0',
 VER='2',
 CDS_LIB='passive',
 CDS_PART_NAME='CAPACITOR-G107-0F226-CM,22UF,2A',
 TOLERANCE='20%',
 CLS_PN='G107-0F226-CM',
 VOLTAGE='10V',
 VALUE='22UF',
 PRIM_FILE='./archive_libs/passive/capacitor/chips/chips.prt';

PART_NAME
 C22 'CAPACITOR-G107-0F226-CM,22UF,2A':;

SECTION_NUMBER 1
 '@TIMECARD_LIB.TIMECARD(SCH_1):PAGE517_I40@PASSIVE.CAPACITOR(CHIPS)':
 C_PATH='@timecard_lib.timecard(sch_1):page517_i40@passive.capacitor(chips)',
 P_PATH='@timecard_lib.timecard(sch_1):page28_i40@passive.capacitor(chips)',
 PATH='I40',
 DRAWING='@TIMECARD_LIB.TIMECARD(SCH_1):PAGE517',
 PACKAGE='0805',
 PHYS_PAGE='28',
 XY='(-1050,5950)',
 ROT='0',
 VER='2',
 CDS_LIB='passive',
 CDS_PART_NAME='CAPACITOR-G107-0F226-CM,22UF,2A',
 TOLERANCE='20%',
 CLS_PN='G107-0F226-CM',
 VOLTAGE='10V',
 VALUE='22UF',
 PRIM_FILE='./archive_libs/passive/capacitor/chips/chips.prt';

PART_NAME
 C23 'CAPACITOR-G105-0B104-CK,0.1UF,A':
 SIGNAL_MODEL='DEFAULT_CAPACITOR_100000pF_1_2';

SECTION_NUMBER 1
 '@TIMECARD_LIB.TIMECARD(SCH_1):PAGE3_I37@PASSIVE.CAPACITOR(CHIPS)':
 C_PATH='@timecard_lib.timecard(sch_1):page3_i37@passive.capacitor(chips)',
 P_PATH='@timecard_lib.timecard(sch_1):page9_i37@passive.capacitor(chips)',
 PATH='I37',
 DRAWING='@TIMECARD_LIB.TIMECARD(SCH_1):PAGE3',
 PACKAGE='0402',
 PHYS_PAGE='9',
 XY='(-4000,6750)',
 ROT='0',
 VER='1',
 CDS_LIB='passive',
 CDS_PART_NAME='CAPACITOR-G105-0B104-CK,0.1UF,A',
 TOLERANCE='10%',
 CLS_PN='G105-0B104-CK',
 SIGNAL_MODEL='DEFAULT_CAPACITOR_100000pF_1_2',
 VALUE='0.1UF',
 PRIM_FILE='./archive_libs/passive/capacitor/chips/chips.prt';

PART_NAME
 C24 'CAPACITOR-G105-0B104-CK,0.1UF,A':
 SIGNAL_MODEL='DEFAULT_CAPACITOR_100000pF_1_2';

SECTION_NUMBER 1
 '@TIMECARD_LIB.TIMECARD(SCH_1):PAGE3_I35@PASSIVE.CAPACITOR(CHIPS)':
 C_PATH='@timecard_lib.timecard(sch_1):page3_i35@passive.capacitor(chips)',
 P_PATH='@timecard_lib.timecard(sch_1):page9_i35@passive.capacitor(chips)',
 PATH='I35',
 DRAWING='@TIMECARD_LIB.TIMECARD(SCH_1):PAGE3',
 PACKAGE='0402',
 PHYS_PAGE='9',
 XY='(-4000,6550)',
 ROT='0',
 VER='1',
 CDS_LIB='passive',
 CDS_PART_NAME='CAPACITOR-G105-0B104-CK,0.1UF,A',
 TOLERANCE='10%',
 CLS_PN='G105-0B104-CK',
 SIGNAL_MODEL='DEFAULT_CAPACITOR_100000pF_1_2',
 VALUE='0.1UF',
 PRIM_FILE='./archive_libs/passive/capacitor/chips/chips.prt';

PART_NAME
 C25 'CAPACITOR-G105-0B104-CK,0.1UF,A':
 SIGNAL_MODEL='DEFAULT_CAPACITOR_100000pF_1_2';

SECTION_NUMBER 1
 '@TIMECARD_LIB.TIMECARD(SCH_1):PAGE3_I115@PASSIVE.CAPACITOR(CHIPS)':
 C_PATH='@timecard_lib.timecard(sch_1):page3_i115@passive.capacitor(chips)',
 P_PATH='@timecard_lib.timecard(sch_1):page9_i115@passive.capacitor(chips)',
 PATH='I115',
 DRAWING='@TIMECARD_LIB.TIMECARD(SCH_1):PAGE3',
 PACKAGE='0402',
 PHYS_PAGE='9',
 XY='(-4000,6450)',
 ROT='0',
 VER='1',
 LOCATION='C25',
 CDS_LIB='passive',
 CDS_PART_NAME='CAPACITOR-G105-0B104-CK,0.1UF,A',
 TOLERANCE='10%',
 CLS_PN='G105-0B104-CK',
 SIGNAL_MODEL='DEFAULT_CAPACITOR_100000pF_1_2',
 VALUE='0.1UF',
 PRIM_FILE='./archive_libs/passive/capacitor/chips/chips.prt';

PART_NAME
 C26 'CAPACITOR-G105-0B104-CK,0.1UF,A':
 SIGNAL_MODEL='DEFAULT_CAPACITOR_100000pF_1_2';

SECTION_NUMBER 1
 '@TIMECARD_LIB.TIMECARD(SCH_1):PAGE3_I116@PASSIVE.CAPACITOR(CHIPS)':
 C_PATH='@timecard_lib.timecard(sch_1):page3_i116@passive.capacitor(chips)',
 P_PATH='@timecard_lib.timecard(sch_1):page9_i116@passive.capacitor(chips)',
 PATH='I116',
 DRAWING='@TIMECARD_LIB.TIMECARD(SCH_1):PAGE3',
 PACKAGE='0402',
 PHYS_PAGE='9',
 XY='(-4000,6050)',
 ROT='0',
 VER='1',
 LOCATION='C26',
 CDS_LIB='passive',
 CDS_PART_NAME='CAPACITOR-G105-0B104-CK,0.1UF,A',
 TOLERANCE='10%',
 CLS_PN='G105-0B104-CK',
 SIGNAL_MODEL='DEFAULT_CAPACITOR_100000pF_1_2',
 VALUE='0.1UF',
 PRIM_FILE='./archive_libs/passive/capacitor/chips/chips.prt';

PART_NAME
 C27 'CAPACITOR-G105-0B104-CK,0.1UF,A':
 SIGNAL_MODEL='DEFAULT_CAPACITOR_100000pF_1_2';

SECTION_NUMBER 1
 '@TIMECARD_LIB.TIMECARD(SCH_1):PAGE3_I117@PASSIVE.CAPACITOR(CHIPS)':
 C_PATH='@timecard_lib.timecard(sch_1):page3_i117@passive.capacitor(chips)',
 P_PATH='@timecard_lib.timecard(sch_1):page9_i117@passive.capacitor(chips)',
 PATH='I117',
 DRAWING='@TIMECARD_LIB.TIMECARD(SCH_1):PAGE3',
 PACKAGE='0402',
 PHYS_PAGE='9',
 XY='(-4000,5950)',
 ROT='0',
 VER='1',
 LOCATION='C27',
 CDS_LIB='passive',
 CDS_PART_NAME='CAPACITOR-G105-0B104-CK,0.1UF,A',
 TOLERANCE='10%',
 CLS_PN='G105-0B104-CK',
 SIGNAL_MODEL='DEFAULT_CAPACITOR_100000pF_1_2',
 VALUE='0.1UF',
 PRIM_FILE='./archive_libs/passive/capacitor/chips/chips.prt';

PART_NAME
 C28 'CAPACITOR-G105-0B104-CK,0.1UF,A':
 SIGNAL_MODEL='DEFAULT_CAPACITOR_100000pF_1_2';

SECTION_NUMBER 1
 '@TIMECARD_LIB.TIMECARD(SCH_1):PAGE3_I118@PASSIVE.CAPACITOR(CHIPS)':
 C_PATH='@timecard_lib.timecard(sch_1):page3_i118@passive.capacitor(chips)',
 P_PATH='@timecard_lib.timecard(sch_1):page9_i118@passive.capacitor(chips)',
 PATH='I118',
 DRAWING='@TIMECARD_LIB.TIMECARD(SCH_1):PAGE3',
 PACKAGE='0402',
 PHYS_PAGE='9',
 XY='(-4000,5650)',
 ROT='0',
 VER='1',
 LOCATION='C28',
 CDS_LIB='passive',
 CDS_PART_NAME='CAPACITOR-G105-0B104-CK,0.1UF,A',
 TOLERANCE='10%',
 CLS_PN='G105-0B104-CK',
 SIGNAL_MODEL='DEFAULT_CAPACITOR_100000pF_1_2',
 VALUE='0.1UF',
 PRIM_FILE='./archive_libs/passive/capacitor/chips/chips.prt';

PART_NAME
 C29 'CAPACITOR-G105-0B104-CK,0.1UF,A':;

SECTION_NUMBER 1
 '@TIMECARD_LIB.TIMECARD(SCH_1):PAGE516_I10@PASSIVE.CAPACITOR(CHIPS)':
 C_PATH='@timecard_lib.timecard(sch_1):page516_i10@passive.capacitor(chips)',
 P_PATH='@timecard_lib.timecard(sch_1):page32_i10@passive.capacitor(chips)',
 PATH='I10',
 DRAWING='@TIMECARD_LIB.TIMECARD(SCH_1):PAGE516',
 PACKAGE='0402',
 PHYS_PAGE='32',
 XY='(-12600,6600)',
 ROT='0',
 VER='2',
 CDS_LIB='passive',
 CDS_PART_NAME='CAPACITOR-G105-0B104-CK,0.1UF,A',
 TOLERANCE='10%',
 CLS_PN='G105-0B104-CK',
 VOLTAGE='10V',
 VALUE='0.1UF',
 PRIM_FILE='./archive_libs/passive/capacitor/chips/chips.prt';

PART_NAME
 C30 'CAPACITOR-G107-0F106-EM,10UF,2A':;

SECTION_NUMBER 1
 '@TIMECARD_LIB.TIMECARD(SCH_1):PAGE516_I18@PASSIVE.CAPACITOR(CHIPS)':
 C_PATH='@timecard_lib.timecard(sch_1):page516_i18@passive.capacitor(chips)',
 P_PATH='@timecard_lib.timecard(sch_1):page32_i18@passive.capacitor(chips)',
 PATH='I18',
 DRAWING='@TIMECARD_LIB.TIMECARD(SCH_1):PAGE516',
 PACKAGE='0805',
 PHYS_PAGE='32',
 XY='(-12250,7950)',
 ROT='0',
 VER='2',
 CDS_LIB='passive',
 CDS_PART_NAME='CAPACITOR-G107-0F106-EM,10UF,2A',
 TOLERANCE='20%',
 CLS_PN='G107-0F106-EM',
 VOLTAGE='25V',
 VALUE='10UF',
 PRIM_FILE='./archive_libs/passive/capacitor/chips/chips.prt';

PART_NAME
 C31 'CAPACITOR-G105-0B223-EK,0.022UA':;

SECTION_NUMBER 1
 '@TIMECARD_LIB.TIMECARD(SCH_1):PAGE516_I11@PASSIVE.CAPACITOR(CHIPS)':
 C_PATH='@timecard_lib.timecard(sch_1):page516_i11@passive.capacitor(chips)',
 P_PATH='@timecard_lib.timecard(sch_1):page32_i11@passive.capacitor(chips)',
 PATH='I11',
 DRAWING='@TIMECARD_LIB.TIMECARD(SCH_1):PAGE516',
 PACKAGE='0402',
 PHYS_PAGE='32',
 XY='(-11850,6100)',
 ROT='0',
 VER='2',
 CDS_LIB='passive',
 CDS_PART_NAME='CAPACITOR-G105-0B223-EK,0.022UA',
 TOLERANCE='10%',
 CLS_PN='G105-0B223-EK',
 VOLTAGE='25V',
 VALUE='0.022UF',
 PRIM_FILE='./archive_libs/passive/capacitor/chips/chips.prt';

PART_NAME
 C32 'CAPACITOR-G107-0F106-EM,10UF,2A':;

SECTION_NUMBER 1
 '@TIMECARD_LIB.TIMECARD(SCH_1):PAGE516_I19@PASSIVE.CAPACITOR(CHIPS)':
 C_PATH='@timecard_lib.timecard(sch_1):page516_i19@passive.capacitor(chips)',
 P_PATH='@timecard_lib.timecard(sch_1):page32_i19@passive.capacitor(chips)',
 PATH='I19',
 DRAWING='@TIMECARD_LIB.TIMECARD(SCH_1):PAGE516',
 PACKAGE='0805',
 PHYS_PAGE='32',
 XY='(-11800,7950)',
 ROT='0',
 VER='2',
 CDS_LIB='passive',
 CDS_PART_NAME='CAPACITOR-G107-0F106-EM,10UF,2A',
 TOLERANCE='20%',
 CLS_PN='G107-0F106-EM',
 VOLTAGE='25V',
 VALUE='10UF',
 PRIM_FILE='./archive_libs/passive/capacitor/chips/chips.prt';

PART_NAME
 C33 'CAPACITOR-G105-0B104-EK,0.1UF,A':;

SECTION_NUMBER 1
 '@TIMECARD_LIB.TIMECARD(SCH_1):PAGE516_I20@PASSIVE.CAPACITOR(CHIPS)':
 C_PATH='@timecard_lib.timecard(sch_1):page516_i20@passive.capacitor(chips)',
 P_PATH='@timecard_lib.timecard(sch_1):page32_i20@passive.capacitor(chips)',
 PATH='I20',
 DRAWING='@TIMECARD_LIB.TIMECARD(SCH_1):PAGE516',
 PACKAGE='0402',
 PHYS_PAGE='32',
 XY='(-11350,7950)',
 ROT='0',
 VER='2',
 CDS_LIB='passive',
 CDS_PART_NAME='CAPACITOR-G105-0B104-EK,0.1UF,A',
 TOLERANCE='10%',
 CLS_PN='G105-0B104-EK',
 VOLTAGE='25V',
 VALUE='0.1UF',
 PRIM_FILE='./archive_libs/passive/capacitor/chips/chips.prt';

PART_NAME
 C34 'CAPACITOR-G105-0B104-CK,0.1UF,A':
 SIGNAL_MODEL='DEFAULT_CAPACITOR_100000pF_1_2';

SECTION_NUMBER 1
 '@TIMECARD_LIB.TIMECARD(SCH_1):PAGE3_I119@PASSIVE.CAPACITOR(CHIPS)':
 C_PATH='@timecard_lib.timecard(sch_1):page3_i119@passive.capacitor(chips)',
 P_PATH='@timecard_lib.timecard(sch_1):page9_i119@passive.capacitor(chips)',
 PATH='I119',
 DRAWING='@TIMECARD_LIB.TIMECARD(SCH_1):PAGE3',
 PACKAGE='0402',
 PHYS_PAGE='9',
 XY='(-4000,5550)',
 ROT='0',
 VER='1',
 LOCATION='C34',
 CDS_LIB='passive',
 CDS_PART_NAME='CAPACITOR-G105-0B104-CK,0.1UF,A',
 TOLERANCE='10%',
 CLS_PN='G105-0B104-CK',
 SIGNAL_MODEL='DEFAULT_CAPACITOR_100000pF_1_2',
 VALUE='0.1UF',
 PRIM_FILE='./archive_libs/passive/capacitor/chips/chips.prt';

PART_NAME
 C35 'CAPACITOR-G105-0B104-CK,0.1UF,A':
 SIGNAL_MODEL='DEFAULT_CAPACITOR_100000pF_1_2';

SECTION_NUMBER 1
 '@TIMECARD_LIB.TIMECARD(SCH_1):PAGE3_I120@PASSIVE.CAPACITOR(CHIPS)':
 C_PATH='@timecard_lib.timecard(sch_1):page3_i120@passive.capacitor(chips)',
 P_PATH='@timecard_lib.timecard(sch_1):page9_i120@passive.capacitor(chips)',
 PATH='I120',
 DRAWING='@TIMECARD_LIB.TIMECARD(SCH_1):PAGE3',
 PACKAGE='0402',
 PHYS_PAGE='9',
 XY='(-4000,5250)',
 ROT='0',
 VER='1',
 LOCATION='C35',
 CDS_LIB='passive',
 CDS_PART_NAME='CAPACITOR-G105-0B104-CK,0.1UF,A',
 TOLERANCE='10%',
 CLS_PN='G105-0B104-CK',
 SIGNAL_MODEL='DEFAULT_CAPACITOR_100000pF_1_2',
 VALUE='0.1UF',
 PRIM_FILE='./archive_libs/passive/capacitor/chips/chips.prt';

PART_NAME
 C36 'CAPACITOR-G105-0B104-CK,0.1UF,A':
 SIGNAL_MODEL='DEFAULT_CAPACITOR_100000pF_1_2';

SECTION_NUMBER 1
 '@TIMECARD_LIB.TIMECARD(SCH_1):PAGE3_I121@PASSIVE.CAPACITOR(CHIPS)':
 C_PATH='@timecard_lib.timecard(sch_1):page3_i121@passive.capacitor(chips)',
 P_PATH='@timecard_lib.timecard(sch_1):page9_i121@passive.capacitor(chips)',
 PATH='I121',
 DRAWING='@TIMECARD_LIB.TIMECARD(SCH_1):PAGE3',
 PACKAGE='0402',
 PHYS_PAGE='9',
 XY='(-4000,5150)',
 ROT='0',
 VER='1',
 LOCATION='C36',
 CDS_LIB='passive',
 CDS_PART_NAME='CAPACITOR-G105-0B104-CK,0.1UF,A',
 TOLERANCE='10%',
 CLS_PN='G105-0B104-CK',
 SIGNAL_MODEL='DEFAULT_CAPACITOR_100000pF_1_2',
 VALUE='0.1UF',
 PRIM_FILE='./archive_libs/passive/capacitor/chips/chips.prt';

PART_NAME
 C37 'CAPACITOR-G105-0B104-CK,0.1UF,A':;

SECTION_NUMBER 1
 '@TIMECARD_LIB.TIMECARD(SCH_1):PAGE3_I4@PASSIVE.CAPACITOR(CHIPS)':
 C_PATH='@timecard_lib.timecard(sch_1):page3_i4@passive.capacitor(chips)',
 P_PATH='@timecard_lib.timecard(sch_1):page9_i4@passive.capacitor(chips)',
 PATH='I4',
 DRAWING='@TIMECARD_LIB.TIMECARD(SCH_1):PAGE3',
 PACKAGE='0402',
 PHYS_PAGE='9',
 XY='(-250,5800)',
 ROT='0',
 VER='2',
 CDS_LIB='passive',
 CDS_PART_NAME='CAPACITOR-G105-0B104-CK,0.1UF,A',
 TOLERANCE='10%',
 CLS_PN='G105-0B104-CK',
 VOLTAGE='10V',
 VALUE='0.1UF',
 PRIM_FILE='./archive_libs/passive/capacitor/chips/chips.prt';

PART_NAME
 C38 'CAPACITOR-G105-0B104-CK,0.1UF,A':;

SECTION_NUMBER 1
 '@TIMECARD_LIB.TIMECARD(SCH_1):PAGE5_I45@PASSIVE.CAPACITOR(CHIPS)':
 C_PATH='@timecard_lib.timecard(sch_1):page5_i45@passive.capacitor(chips)',
 P_PATH='@timecard_lib.timecard(sch_1):page16_i45@passive.capacitor(chips)',
 PATH='I45',
 DRAWING='@TIMECARD_LIB.TIMECARD(SCH_1):PAGE5',
 PACKAGE='0402',
 PHYS_PAGE='16',
 XY='(-5850,8900)',
 ROT='0',
 VER='2',
 CDS_LIB='passive',
 CDS_PART_NAME='CAPACITOR-G105-0B104-CK,0.1UF,A',
 TOLERANCE='10%',
 CLS_PN='G105-0B104-CK',
 VOLTAGE='10V',
 VALUE='0.1UF',
 PRIM_FILE='./archive_libs/passive/capacitor/chips/chips.prt';

PART_NAME
 C39 'CAPACITOR-G105-0B104-EK,0.1UF,A':;

SECTION_NUMBER 1
 '@TIMECARD_LIB.TIMECARD(SCH_1):PAGE6_I37@PASSIVE.CAPACITOR(CHIPS)':
 C_PATH='@timecard_lib.timecard(sch_1):page6_i37@passive.capacitor(chips)',
 P_PATH='@timecard_lib.timecard(sch_1):page17_i37@passive.capacitor(chips)',
 PATH='I37',
 DRAWING='@TIMECARD_LIB.TIMECARD(SCH_1):PAGE6',
 PACKAGE='0402',
 PHYS_PAGE='17',
 XY='(-1450,6400)',
 ROT='0',
 VER='1',
 CDS_LIB='passive',
 CDS_PART_NAME='CAPACITOR-G105-0B104-EK,0.1UF,A',
 TOLERANCE='10%',
 CLS_PN='G105-0B104-EK',
 VOLTAGE='25V',
 VALUE='0.1UF',
 PRIM_FILE='./archive_libs/passive/capacitor/chips/chips.prt';

PART_NAME
 C40 'CAPACITOR-G105-0B104-EK,0.1UF,A':;

SECTION_NUMBER 1
 '@TIMECARD_LIB.TIMECARD(SCH_1):PAGE7_I18@PASSIVE.CAPACITOR(CHIPS)':
 C_PATH='@timecard_lib.timecard(sch_1):page7_i18@passive.capacitor(chips)',
 P_PATH='@timecard_lib.timecard(sch_1):page18_i18@passive.capacitor(chips)',
 PATH='I18',
 DRAWING='@TIMECARD_LIB.TIMECARD(SCH_1):PAGE7',
 PACKAGE='0402',
 PHYS_PAGE='18',
 XY='(-4300,8750)',
 ROT='2',
 VER='2',
 CDS_LIB='passive',
 CDS_PART_NAME='CAPACITOR-G105-0B104-EK,0.1UF,A',
 TOLERANCE='10%',
 CLS_PN='G105-0B104-EK',
 VOLTAGE='25V',
 VALUE='0.1UF',
 PRIM_FILE='./archive_libs/passive/capacitor/chips/chips.prt';

PART_NAME
 C41 'CAPACITOR-G105-0B104-EK,0.1UF,A':;

SECTION_NUMBER 1
 '@TIMECARD_LIB.TIMECARD(SCH_1):PAGE516_I22@PASSIVE.CAPACITOR(CHIPS)':
 C_PATH='@timecard_lib.timecard(sch_1):page516_i22@passive.capacitor(chips)',
 P_PATH='@timecard_lib.timecard(sch_1):page32_i22@passive.capacitor(chips)',
 PATH='I22',
 DRAWING='@TIMECARD_LIB.TIMECARD(SCH_1):PAGE516',
 PACKAGE='0402',
 PHYS_PAGE='32',
 XY='(-10800,7950)',
 ROT='0',
 VER='2',
 CDS_LIB='passive',
 CDS_PART_NAME='CAPACITOR-G105-0B104-EK,0.1UF,A',
 TOLERANCE='10%',
 CLS_PN='G105-0B104-EK',
 VOLTAGE='25V',
 VALUE='0.1UF',
 PRIM_FILE='./archive_libs/passive/capacitor/chips/chips.prt';

PART_NAME
 C42 'CAPACITOR-G105-0B222-FK,2200PFA':;

SECTION_NUMBER 1
 '@TIMECARD_LIB.TIMECARD(SCH_1):PAGE516_I13@PASSIVE.CAPACITOR(CHIPS)':
 C_PATH='@timecard_lib.timecard(sch_1):page516_i13@passive.capacitor(chips)',
 P_PATH='@timecard_lib.timecard(sch_1):page32_i13@passive.capacitor(chips)',
 PATH='I13',
 DRAWING='@TIMECARD_LIB.TIMECARD(SCH_1):PAGE516',
 PACKAGE='0402',
 PHYS_PAGE='32',
 XY='(-10700,5750)',
 ROT='0',
 VER='2',
 CDS_LIB='passive',
 CDS_PART_NAME='CAPACITOR-G105-0B222-FK,2200PFA',
 TOLERANCE='10%',
 CLS_PN='G105-0B222-FK',
 VOLTAGE='50V',
 VALUE='2200PF',
 PRIM_FILE='./archive_libs/passive/capacitor/chips/chips.prt';

PART_NAME
 C43 'CAPACITOR-G104-0A180-FJ,18PF,5%':;

SECTION_NUMBER 1
 '@TIMECARD_LIB.TIMECARD(SCH_1):PAGE516_I15@PASSIVE.CAPACITOR(CHIPS)':
 C_PATH='@timecard_lib.timecard(sch_1):page516_i15@passive.capacitor(chips)',
 P_PATH='@timecard_lib.timecard(sch_1):page32_i15@passive.capacitor(chips)',
 PATH='I15',
 DRAWING='@TIMECARD_LIB.TIMECARD(SCH_1):PAGE516',
 PACKAGE='0201',
 PHYS_PAGE='32',
 XY='(-10050,5850)',
 ROT='0',
 VER='2',
 CDS_LIB='passive',
 CDS_PART_NAME='CAPACITOR-G104-0A180-FJ,18PF,5%',
 TOLERANCE='5%',
 CLS_PN='G104-0A180-FJ',
 VOLTAGE='50V',
 VALUE='18PF',
 PRIM_FILE='./archive_libs/passive/capacitor/chips/chips.prt';

PART_NAME
 C44 'CAPACITOR-G105-0B104-EK,0.1UF,A':;

SECTION_NUMBER 1
 '@TIMECARD_LIB.TIMECARD(SCH_1):PAGE516_I27@PASSIVE.CAPACITOR(CHIPS)':
 C_PATH='@timecard_lib.timecard(sch_1):page516_i27@passive.capacitor(chips)',
 P_PATH='@timecard_lib.timecard(sch_1):page32_i27@passive.capacitor(chips)',
 PATH='I27',
 DRAWING='@TIMECARD_LIB.TIMECARD(SCH_1):PAGE516',
 PACKAGE='0402',
 PHYS_PAGE='32',
 XY='(-6200,7300)',
 ROT='0',
 VER='1',
 CDS_LIB='passive',
 CDS_PART_NAME='CAPACITOR-G105-0B104-EK,0.1UF,A',
 TOLERANCE='10%',
 CLS_PN='G105-0B104-EK',
 VOLTAGE='25V',
 VALUE='0.1UF',
 PRIM_FILE='./archive_libs/passive/capacitor/chips/chips.prt';

PART_NAME
 C45 'CAPACITOR-G105-0A102-FJ,1000PFA':;

SECTION_NUMBER 1
 '@TIMECARD_LIB.TIMECARD(SCH_1):PAGE516_I37@PASSIVE.CAPACITOR(CHIPS)':
 C_PATH='@timecard_lib.timecard(sch_1):page516_i37@passive.capacitor(chips)',
 P_PATH='@timecard_lib.timecard(sch_1):page32_i37@passive.capacitor(chips)',
 PATH='I37',
 DRAWING='@TIMECARD_LIB.TIMECARD(SCH_1):PAGE516',
 PACKAGE='0402',
 PHYS_PAGE='32',
 XY='(-4900,7450)',
 ROT='0',
 VER='1',
 CDS_LIB='passive',
 CDS_PART_NAME='CAPACITOR-G105-0A102-FJ,1000PFA',
 NO_ASSY='TRUE',
 TOLERANCE='5%',
 CLS_PN='G105-0A102-FJ',
 VOLTAGE='50V',
 VALUE='1000PF',
 PRIM_FILE='./archive_libs/passive/capacitor/chips/chips.prt';

PART_NAME
 C46 'CAPACITOR-G105-0B104-CK,0.1UF,A':;

SECTION_NUMBER 1
 '@TIMECARD_LIB.TIMECARD(SCH_1):PAGE517_I12@PASSIVE.CAPACITOR(CHIPS)':
 C_PATH='@timecard_lib.timecard(sch_1):page517_i12@passive.capacitor(chips)',
 P_PATH='@timecard_lib.timecard(sch_1):page28_i12@passive.capacitor(chips)',
 PATH='I12',
 DRAWING='@TIMECARD_LIB.TIMECARD(SCH_1):PAGE517',
 PACKAGE='0402',
 PHYS_PAGE='28',
 XY='(-12350,5800)',
 ROT='0',
 VER='2',
 CDS_LIB='passive',
 CDS_PART_NAME='CAPACITOR-G105-0B104-CK,0.1UF,A',
 TOLERANCE='10%',
 CLS_PN='G105-0B104-CK',
 VOLTAGE='10V',
 VALUE='0.1UF',
 PRIM_FILE='./archive_libs/passive/capacitor/chips/chips.prt';

PART_NAME
 C47 'CAPACITOR-G104-0A120-FJ,12PF,5%':;

SECTION_NUMBER 1
 '@TIMECARD_LIB.TIMECARD(SCH_1):PAGE9_I54@PASSIVE.CAPACITOR(CHIPS)':
 C_PATH='@timecard_lib.timecard(sch_1):page9_i54@passive.capacitor(chips)',
 P_PATH='@timecard_lib.timecard(sch_1):page20_i54@passive.capacitor(chips)',
 PATH='I54',
 DRAWING='@TIMECARD_LIB.TIMECARD(SCH_1):PAGE9',
 PACKAGE='0201',
 PHYS_PAGE='20',
 XY='(-4300,9900)',
 ROT='1',
 VER='2',
 LOCATION='C47',
 CDS_LIB='passive',
 CDS_PART_NAME='CAPACITOR-G104-0A120-FJ,12PF,5%',
 TOLERANCE='5%',
 CLS_PN='G104-0A120-FJ',
 VOLTAGE='50V',
 VALUE='12PF',
 PRIM_FILE='./archive_libs/passive/capacitor/chips/chips.prt';

PART_NAME
 C48 'CAPACITOR-G107-0F106-EM,10UF,2A':;

SECTION_NUMBER 1
 '@TIMECARD_LIB.TIMECARD(SCH_1):PAGE517_I14@PASSIVE.CAPACITOR(CHIPS)':
 C_PATH='@timecard_lib.timecard(sch_1):page517_i14@passive.capacitor(chips)',
 P_PATH='@timecard_lib.timecard(sch_1):page28_i14@passive.capacitor(chips)',
 PATH='I14',
 DRAWING='@TIMECARD_LIB.TIMECARD(SCH_1):PAGE517',
 PACKAGE='0805',
 PHYS_PAGE='28',
 XY='(-12000,7150)',
 ROT='0',
 VER='2',
 CDS_LIB='passive',
 CDS_PART_NAME='CAPACITOR-G107-0F106-EM,10UF,2A',
 TOLERANCE='20%',
 CLS_PN='G107-0F106-EM',
 VOLTAGE='25V',
 VALUE='10UF',
 PRIM_FILE='./archive_libs/passive/capacitor/chips/chips.prt';

PART_NAME
 C49 'CAPACITOR-G105-0B223-EK,0.022UA':;

SECTION_NUMBER 1
 '@TIMECARD_LIB.TIMECARD(SCH_1):PAGE517_I9@PASSIVE.CAPACITOR(CHIPS)':
 C_PATH='@timecard_lib.timecard(sch_1):page517_i9@passive.capacitor(chips)',
 P_PATH='@timecard_lib.timecard(sch_1):page28_i9@passive.capacitor(chips)',
 PATH='I9',
 DRAWING='@TIMECARD_LIB.TIMECARD(SCH_1):PAGE517',
 PACKAGE='0402',
 PHYS_PAGE='28',
 XY='(-11600,5300)',
 ROT='0',
 VER='2',
 CDS_LIB='passive',
 CDS_PART_NAME='CAPACITOR-G105-0B223-EK,0.022UA',
 TOLERANCE='10%',
 CLS_PN='G105-0B223-EK',
 VALUE='0.022UF',
 PRIM_FILE='./archive_libs/passive/capacitor/chips/chips.prt';

PART_NAME
 C50 'CAPACITOR-G107-0F106-EM,10UF,2A':;

SECTION_NUMBER 1
 '@TIMECARD_LIB.TIMECARD(SCH_1):PAGE517_I15@PASSIVE.CAPACITOR(CHIPS)':
 C_PATH='@timecard_lib.timecard(sch_1):page517_i15@passive.capacitor(chips)',
 P_PATH='@timecard_lib.timecard(sch_1):page28_i15@passive.capacitor(chips)',
 PATH='I15',
 DRAWING='@TIMECARD_LIB.TIMECARD(SCH_1):PAGE517',
 PACKAGE='0805',
 PHYS_PAGE='28',
 XY='(-11550,7150)',
 ROT='0',
 VER='2',
 CDS_LIB='passive',
 CDS_PART_NAME='CAPACITOR-G107-0F106-EM,10UF,2A',
 TOLERANCE='20%',
 CLS_PN='G107-0F106-EM',
 VOLTAGE='25V',
 VALUE='10UF',
 PRIM_FILE='./archive_libs/passive/capacitor/chips/chips.prt';

PART_NAME
 C51 'CAPACITOR-G104-0A120-FJ,12PF,5%':;

SECTION_NUMBER 1
 '@TIMECARD_LIB.TIMECARD(SCH_1):PAGE9_I17@PASSIVE.CAPACITOR(CHIPS)':
 C_PATH='@timecard_lib.timecard(sch_1):page9_i17@passive.capacitor(chips)',
 P_PATH='@timecard_lib.timecard(sch_1):page20_i17@passive.capacitor(chips)',
 PATH='I17',
 DRAWING='@TIMECARD_LIB.TIMECARD(SCH_1):PAGE9',
 PACKAGE='0201',
 PHYS_PAGE='20',
 XY='(-4300,10450)',
 ROT='1',
 VER='2',
 CDS_LIB='passive',
 CDS_PART_NAME='CAPACITOR-G104-0A120-FJ,12PF,5%',
 TOLERANCE='5%',
 CLS_PN='G104-0A120-FJ',
 VOLTAGE='50V',
 VALUE='12PF',
 PRIM_FILE='./archive_libs/passive/capacitor/chips/chips.prt';

PART_NAME
 C52 'CAPACITOR-G105-0B104-EK,0.1UF,A':;

SECTION_NUMBER 1
 '@TIMECARD_LIB.TIMECARD(SCH_1):PAGE517_I16@PASSIVE.CAPACITOR(CHIPS)':
 C_PATH='@timecard_lib.timecard(sch_1):page517_i16@passive.capacitor(chips)',
 P_PATH='@timecard_lib.timecard(sch_1):page28_i16@passive.capacitor(chips)',
 PATH='I16',
 DRAWING='@TIMECARD_LIB.TIMECARD(SCH_1):PAGE517',
 PACKAGE='0402',
 PHYS_PAGE='28',
 XY='(-11100,7150)',
 ROT='0',
 VER='2',
 CDS_LIB='passive',
 CDS_PART_NAME='CAPACITOR-G105-0B104-EK,0.1UF,A',
 TOLERANCE='10%',
 CLS_PN='G105-0B104-EK',
 VOLTAGE='25V',
 VALUE='0.1UF',
 PRIM_FILE='./archive_libs/passive/capacitor/chips/chips.prt';

PART_NAME
 C53 'CAPACITOR-G105-0B104-EK,0.1UF,A':;

SECTION_NUMBER 1
 '@TIMECARD_LIB.TIMECARD(SCH_1):PAGE517_I21@PASSIVE.CAPACITOR(CHIPS)':
 C_PATH='@timecard_lib.timecard(sch_1):page517_i21@passive.capacitor(chips)',
 P_PATH='@timecard_lib.timecard(sch_1):page28_i21@passive.capacitor(chips)',
 PATH='I21',
 DRAWING='@TIMECARD_LIB.TIMECARD(SCH_1):PAGE517',
 PACKAGE='0402',
 PHYS_PAGE='28',
 XY='(-10550,7150)',
 ROT='0',
 VER='2',
 CDS_LIB='passive',
 CDS_PART_NAME='CAPACITOR-G105-0B104-EK,0.1UF,A',
 TOLERANCE='10%',
 CLS_PN='G105-0B104-EK',
 VOLTAGE='25V',
 VALUE='0.1UF',
 PRIM_FILE='./archive_libs/passive/capacitor/chips/chips.prt';

PART_NAME
 C54 'CAPACITOR-G105-0B222-FK,2200PFA':;

SECTION_NUMBER 1
 '@TIMECARD_LIB.TIMECARD(SCH_1):PAGE517_I17@PASSIVE.CAPACITOR(CHIPS)':
 C_PATH='@timecard_lib.timecard(sch_1):page517_i17@passive.capacitor(chips)',
 P_PATH='@timecard_lib.timecard(sch_1):page28_i17@passive.capacitor(chips)',
 PATH='I17',
 DRAWING='@TIMECARD_LIB.TIMECARD(SCH_1):PAGE517',
 PACKAGE='0402',
 PHYS_PAGE='28',
 XY='(-10400,4900)',
 ROT='0',
 VER='2',
 CDS_LIB='passive',
 CDS_PART_NAME='CAPACITOR-G105-0B222-FK,2200PFA',
 TOLERANCE='10%',
 CLS_PN='G105-0B222-FK',
 VOLTAGE='50V',
 VALUE='2200PF',
 PRIM_FILE='./archive_libs/passive/capacitor/chips/chips.prt';

PART_NAME
 C55 'CAPACITOR-G104-0A180-FJ,18PF,5%':;

SECTION_NUMBER 1
 '@TIMECARD_LIB.TIMECARD(SCH_1):PAGE517_I19@PASSIVE.CAPACITOR(CHIPS)':
 C_PATH='@timecard_lib.timecard(sch_1):page517_i19@passive.capacitor(chips)',
 P_PATH='@timecard_lib.timecard(sch_1):page28_i19@passive.capacitor(chips)',
 PATH='I19',
 DRAWING='@TIMECARD_LIB.TIMECARD(SCH_1):PAGE517',
 PACKAGE='0201',
 PHYS_PAGE='28',
 XY='(-9800,5050)',
 ROT='0',
 VER='2',
 CDS_LIB='passive',
 CDS_PART_NAME='CAPACITOR-G104-0A180-FJ,18PF,5%',
 TOLERANCE='5%',
 CLS_PN='G104-0A180-FJ',
 VOLTAGE='25V',
 VALUE='18PF',
 PRIM_FILE='./archive_libs/passive/capacitor/chips/chips.prt';

PART_NAME
 C56 'CAPACITOR-G105-0B104-EK,0.1UF,A':;

SECTION_NUMBER 1
 '@TIMECARD_LIB.TIMECARD(SCH_1):PAGE517_I27@PASSIVE.CAPACITOR(CHIPS)':
 C_PATH='@timecard_lib.timecard(sch_1):page517_i27@passive.capacitor(chips)',
 P_PATH='@timecard_lib.timecard(sch_1):page28_i27@passive.capacitor(chips)',
 PATH='I27',
 DRAWING='@TIMECARD_LIB.TIMECARD(SCH_1):PAGE517',
 PACKAGE='0402',
 PHYS_PAGE='28',
 XY='(-5950,6500)',
 ROT='0',
 VER='1',
 CDS_LIB='passive',
 CDS_PART_NAME='CAPACITOR-G105-0B104-EK,0.1UF,A',
 TOLERANCE='10%',
 CLS_PN='G105-0B104-EK',
 VOLTAGE='25V',
 VALUE='0.1UF',
 PRIM_FILE='./archive_libs/passive/capacitor/chips/chips.prt';

PART_NAME
 C57 'CAPACITOR-G105-0A102-FJ,1000PFA':;

SECTION_NUMBER 1
 '@TIMECARD_LIB.TIMECARD(SCH_1):PAGE517_I29@PASSIVE.CAPACITOR(CHIPS)':
 C_PATH='@timecard_lib.timecard(sch_1):page517_i29@passive.capacitor(chips)',
 P_PATH='@timecard_lib.timecard(sch_1):page28_i29@passive.capacitor(chips)',
 PATH='I29',
 DRAWING='@TIMECARD_LIB.TIMECARD(SCH_1):PAGE517',
 PACKAGE='0402',
 PHYS_PAGE='28',
 XY='(-4650,6650)',
 ROT='0',
 VER='1',
 CDS_LIB='passive',
 CDS_PART_NAME='CAPACITOR-G105-0A102-FJ,1000PFA',
 NO_ASSY='TRUE',
 TOLERANCE='5%',
 CLS_PN='G105-0A102-FJ',
 VOLTAGE='50V',
 VALUE='1000PF',
 PRIM_FILE='./archive_libs/passive/capacitor/chips/chips.prt';

PART_NAME
 C58 'CAPACITOR-G107-0F106-EM,10UF,2A':;

SECTION_NUMBER 1
 '@TIMECARD_LIB.TIMECARD(SCH_1):PAGE527_I47@PASSIVE.CAPACITOR(CHIPS)':
 C_PATH='@timecard_lib.timecard(sch_1):page527_i47@passive.capacitor(chips)',
 P_PATH='@timecard_lib.timecard(sch_1):page21_i47@passive.capacitor(chips)',
 PATH='I47',
 DRAWING='@TIMECARD_LIB.TIMECARD(SCH_1):PAGE527',
 PACKAGE='0805',
 PHYS_PAGE='21',
 XY='(-9250,4550)',
 ROT='5',
 VER='1',
 CDS_LIB='passive',
 CDS_PART_NAME='CAPACITOR-G107-0F106-EM,10UF,2A',
 TOLERANCE='20%',
 CLS_PN='G107-0F106-EM',
 VOLTAGE='25V',
 VALUE='10UF',
 PRIM_FILE='./archive_libs/passive/capacitor/chips/chips.prt';

PART_NAME
 C59 'CAPACITOR-G105-0B104-EK,0.1UF,A':;

SECTION_NUMBER 1
 '@TIMECARD_LIB.TIMECARD(SCH_1):PAGE527_I48@PASSIVE.CAPACITOR(CHIPS)':
 C_PATH='@timecard_lib.timecard(sch_1):page527_i48@passive.capacitor(chips)',
 P_PATH='@timecard_lib.timecard(sch_1):page21_i48@passive.capacitor(chips)',
 PATH='I48',
 DRAWING='@TIMECARD_LIB.TIMECARD(SCH_1):PAGE527',
 PACKAGE='0402',
 PHYS_PAGE='21',
 XY='(-10200,4550)',
 ROT='3',
 VER='1',
 CDS_LIB='passive',
 CDS_PART_NAME='CAPACITOR-G105-0B104-EK,0.1UF,A',
 TOLERANCE='10%',
 CLS_PN='G105-0B104-EK',
 VOLTAGE='25V',
 VALUE='0.1UF',
 PRIM_FILE='./archive_libs/passive/capacitor/chips/chips.prt';

PART_NAME
 C60 'CAPACITOR-G105-0B104-EK,0.1UF,A':;

SECTION_NUMBER 1
 '@TIMECARD_LIB.TIMECARD(SCH_1):PAGE527_I66@PASSIVE.CAPACITOR(CHIPS)':
 C_PATH='@timecard_lib.timecard(sch_1):page527_i66@passive.capacitor(chips)',
 P_PATH='@timecard_lib.timecard(sch_1):page21_i66@passive.capacitor(chips)',
 PATH='I66',
 DRAWING='@TIMECARD_LIB.TIMECARD(SCH_1):PAGE527',
 PACKAGE='0402',
 PHYS_PAGE='21',
 XY='(-9750,4550)',
 ROT='3',
 VER='1',
 CDS_LIB='passive',
 CDS_PART_NAME='CAPACITOR-G105-0B104-EK,0.1UF,A',
 TOLERANCE='10%',
 CLS_PN='G105-0B104-EK',
 VOLTAGE='25V',
 VALUE='0.1UF',
 PRIM_FILE='./archive_libs/passive/capacitor/chips/chips.prt';

PART_NAME
 C61 'CAPACITOR-G107-0F106-EM,10UF,2A':;

SECTION_NUMBER 1
 '@TIMECARD_LIB.TIMECARD(SCH_1):PAGE527_I16@PASSIVE.CAPACITOR(CHIPS)':
 C_PATH='@timecard_lib.timecard(sch_1):page527_i16@passive.capacitor(chips)',
 P_PATH='@timecard_lib.timecard(sch_1):page21_i16@passive.capacitor(chips)',
 PATH='I16',
 DRAWING='@TIMECARD_LIB.TIMECARD(SCH_1):PAGE527',
 PACKAGE='0805',
 PHYS_PAGE='21',
 XY='(-8900,150)',
 ROT='5',
 VER='1',
 CDS_LIB='passive',
 CDS_PART_NAME='CAPACITOR-G107-0F106-EM,10UF,2A',
 NO_ASSY='TRUE',
 TOLERANCE='20%',
 CLS_PN='G107-0F106-EM',
 VOLTAGE='25V',
 VALUE='10UF',
 PRIM_FILE='./archive_libs/passive/capacitor/chips/chips.prt';

PART_NAME
 C62 'CAPACITOR-G105-0B104-EK,0.1UF,A':;

SECTION_NUMBER 1
 '@TIMECARD_LIB.TIMECARD(SCH_1):PAGE527_I93@PASSIVE.CAPACITOR(CHIPS)':
 C_PATH='@timecard_lib.timecard(sch_1):page527_i93@passive.capacitor(chips)',
 P_PATH='@timecard_lib.timecard(sch_1):page21_i93@passive.capacitor(chips)',
 PATH='I93',
 DRAWING='@TIMECARD_LIB.TIMECARD(SCH_1):PAGE527',
 PACKAGE='0402',
 PHYS_PAGE='21',
 XY='(-7550,4550)',
 ROT='3',
 VER='1',
 CDS_LIB='passive',
 CDS_PART_NAME='CAPACITOR-G105-0B104-EK,0.1UF,A',
 TOLERANCE='10%',
 CLS_PN='G105-0B104-EK',
 VOLTAGE='25V',
 VALUE='0.1UF',
 PRIM_FILE='./archive_libs/passive/capacitor/chips/chips.prt';

PART_NAME
 C63 'CAPACITOR-G105-0B104-EK,0.1UF,A':;

SECTION_NUMBER 1
 '@TIMECARD_LIB.TIMECARD(SCH_1):PAGE527_I15@PASSIVE.CAPACITOR(CHIPS)':
 C_PATH='@timecard_lib.timecard(sch_1):page527_i15@passive.capacitor(chips)',
 P_PATH='@timecard_lib.timecard(sch_1):page21_i15@passive.capacitor(chips)',
 PATH='I15',
 DRAWING='@TIMECARD_LIB.TIMECARD(SCH_1):PAGE527',
 PACKAGE='0402',
 PHYS_PAGE='21',
 XY='(-8500,150)',
 ROT='3',
 VER='1',
 CDS_LIB='passive',
 CDS_PART_NAME='CAPACITOR-G105-0B104-EK,0.1UF,A',
 NO_ASSY='TRUE',
 TOLERANCE='10%',
 CLS_PN='G105-0B104-EK',
 VOLTAGE='25V',
 VALUE='0.1UF',
 PRIM_FILE='./archive_libs/passive/capacitor/chips/chips.prt';

PART_NAME
 C64 'CAPACITOR-G107-0F106-EM,10UF,2A':;

SECTION_NUMBER 1
 '@TIMECARD_LIB.TIMECARD(SCH_1):PAGE527_I51@PASSIVE.CAPACITOR(CHIPS)':
 C_PATH='@timecard_lib.timecard(sch_1):page527_i51@passive.capacitor(chips)',
 P_PATH='@timecard_lib.timecard(sch_1):page21_i51@passive.capacitor(chips)',
 PATH='I51',
 DRAWING='@TIMECARD_LIB.TIMECARD(SCH_1):PAGE527',
 PACKAGE='0805',
 PHYS_PAGE='21',
 XY='(-4200,7100)',
 ROT='5',
 VER='1',
 CDS_LIB='passive',
 CDS_PART_NAME='CAPACITOR-G107-0F106-EM,10UF,2A',
 TOLERANCE='20%',
 CLS_PN='G107-0F106-EM',
 VOLTAGE='25V',
 VALUE='10UF',
 PRIM_FILE='./archive_libs/passive/capacitor/chips/chips.prt';

PART_NAME
 C65 'CAPACITOR-G105-0B104-EK,0.1UF,A':;

SECTION_NUMBER 1
 '@TIMECARD_LIB.TIMECARD(SCH_1):PAGE527_I56@PASSIVE.CAPACITOR(CHIPS)':
 C_PATH='@timecard_lib.timecard(sch_1):page527_i56@passive.capacitor(chips)',
 P_PATH='@timecard_lib.timecard(sch_1):page21_i56@passive.capacitor(chips)',
 PATH='I56',
 DRAWING='@TIMECARD_LIB.TIMECARD(SCH_1):PAGE527',
 PACKAGE='0402',
 PHYS_PAGE='21',
 XY='(-3700,7100)',
 ROT='3',
 VER='1',
 CDS_LIB='passive',
 CDS_PART_NAME='CAPACITOR-G105-0B104-EK,0.1UF,A',
 TOLERANCE='10%',
 CLS_PN='G105-0B104-EK',
 VOLTAGE='25V',
 VALUE='0.1UF',
 PRIM_FILE='./archive_libs/passive/capacitor/chips/chips.prt';

PART_NAME
 C66 'CAPACITOR-G105-0B104-EK,0.1UF,A':;

SECTION_NUMBER 1
 '@TIMECARD_LIB.TIMECARD(SCH_1):PAGE527_I57@PASSIVE.CAPACITOR(CHIPS)':
 C_PATH='@timecard_lib.timecard(sch_1):page527_i57@passive.capacitor(chips)',
 P_PATH='@timecard_lib.timecard(sch_1):page21_i57@passive.capacitor(chips)',
 PATH='I57',
 DRAWING='@TIMECARD_LIB.TIMECARD(SCH_1):PAGE527',
 PACKAGE='0402',
 PHYS_PAGE='21',
 XY='(-3200,7100)',
 ROT='3',
 VER='1',
 CDS_LIB='passive',
 CDS_PART_NAME='CAPACITOR-G105-0B104-EK,0.1UF,A',
 TOLERANCE='10%',
 CLS_PN='G105-0B104-EK',
 VOLTAGE='25V',
 VALUE='0.1UF',
 PRIM_FILE='./archive_libs/passive/capacitor/chips/chips.prt';

PART_NAME
 C67 'CAPACITOR-G105-0B104-CK,0.1UF,A':;

SECTION_NUMBER 1
 '@TIMECARD_LIB.TIMECARD(SCH_1):PAGE527_I103@PASSIVE.CAPACITOR(CHIPS)':
 C_PATH='@timecard_lib.timecard(sch_1):page527_i103@passive.capacitor(chips)',
 P_PATH='@timecard_lib.timecard(sch_1):page21_i103@passive.capacitor(chips)',
 PATH='I103',
 DRAWING='@TIMECARD_LIB.TIMECARD(SCH_1):PAGE527',
 PACKAGE='0402',
 PHYS_PAGE='21',
 XY='(-4300,950)',
 ROT='5',
 VER='2',
 CDS_LIB='passive',
 CDS_PART_NAME='CAPACITOR-G105-0B104-CK,0.1UF,A',
 NO_ASSY='TRUE',
 TOLERANCE='10%',
 CLS_PN='G105-0B104-CK',
 VOLTAGE='10V',
 VALUE='0.1UF',
 PRIM_FILE='./archive_libs/passive/capacitor/chips/chips.prt';

PART_NAME
 C68 'CAPACITOR-G105-0B104-EK,0.1UF,A':;

SECTION_NUMBER 1
 '@TIMECARD_LIB.TIMECARD(SCH_1):PAGE527_I144@PASSIVE.CAPACITOR(CHIPS)':
 C_PATH='@timecard_lib.timecard(sch_1):page527_i144@passive.capacitor(chips)',
 P_PATH='@timecard_lib.timecard(sch_1):page21_i144@passive.capacitor(chips)',
 PATH='I144',
 DRAWING='@TIMECARD_LIB.TIMECARD(SCH_1):PAGE527',
 PACKAGE='0402',
 PHYS_PAGE='21',
 XY='(-1100,3000)',
 ROT='0',
 VER='2',
 CDS_LIB='passive',
 CDS_PART_NAME='CAPACITOR-G105-0B104-EK,0.1UF,A',
 NO_ASSY='TRUE',
 TOLERANCE='10%',
 CLS_PN='G105-0B104-EK',
 VOLTAGE='25V',
 VALUE='0.1UF',
 PRIM_FILE='./archive_libs/passive/capacitor/chips/chips.prt';

PART_NAME
 C69 'CAPACITOR-G105-0B104-EK,0.1UF,A':;

SECTION_NUMBER 1
 '@TIMECARD_LIB.TIMECARD(SCH_1):PAGE527_I74@PASSIVE.CAPACITOR(CHIPS)':
 C_PATH='@timecard_lib.timecard(sch_1):page527_i74@passive.capacitor(chips)',
 P_PATH='@timecard_lib.timecard(sch_1):page21_i74@passive.capacitor(chips)',
 PATH='I74',
 DRAWING='@TIMECARD_LIB.TIMECARD(SCH_1):PAGE527',
 PACKAGE='0402',
 PHYS_PAGE='21',
 XY='(-600,3400)',
 ROT='0',
 VER='2',
 CDS_LIB='passive',
 CDS_PART_NAME='CAPACITOR-G105-0B104-EK,0.1UF,A',
 NO_ASSY='TRUE',
 TOLERANCE='10%',
 CLS_PN='G105-0B104-EK',
 VOLTAGE='25V',
 VALUE='0.1UF',
 PRIM_FILE='./archive_libs/passive/capacitor/chips/chips.prt';

PART_NAME
 C70 'CAPACITOR-G105-0B104-EK,0.1UF,A':;

SECTION_NUMBER 1
 '@TIMECARD_LIB.TIMECARD(SCH_1):PAGE527_I77@PASSIVE.CAPACITOR(CHIPS)':
 C_PATH='@timecard_lib.timecard(sch_1):page527_i77@passive.capacitor(chips)',
 P_PATH='@timecard_lib.timecard(sch_1):page21_i77@passive.capacitor(chips)',
 PATH='I77',
 DRAWING='@TIMECARD_LIB.TIMECARD(SCH_1):PAGE527',
 PACKAGE='0402',
 PHYS_PAGE='21',
 XY='(-200,3400)',
 ROT='0',
 VER='2',
 CDS_LIB='passive',
 CDS_PART_NAME='CAPACITOR-G105-0B104-EK,0.1UF,A',
 TOLERANCE='10%',
 CLS_PN='G105-0B104-EK',
 VOLTAGE='25V',
 VALUE='0.1UF',
 PRIM_FILE='./archive_libs/passive/capacitor/chips/chips.prt';

PART_NAME
 C71 'CAPACITOR-G105-0B104-EK,0.1UF,A':;

SECTION_NUMBER 1
 '@TIMECARD_LIB.TIMECARD(SCH_1):PAGE527_I85@PASSIVE.CAPACITOR(CHIPS)':
 C_PATH='@timecard_lib.timecard(sch_1):page527_i85@passive.capacitor(chips)',
 P_PATH='@timecard_lib.timecard(sch_1):page21_i85@passive.capacitor(chips)',
 PATH='I85',
 DRAWING='@TIMECARD_LIB.TIMECARD(SCH_1):PAGE527',
 PACKAGE='0402',
 PHYS_PAGE='21',
 XY='(2250,3550)',
 ROT='0',
 VER='2',
 CDS_LIB='passive',
 CDS_PART_NAME='CAPACITOR-G105-0B104-EK,0.1UF,A',
 TOLERANCE='10%',
 CLS_PN='G105-0B104-EK',
 VOLTAGE='25V',
 VALUE='0.1UF',
 PRIM_FILE='./archive_libs/passive/capacitor/chips/chips.prt';

PART_NAME
 C72 'CAPACITOR-G107-0F106-EM,10UF,2A':;

SECTION_NUMBER 1
 '@TIMECARD_LIB.TIMECARD(SCH_1):PAGE11_I12@PASSIVE.CAPACITOR(CHIPS)':
 C_PATH='@timecard_lib.timecard(sch_1):page11_i12@passive.capacitor(chips)',
 P_PATH='@timecard_lib.timecard(sch_1):page22_i12@passive.capacitor(chips)',
 PATH='I12',
 DRAWING='@TIMECARD_LIB.TIMECARD(SCH_1):PAGE11',
 PACKAGE='0805',
 PHYS_PAGE='22',
 XY='(-6050,6950)',
 ROT='5',
 VER='1',
 CDS_LIB='passive',
 CDS_PART_NAME='CAPACITOR-G107-0F106-EM,10UF,2A',
 TOLERANCE='20%',
 CLS_PN='G107-0F106-EM',
 VOLTAGE='25V',
 VALUE='10UF',
 PRIM_FILE='./archive_libs/passive/capacitor/chips/chips.prt';

PART_NAME
 C73 'CAPACITOR-G105-0B104-EK,0.1UF,A':;

SECTION_NUMBER 1
 '@TIMECARD_LIB.TIMECARD(SCH_1):PAGE11_I13@PASSIVE.CAPACITOR(CHIPS)':
 C_PATH='@timecard_lib.timecard(sch_1):page11_i13@passive.capacitor(chips)',
 P_PATH='@timecard_lib.timecard(sch_1):page22_i13@passive.capacitor(chips)',
 PATH='I13',
 DRAWING='@TIMECARD_LIB.TIMECARD(SCH_1):PAGE11',
 PACKAGE='0402',
 PHYS_PAGE='22',
 XY='(-5650,6950)',
 ROT='3',
 VER='1',
 CDS_LIB='passive',
 CDS_PART_NAME='CAPACITOR-G105-0B104-EK,0.1UF,A',
 TOLERANCE='10%',
 CLS_PN='G105-0B104-EK',
 VOLTAGE='25V',
 VALUE='0.1UF',
 PRIM_FILE='./archive_libs/passive/capacitor/chips/chips.prt';

PART_NAME
 C74 'CAPACITOR-G105-0B104-EK,0.1UF,A':;

SECTION_NUMBER 1
 '@TIMECARD_LIB.TIMECARD(SCH_1):PAGE516_I4@PASSIVE.CAPACITOR(CHIPS)':
 C_PATH='@timecard_lib.timecard(sch_1):page516_i4@passive.capacitor(chips)',
 P_PATH='@timecard_lib.timecard(sch_1):page32_i4@passive.capacitor(chips)',
 PATH='I4',
 DRAWING='@TIMECARD_LIB.TIMECARD(SCH_1):PAGE516',
 PACKAGE='0402',
 PHYS_PAGE='32',
 XY='(-13700,8000)',
 ROT='0',
 VER='2',
 CDS_LIB='passive',
 CDS_PART_NAME='CAPACITOR-G105-0B104-EK,0.1UF,A',
 TOLERANCE='10%',
 CLS_PN='G105-0B104-EK',
 VOLTAGE='25V',
 VALUE='0.1UF',
 PRIM_FILE='./archive_libs/passive/capacitor/chips/chips.prt';

PART_NAME
 C75 'CAPACITOR-G104-0B103-EK,0.01UFA':;

SECTION_NUMBER 1
 '@TIMECARD_LIB.TIMECARD(SCH_1):PAGE516_I7@PASSIVE.CAPACITOR(CHIPS)':
 C_PATH='@timecard_lib.timecard(sch_1):page516_i7@passive.capacitor(chips)',
 P_PATH='@timecard_lib.timecard(sch_1):page32_i7@passive.capacitor(chips)',
 PATH='I7',
 DRAWING='@TIMECARD_LIB.TIMECARD(SCH_1):PAGE516',
 PACKAGE='0201',
 PHYS_PAGE='32',
 XY='(-13150,5450)',
 ROT='1',
 VER='1',
 CDS_LIB='passive',
 CDS_PART_NAME='CAPACITOR-G104-0B103-EK,0.01UFA',
 TOLERANCE='10%',
 CLS_PN='G104-0B103-EK',
 VOLTAGE='25V',
 VALUE='0.01UF',
 PRIM_FILE='./archive_libs/passive/capacitor/chips/chips.prt';

PART_NAME
 C76 'CAPACITOR-G105-0B104-EK,0.1UF,A':;

SECTION_NUMBER 1
 '@TIMECARD_LIB.TIMECARD(SCH_1):PAGE517_I6@PASSIVE.CAPACITOR(CHIPS)':
 C_PATH='@timecard_lib.timecard(sch_1):page517_i6@passive.capacitor(chips)',
 P_PATH='@timecard_lib.timecard(sch_1):page28_i6@passive.capacitor(chips)',
 PATH='I6',
 DRAWING='@TIMECARD_LIB.TIMECARD(SCH_1):PAGE517',
 PACKAGE='0402',
 PHYS_PAGE='28',
 XY='(-13750,7200)',
 ROT='0',
 VER='2',
 CDS_LIB='passive',
 CDS_PART_NAME='CAPACITOR-G105-0B104-EK,0.1UF,A',
 TOLERANCE='10%',
 CLS_PN='G105-0B104-EK',
 VOLTAGE='25V',
 VALUE='0.1UF',
 PRIM_FILE='./archive_libs/passive/capacitor/chips/chips.prt';

PART_NAME
 C77 'CAPACITOR-G104-0B103-EK,0.01UFA':;

SECTION_NUMBER 1
 '@TIMECARD_LIB.TIMECARD(SCH_1):PAGE517_I2@PASSIVE.CAPACITOR(CHIPS)':
 C_PATH='@timecard_lib.timecard(sch_1):page517_i2@passive.capacitor(chips)',
 P_PATH='@timecard_lib.timecard(sch_1):page28_i2@passive.capacitor(chips)',
 PATH='I2',
 DRAWING='@TIMECARD_LIB.TIMECARD(SCH_1):PAGE517',
 PACKAGE='0402',
 PHYS_PAGE='28',
 XY='(-11950,3700)',
 ROT='1',
 VER='1',
 CDS_LIB='passive',
 CDS_PART_NAME='CAPACITOR-G104-0B103-EK,0.01UFA',
 TOLERANCE='10%',
 CLS_PN='G104-0B103-EK',
 VOLTAGE='25V',
 VALUE='0.01UF',
 PRIM_FILE='./archive_libs/passive/capacitor/chips/chips.prt';

PART_NAME
 C78 'CAPACITOR-G105-0B104-EK,0.1UF,A':;

SECTION_NUMBER 1
 '@TIMECARD_LIB.TIMECARD(SCH_1):PAGE11_I15@PASSIVE.CAPACITOR(CHIPS)':
 C_PATH='@timecard_lib.timecard(sch_1):page11_i15@passive.capacitor(chips)',
 P_PATH='@timecard_lib.timecard(sch_1):page22_i15@passive.capacitor(chips)',
 PATH='I15',
 DRAWING='@TIMECARD_LIB.TIMECARD(SCH_1):PAGE11',
 PACKAGE='0402',
 PHYS_PAGE='22',
 XY='(-5200,6950)',
 ROT='3',
 VER='1',
 CDS_LIB='passive',
 CDS_PART_NAME='CAPACITOR-G105-0B104-EK,0.1UF,A',
 TOLERANCE='10%',
 CLS_PN='G105-0B104-EK',
 VOLTAGE='25V',
 VALUE='0.1UF',
 PRIM_FILE='./archive_libs/passive/capacitor/chips/chips.prt';

PART_NAME
 C79 'CAPACITOR-G107-0F106-EM,10UF,2A':;

SECTION_NUMBER 1
 '@TIMECARD_LIB.TIMECARD(SCH_1):PAGE11_I24@PASSIVE.CAPACITOR(CHIPS)':
 C_PATH='@timecard_lib.timecard(sch_1):page11_i24@passive.capacitor(chips)',
 P_PATH='@timecard_lib.timecard(sch_1):page22_i24@passive.capacitor(chips)',
 PATH='I24',
 DRAWING='@TIMECARD_LIB.TIMECARD(SCH_1):PAGE11',
 PACKAGE='0805',
 PHYS_PAGE='22',
 XY='(-1600,6850)',
 ROT='5',
 VER='1',
 CDS_LIB='passive',
 CDS_PART_NAME='CAPACITOR-G107-0F106-EM,10UF,2A',
 TOLERANCE='20%',
 CLS_PN='G107-0F106-EM',
 VOLTAGE='25V',
 VALUE='10UF',
 PRIM_FILE='./archive_libs/passive/capacitor/chips/chips.prt';

PART_NAME
 C80 'CAPACITOR-G105-0B104-CK,0.1UF,A':;

SECTION_NUMBER 1
 '@TIMECARD_LIB.TIMECARD(SCH_1):PAGE11_I26@PASSIVE.CAPACITOR(CHIPS)':
 C_PATH='@timecard_lib.timecard(sch_1):page11_i26@passive.capacitor(chips)',
 P_PATH='@timecard_lib.timecard(sch_1):page22_i26@passive.capacitor(chips)',
 PATH='I26',
 DRAWING='@TIMECARD_LIB.TIMECARD(SCH_1):PAGE11',
 PACKAGE='0402',
 PHYS_PAGE='22',
 XY='(-2150,6850)',
 ROT='3',
 VER='1',
 CDS_LIB='passive',
 CDS_PART_NAME='CAPACITOR-G105-0B104-CK,0.1UF,A',
 TOLERANCE='10%',
 CLS_PN='G105-0B104-CK',
 VOLTAGE='10V',
 VALUE='0.1UF',
 PRIM_FILE='./archive_libs/passive/capacitor/chips/chips.prt';

PART_NAME
 C81 'CAPACITOR-G105-0B104-CK,0.1UF,A':;

SECTION_NUMBER 1
 '@TIMECARD_LIB.TIMECARD(SCH_1):PAGE11_I43@PASSIVE.CAPACITOR(CHIPS)':
 C_PATH='@timecard_lib.timecard(sch_1):page11_i43@passive.capacitor(chips)',
 P_PATH='@timecard_lib.timecard(sch_1):page22_i43@passive.capacitor(chips)',
 PATH='I43',
 DRAWING='@TIMECARD_LIB.TIMECARD(SCH_1):PAGE11',
 PACKAGE='0402',
 PHYS_PAGE='22',
 XY='(-800,6900)',
 ROT='3',
 VER='1',
 CDS_LIB='passive',
 CDS_PART_NAME='CAPACITOR-G105-0B104-CK,0.1UF,A',
 TOLERANCE='10%',
 CLS_PN='G105-0B104-CK',
 VOLTAGE='10V',
 VALUE='0.1UF',
 PRIM_FILE='./archive_libs/passive/capacitor/chips/chips.prt';

PART_NAME
 C82 'CAPACITOR-G105-0B104-CK,0.1UF,A':;

SECTION_NUMBER 1
 '@TIMECARD_LIB.TIMECARD(SCH_1):PAGE12_I231@PASSIVE.CAPACITOR(CHIPS)':
 C_PATH='@timecard_lib.timecard(sch_1):page12_i231@passive.capacitor(chips)',
 P_PATH='@timecard_lib.timecard(sch_1):page23_i231@passive.capacitor(chips)',
 PATH='I231',
 DRAWING='@TIMECARD_LIB.TIMECARD(SCH_1):PAGE12',
 PACKAGE='0402',
 PHYS_PAGE='23',
 XY='(-8400,6600)',
 ROT='0',
 VER='2',
 LOCATION='C82',
 CDS_LIB='passive',
 CDS_PART_NAME='CAPACITOR-G105-0B104-CK,0.1UF,A',
 TOLERANCE='10%',
 CLS_PN='G105-0B104-CK',
 VOLTAGE='10V',
 VALUE='0.1UF',
 PRIM_FILE='./archive_libs/passive/capacitor/chips/chips.prt';

PART_NAME
 C83 'CAPACITOR-G105-0B104-CK,0.1UF,A':;

SECTION_NUMBER 1
 '@TIMECARD_LIB.TIMECARD(SCH_1):PAGE12_I207@PASSIVE.CAPACITOR(CHIPS)':
 C_PATH='@timecard_lib.timecard(sch_1):page12_i207@passive.capacitor(chips)',
 P_PATH='@timecard_lib.timecard(sch_1):page23_i207@passive.capacitor(chips)',
 PATH='I207',
 DRAWING='@TIMECARD_LIB.TIMECARD(SCH_1):PAGE12',
 PACKAGE='0402',
 PHYS_PAGE='23',
 XY='(-8450,8750)',
 ROT='0',
 VER='2',
 CDS_LIB='passive',
 CDS_PART_NAME='CAPACITOR-G105-0B104-CK,0.1UF,A',
 TOLERANCE='10%',
 CLS_PN='G105-0B104-CK',
 VOLTAGE='10V',
 VALUE='0.1UF',
 PRIM_FILE='./archive_libs/passive/capacitor/chips/chips.prt';

PART_NAME
 C84 'CAPACITOR-G105-0B104-CK,0.1UF,A':;

SECTION_NUMBER 1
 '@TIMECARD_LIB.TIMECARD(SCH_1):PAGE12_I289@PASSIVE.CAPACITOR(CHIPS)':
 C_PATH='@timecard_lib.timecard(sch_1):page12_i289@passive.capacitor(chips)',
 P_PATH='@timecard_lib.timecard(sch_1):page23_i289@passive.capacitor(chips)',
 PATH='I289',
 DRAWING='@TIMECARD_LIB.TIMECARD(SCH_1):PAGE12',
 PACKAGE='0402',
 PHYS_PAGE='23',
 XY='(-8350,2300)',
 ROT='0',
 VER='2',
 CDS_LIB='passive',
 CDS_PART_NAME='CAPACITOR-G105-0B104-CK,0.1UF,A',
 TOLERANCE='10%',
 CLS_PN='G105-0B104-CK',
 VOLTAGE='10V',
 VALUE='0.1UF',
 PRIM_FILE='./archive_libs/passive/capacitor/chips/chips.prt';

PART_NAME
 C85 'CAPACITOR-G105-0B104-CK,0.1UF,A':;

SECTION_NUMBER 1
 '@TIMECARD_LIB.TIMECARD(SCH_1):PAGE12_I272@PASSIVE.CAPACITOR(CHIPS)':
 C_PATH='@timecard_lib.timecard(sch_1):page12_i272@passive.capacitor(chips)',
 P_PATH='@timecard_lib.timecard(sch_1):page23_i272@passive.capacitor(chips)',
 PATH='I272',
 DRAWING='@TIMECARD_LIB.TIMECARD(SCH_1):PAGE12',
 PACKAGE='0402',
 PHYS_PAGE='23',
 XY='(-8400,4450)',
 ROT='0',
 VER='2',
 CDS_LIB='passive',
 CDS_PART_NAME='CAPACITOR-G105-0B104-CK,0.1UF,A',
 TOLERANCE='10%',
 CLS_PN='G105-0B104-CK',
 VOLTAGE='10V',
 VALUE='0.1UF',
 PRIM_FILE='./archive_libs/passive/capacitor/chips/chips.prt';

PART_NAME
 C86 'CAPACITOR-G104-0A180-FJ,18PF,5%':;

SECTION_NUMBER 1
 '@TIMECARD_LIB.TIMECARD(SCH_1):PAGE524_I7@PASSIVE.CAPACITOR(CHIPS)':
 C_PATH='@timecard_lib.timecard(sch_1):page524_i7@passive.capacitor(chips)',
 P_PATH='@timecard_lib.timecard(sch_1):page24_i7@passive.capacitor(chips)',
 PATH='I7',
 DRAWING='@TIMECARD_LIB.TIMECARD(SCH_1):PAGE524',
 PACKAGE='0201',
 PHYS_PAGE='24',
 XY='(-10700,7400)',
 ROT='1',
 VER='1',
 CDS_LIB='passive',
 CDS_PART_NAME='CAPACITOR-G104-0A180-FJ,18PF,5%',
 TOLERANCE='5%',
 CLS_PN='G104-0A180-FJ',
 VALUE='18PF',
 PRIM_FILE='./archive_libs/passive/capacitor/chips/chips.prt';

PART_NAME
 C87 'CAPACITOR-G104-0A180-FJ,18PF,5%':;

SECTION_NUMBER 1
 '@TIMECARD_LIB.TIMECARD(SCH_1):PAGE524_I10@PASSIVE.CAPACITOR(CHIPS)':
 C_PATH='@timecard_lib.timecard(sch_1):page524_i10@passive.capacitor(chips)',
 P_PATH='@timecard_lib.timecard(sch_1):page24_i10@passive.capacitor(chips)',
 PATH='I10',
 DRAWING='@TIMECARD_LIB.TIMECARD(SCH_1):PAGE524',
 PACKAGE='0201',
 PHYS_PAGE='24',
 XY='(-9650,7600)',
 ROT='1',
 VER='1',
 CDS_LIB='passive',
 CDS_PART_NAME='CAPACITOR-G104-0A180-FJ,18PF,5%',
 TOLERANCE='5%',
 CLS_PN='G104-0A180-FJ',
 VALUE='18PF',
 PRIM_FILE='./archive_libs/passive/capacitor/chips/chips.prt';

PART_NAME
 C88 'CAPACITOR-G105-0B104-EK,0.1UF,A':;

SECTION_NUMBER 1
 '@TIMECARD_LIB.TIMECARD(SCH_1):PAGE524_I378@PASSIVE.CAPACITOR(CHIPS)':
 C_PATH='@timecard_lib.timecard(sch_1):page524_i378@passive.capacitor(chips)',
 P_PATH='@timecard_lib.timecard(sch_1):page24_i378@passive.capacitor(chips)',
 PATH='I378',
 DRAWING='@TIMECARD_LIB.TIMECARD(SCH_1):PAGE524',
 PACKAGE='0402',
 PHYS_PAGE='24',
 XY='(-14150,7550)',
 ROT='2',
 VER='2',
 CDS_LIB='passive',
 CDS_PART_NAME='CAPACITOR-G105-0B104-EK,0.1UF,A',
 TOLERANCE='10%',
 CLS_PN='G105-0B104-EK',
 VOLTAGE='25V',
 VALUE='0.1UF',
 PRIM_FILE='./archive_libs/passive/capacitor/chips/chips.prt';

PART_NAME
 C89 'CAPACITOR-G105-0B104-EK,0.1UF,A':;

SECTION_NUMBER 1
 '@TIMECARD_LIB.TIMECARD(SCH_1):PAGE524_I474@PASSIVE.CAPACITOR(CHIPS)':
 C_PATH='@timecard_lib.timecard(sch_1):page524_i474@passive.capacitor(chips)',
 P_PATH='@timecard_lib.timecard(sch_1):page24_i474@passive.capacitor(chips)',
 PATH='I474',
 DRAWING='@TIMECARD_LIB.TIMECARD(SCH_1):PAGE524',
 PACKAGE='0402',
 PHYS_PAGE='24',
 XY='(-13200,2550)',
 ROT='2',
 VER='2',
 CDS_LIB='passive',
 CDS_PART_NAME='CAPACITOR-G105-0B104-EK,0.1UF,A',
 TOLERANCE='10%',
 CLS_PN='G105-0B104-EK',
 VOLTAGE='25V',
 VALUE='0.1UF',
 PRIM_FILE='./archive_libs/passive/capacitor/chips/chips.prt';

PART_NAME
 C90 'CAPACITOR-G105-0F475-BM,4.7UF,A':;

SECTION_NUMBER 1
 '@TIMECARD_LIB.TIMECARD(SCH_1):PAGE524_I123@PASSIVE.CAPACITOR(CHIPS)':
 C_PATH='@timecard_lib.timecard(sch_1):page524_i123@passive.capacitor(chips)',
 P_PATH='@timecard_lib.timecard(sch_1):page24_i123@passive.capacitor(chips)',
 PATH='I123',
 DRAWING='@TIMECARD_LIB.TIMECARD(SCH_1):PAGE524',
 PACKAGE='0402',
 PHYS_PAGE='24',
 XY='(-11450,10750)',
 ROT='0',
 VER='2',
 CDS_LIB='passive',
 CDS_PART_NAME='CAPACITOR-G105-0F475-BM,4.7UF,A',
 TOLERANCE='20%',
 CLS_PN='G105-0F475-BM',
 VALUE='4.7UF',
 PRIM_FILE='./archive_libs/passive/capacitor/chips/chips.prt';

PART_NAME
 C91 'CAPACITOR-G105-0F475-BM,4.7UF,A':;

SECTION_NUMBER 1
 '@TIMECARD_LIB.TIMECARD(SCH_1):PAGE524_I128@PASSIVE.CAPACITOR(CHIPS)':
 C_PATH='@timecard_lib.timecard(sch_1):page524_i128@passive.capacitor(chips)',
 P_PATH='@timecard_lib.timecard(sch_1):page24_i128@passive.capacitor(chips)',
 PATH='I128',
 DRAWING='@TIMECARD_LIB.TIMECARD(SCH_1):PAGE524',
 PACKAGE='0402',
 PHYS_PAGE='24',
 XY='(-11450,11650)',
 ROT='0',
 VER='2',
 CDS_LIB='passive',
 CDS_PART_NAME='CAPACITOR-G105-0F475-BM,4.7UF,A',
 TOLERANCE='20%',
 CLS_PN='G105-0F475-BM',
 VOLTAGE='6.3V',
 VALUE='4.7UF',
 PRIM_FILE='./archive_libs/passive/capacitor/chips/chips.prt';

PART_NAME
 C92 'CAPACITOR-G105-0B104-EK,0.1UF,A':;

SECTION_NUMBER 1
 '@TIMECARD_LIB.TIMECARD(SCH_1):PAGE524_I476@PASSIVE.CAPACITOR(CHIPS)':
 C_PATH='@timecard_lib.timecard(sch_1):page524_i476@passive.capacitor(chips)',
 P_PATH='@timecard_lib.timecard(sch_1):page24_i476@passive.capacitor(chips)',
 PATH='I476',
 DRAWING='@TIMECARD_LIB.TIMECARD(SCH_1):PAGE524',
 PACKAGE='0402',
 PHYS_PAGE='24',
 XY='(-11900,2550)',
 ROT='2',
 VER='2',
 CDS_LIB='passive',
 CDS_PART_NAME='CAPACITOR-G105-0B104-EK,0.1UF,A',
 TOLERANCE='10%',
 CLS_PN='G105-0B104-EK',
 VOLTAGE='25V',
 VALUE='0.1UF',
 PRIM_FILE='./archive_libs/passive/capacitor/chips/chips.prt';

PART_NAME
 C93 'CAPACITOR-G105-0F475-BM,4.7UF,A':;

SECTION_NUMBER 1
 '@TIMECARD_LIB.TIMECARD(SCH_1):PAGE164_I292@PASSIVE.CAPACITOR(CHIPS)':
 C_PATH='@timecard_lib.timecard(sch_1):page164_i292@passive.capacitor(chips)',
 P_PATH='@timecard_lib.timecard(sch_1):page14_i292@passive.capacitor(chips)',
 PATH='I292',
 DRAWING='@TIMECARD_LIB.TIMECARD(SCH_1):PAGE164',
 PACKAGE='0402',
 PHYS_PAGE='14',
 XY='(-6050,2050)',
 ROT='0',
 VER='2',
 CDS_LIB='passive',
 CDS_PART_NAME='CAPACITOR-G105-0F475-BM,4.7UF,A',
 TOLERANCE='20%',
 CLS_PN='G105-0F475-BM',
 VOLTAGE='6.3V',
 VALUE='4.7UF',
 PRIM_FILE='./archive_libs/passive/capacitor/chips/chips.prt';

PART_NAME
 C94 'CAPACITOR-G105-0B104-EK,0.1UF,A':;

SECTION_NUMBER 1
 '@TIMECARD_LIB.TIMECARD(SCH_1):PAGE524_I377@PASSIVE.CAPACITOR(CHIPS)':
 C_PATH='@timecard_lib.timecard(sch_1):page524_i377@passive.capacitor(chips)',
 P_PATH='@timecard_lib.timecard(sch_1):page24_i377@passive.capacitor(chips)',
 PATH='I377',
 DRAWING='@TIMECARD_LIB.TIMECARD(SCH_1):PAGE524',
 PACKAGE='0402',
 PHYS_PAGE='24',
 XY='(-11700,9150)',
 ROT='2',
 VER='2',
 CDS_LIB='passive',
 CDS_PART_NAME='CAPACITOR-G105-0B104-EK,0.1UF,A',
 TOLERANCE='10%',
 CLS_PN='G105-0B104-EK',
 VOLTAGE='25V',
 VALUE='0.1UF',
 PRIM_FILE='./archive_libs/passive/capacitor/chips/chips.prt';

PART_NAME
 C95 'CAPACITOR-G105-0B104-EK,0.1UF,A':;

SECTION_NUMBER 1
 '@TIMECARD_LIB.TIMECARD(SCH_1):PAGE524_I375@PASSIVE.CAPACITOR(CHIPS)':
 C_PATH='@timecard_lib.timecard(sch_1):page524_i375@passive.capacitor(chips)',
 P_PATH='@timecard_lib.timecard(sch_1):page24_i375@passive.capacitor(chips)',
 PATH='I375',
 DRAWING='@TIMECARD_LIB.TIMECARD(SCH_1):PAGE524',
 PACKAGE='0402',
 PHYS_PAGE='24',
 XY='(-10900,11600)',
 ROT='2',
 VER='2',
 CDS_LIB='passive',
 CDS_PART_NAME='CAPACITOR-G105-0B104-EK,0.1UF,A',
 TOLERANCE='10%',
 CLS_PN='G105-0B104-EK',
 VOLTAGE='25V',
 VALUE='0.1UF',
 PRIM_FILE='./archive_libs/passive/capacitor/chips/chips.prt';

PART_NAME
 C96 'CAPACITOR-G105-0B104-EK,0.1UF,A':;

SECTION_NUMBER 1
 '@TIMECARD_LIB.TIMECARD(SCH_1):PAGE524_I376@PASSIVE.CAPACITOR(CHIPS)':
 C_PATH='@timecard_lib.timecard(sch_1):page524_i376@passive.capacitor(chips)',
 P_PATH='@timecard_lib.timecard(sch_1):page24_i376@passive.capacitor(chips)',
 PATH='I376',
 DRAWING='@TIMECARD_LIB.TIMECARD(SCH_1):PAGE524',
 PACKAGE='0402',
 PHYS_PAGE='24',
 XY='(-10900,10750)',
 ROT='2',
 VER='2',
 CDS_LIB='passive',
 CDS_PART_NAME='CAPACITOR-G105-0B104-EK,0.1UF,A',
 TOLERANCE='10%',
 CLS_PN='G105-0B104-EK',
 VOLTAGE='25V',
 VALUE='0.1UF',
 PRIM_FILE='./archive_libs/passive/capacitor/chips/chips.prt';

PART_NAME
 C97 'CAPACITOR-G105-0B104-EK,0.1UF,A':;

SECTION_NUMBER 1
 '@TIMECARD_LIB.TIMECARD(SCH_1):PAGE524_I482@PASSIVE.CAPACITOR(CHIPS)':
 C_PATH='@timecard_lib.timecard(sch_1):page524_i482@passive.capacitor(chips)',
 P_PATH='@timecard_lib.timecard(sch_1):page24_i482@passive.capacitor(chips)',
 PATH='I482',
 DRAWING='@TIMECARD_LIB.TIMECARD(SCH_1):PAGE524',
 PACKAGE='0402',
 PHYS_PAGE='24',
 XY='(-10650,2550)',
 ROT='2',
 VER='2',
 CDS_LIB='passive',
 CDS_PART_NAME='CAPACITOR-G105-0B104-EK,0.1UF,A',
 TOLERANCE='10%',
 CLS_PN='G105-0B104-EK',
 VOLTAGE='25V',
 VALUE='0.1UF',
 PRIM_FILE='./archive_libs/passive/capacitor/chips/chips.prt';

PART_NAME
 C98 'CAPACITOR-G105-0F475-BM,4.7UF,A':;

SECTION_NUMBER 1
 '@TIMECARD_LIB.TIMECARD(SCH_1):PAGE524_I379@PASSIVE.CAPACITOR(CHIPS)':
 C_PATH='@timecard_lib.timecard(sch_1):page524_i379@passive.capacitor(chips)',
 P_PATH='@timecard_lib.timecard(sch_1):page24_i379@passive.capacitor(chips)',
 PATH='I379',
 DRAWING='@TIMECARD_LIB.TIMECARD(SCH_1):PAGE524',
 PACKAGE='0402',
 PHYS_PAGE='24',
 XY='(-9500,11600)',
 ROT='0',
 VER='2',
 CDS_LIB='passive',
 CDS_PART_NAME='CAPACITOR-G105-0F475-BM,4.7UF,A',
 TOLERANCE='20%',
 CLS_PN='G105-0F475-BM',
 VOLTAGE='6.3V',
 VALUE='4.7UF',
 PRIM_FILE='./archive_libs/passive/capacitor/chips/chips.prt';

PART_NAME
 C99 'CAPACITOR-G105-0F475-BM,4.7UF,A':;

SECTION_NUMBER 1
 '@TIMECARD_LIB.TIMECARD(SCH_1):PAGE524_I380@PASSIVE.CAPACITOR(CHIPS)':
 C_PATH='@timecard_lib.timecard(sch_1):page524_i380@passive.capacitor(chips)',
 P_PATH='@timecard_lib.timecard(sch_1):page24_i380@passive.capacitor(chips)',
 PATH='I380',
 DRAWING='@TIMECARD_LIB.TIMECARD(SCH_1):PAGE524',
 PACKAGE='0402',
 PHYS_PAGE='24',
 XY='(-9500,10800)',
 ROT='0',
 VER='2',
 CDS_LIB='passive',
 CDS_PART_NAME='CAPACITOR-G105-0F475-BM,4.7UF,A',
 TOLERANCE='20%',
 CLS_PN='G105-0F475-BM',
 VOLTAGE='6.3V',
 VALUE='4.7UF',
 PRIM_FILE='./archive_libs/passive/capacitor/chips/chips.prt';

PART_NAME
 C100 'CAPACITOR-G105-0B104-EK,0.1UF,A':;

SECTION_NUMBER 1
 '@TIMECARD_LIB.TIMECARD(SCH_1):PAGE524_I374@PASSIVE.CAPACITOR(CHIPS)':
 C_PATH='@timecard_lib.timecard(sch_1):page524_i374@passive.capacitor(chips)',
 P_PATH='@timecard_lib.timecard(sch_1):page24_i374@passive.capacitor(chips)',
 PATH='I374',
 DRAWING='@TIMECARD_LIB.TIMECARD(SCH_1):PAGE524',
 PACKAGE='0402',
 PHYS_PAGE='24',
 XY='(-9000,11600)',
 ROT='2',
 VER='2',
 CDS_LIB='passive',
 CDS_PART_NAME='CAPACITOR-G105-0B104-EK,0.1UF,A',
 TOLERANCE='10%',
 CLS_PN='G105-0B104-EK',
 VOLTAGE='25V',
 VALUE='0.1UF',
 PRIM_FILE='./archive_libs/passive/capacitor/chips/chips.prt';

PART_NAME
 C101 'CAPACITOR-G105-0B104-EK,0.1UF,A':;

SECTION_NUMBER 1
 '@TIMECARD_LIB.TIMECARD(SCH_1):PAGE524_I373@PASSIVE.CAPACITOR(CHIPS)':
 C_PATH='@timecard_lib.timecard(sch_1):page524_i373@passive.capacitor(chips)',
 P_PATH='@timecard_lib.timecard(sch_1):page24_i373@passive.capacitor(chips)',
 PATH='I373',
 DRAWING='@TIMECARD_LIB.TIMECARD(SCH_1):PAGE524',
 PACKAGE='0402',
 PHYS_PAGE='24',
 XY='(-9000,10800)',
 ROT='2',
 VER='2',
 CDS_LIB='passive',
 CDS_PART_NAME='CAPACITOR-G105-0B104-EK,0.1UF,A',
 TOLERANCE='10%',
 CLS_PN='G105-0B104-EK',
 VOLTAGE='25V',
 VALUE='0.1UF',
 PRIM_FILE='./archive_libs/passive/capacitor/chips/chips.prt';

PART_NAME
 C102 'CAPACITOR-G105-0B104-EK,0.1UF,A':;

SECTION_NUMBER 1
 '@TIMECARD_LIB.TIMECARD(SCH_1):PAGE524_I490@PASSIVE.CAPACITOR(CHIPS)':
 C_PATH='@timecard_lib.timecard(sch_1):page524_i490@passive.capacitor(chips)',
 P_PATH='@timecard_lib.timecard(sch_1):page24_i490@passive.capacitor(chips)',
 PATH='I490',
 DRAWING='@TIMECARD_LIB.TIMECARD(SCH_1):PAGE524',
 PACKAGE='0402',
 PHYS_PAGE='24',
 XY='(-4350,2550)',
 ROT='2',
 VER='2',
 CDS_LIB='passive',
 CDS_PART_NAME='CAPACITOR-G105-0B104-EK,0.1UF,A',
 TOLERANCE='10%',
 CLS_PN='G105-0B104-EK',
 VOLTAGE='25V',
 VALUE='0.1UF',
 PRIM_FILE='./archive_libs/passive/capacitor/chips/chips.prt';

PART_NAME
 C103 'CAPACITOR-G105-0B104-CK,0.1UF,A':;

SECTION_NUMBER 1
 '@TIMECARD_LIB.TIMECARD(SCH_1):PAGE164_I208@PASSIVE.CAPACITOR(CHIPS)':
 C_PATH='@timecard_lib.timecard(sch_1):page164_i208@passive.capacitor(chips)',
 P_PATH='@timecard_lib.timecard(sch_1):page14_i208@passive.capacitor(chips)',
 PATH='I208',
 DRAWING='@TIMECARD_LIB.TIMECARD(SCH_1):PAGE164',
 PACKAGE='0402',
 PHYS_PAGE='14',
 XY='(-9800,4300)',
 ROT='0',
 VER='2',
 CDS_LIB='passive',
 CDS_PART_NAME='CAPACITOR-G105-0B104-CK,0.1UF,A',
 TOLERANCE='10%',
 CLS_PN='G105-0B104-CK',
 VOLTAGE='10V',
 VALUE='0.1UF',
 PRIM_FILE='./archive_libs/passive/capacitor/chips/chips.prt';

PART_NAME
 C104 'CAPACITOR-G105-0B104-CK,0.1UF,A':;

SECTION_NUMBER 1
 '@TIMECARD_LIB.TIMECARD(SCH_1):PAGE164_I257@PASSIVE.CAPACITOR(CHIPS)':
 C_PATH='@timecard_lib.timecard(sch_1):page164_i257@passive.capacitor(chips)',
 P_PATH='@timecard_lib.timecard(sch_1):page14_i257@passive.capacitor(chips)',
 PATH='I257',
 DRAWING='@TIMECARD_LIB.TIMECARD(SCH_1):PAGE164',
 PACKAGE='0402',
 PHYS_PAGE='14',
 XY='(-9800,-650)',
 ROT='0',
 VER='2',
 CDS_LIB='passive',
 CDS_PART_NAME='CAPACITOR-G105-0B104-CK,0.1UF,A',
 TOLERANCE='10%',
 CLS_PN='G105-0B104-CK',
 VOLTAGE='10V',
 VALUE='0.1UF',
 PRIM_FILE='./archive_libs/passive/capacitor/chips/chips.prt';

PART_NAME
 C105 'CAPACITOR-G105-0B104-CK,0.1UF,A':;

SECTION_NUMBER 1
 '@TIMECARD_LIB.TIMECARD(SCH_1):PAGE164_I252@PASSIVE.CAPACITOR(CHIPS)':
 C_PATH='@timecard_lib.timecard(sch_1):page164_i252@passive.capacitor(chips)',
 P_PATH='@timecard_lib.timecard(sch_1):page14_i252@passive.capacitor(chips)',
 PATH='I252',
 DRAWING='@TIMECARD_LIB.TIMECARD(SCH_1):PAGE164',
 PACKAGE='0402',
 PHYS_PAGE='14',
 XY='(-9750,450)',
 ROT='0',
 VER='2',
 CDS_LIB='passive',
 CDS_PART_NAME='CAPACITOR-G105-0B104-CK,0.1UF,A',
 TOLERANCE='10%',
 CLS_PN='G105-0B104-CK',
 VOLTAGE='10V',
 VALUE='0.1UF',
 PRIM_FILE='./archive_libs/passive/capacitor/chips/chips.prt';

PART_NAME
 C106 'CAPACITOR-G105-0B104-CK,0.1UF,A':;

SECTION_NUMBER 1
 '@TIMECARD_LIB.TIMECARD(SCH_1):PAGE164_I203@PASSIVE.CAPACITOR(CHIPS)':
 C_PATH='@timecard_lib.timecard(sch_1):page164_i203@passive.capacitor(chips)',
 P_PATH='@timecard_lib.timecard(sch_1):page14_i203@passive.capacitor(chips)',
 PATH='I203',
 DRAWING='@TIMECARD_LIB.TIMECARD(SCH_1):PAGE164',
 PACKAGE='0402',
 PHYS_PAGE='14',
 XY='(-9500,7150)',
 ROT='0',
 VER='2',
 CDS_LIB='passive',
 CDS_PART_NAME='CAPACITOR-G105-0B104-CK,0.1UF,A',
 TOLERANCE='10%',
 CLS_PN='G105-0B104-CK',
 VOLTAGE='10V',
 VALUE='0.1UF',
 PRIM_FILE='./archive_libs/passive/capacitor/chips/chips.prt';

PART_NAME
 C107 'CAPACITOR-G105-0B104-CK,0.1UF,A':;

SECTION_NUMBER 1
 '@TIMECARD_LIB.TIMECARD(SCH_1):PAGE164_I220@PASSIVE.CAPACITOR(CHIPS)':
 C_PATH='@timecard_lib.timecard(sch_1):page164_i220@passive.capacitor(chips)',
 P_PATH='@timecard_lib.timecard(sch_1):page14_i220@passive.capacitor(chips)',
 PATH='I220',
 DRAWING='@TIMECARD_LIB.TIMECARD(SCH_1):PAGE164',
 PACKAGE='0402',
 PHYS_PAGE='14',
 XY='(-9500,3450)',
 ROT='0',
 VER='2',
 CDS_LIB='passive',
 CDS_PART_NAME='CAPACITOR-G105-0B104-CK,0.1UF,A',
 TOLERANCE='10%',
 CLS_PN='G105-0B104-CK',
 VOLTAGE='10V',
 VALUE='0.1UF',
 PRIM_FILE='./archive_libs/passive/capacitor/chips/chips.prt';

PART_NAME
 C108 'CAPACITOR-G105-0B104-CK,0.1UF,A':;

SECTION_NUMBER 1
 '@TIMECARD_LIB.TIMECARD(SCH_1):PAGE164_I235@PASSIVE.CAPACITOR(CHIPS)':
 C_PATH='@timecard_lib.timecard(sch_1):page164_i235@passive.capacitor(chips)',
 P_PATH='@timecard_lib.timecard(sch_1):page14_i235@passive.capacitor(chips)',
 PATH='I235',
 DRAWING='@TIMECARD_LIB.TIMECARD(SCH_1):PAGE164',
 PACKAGE='0402',
 PHYS_PAGE='14',
 XY='(-9500,2050)',
 ROT='0',
 VER='2',
 CDS_LIB='passive',
 CDS_PART_NAME='CAPACITOR-G105-0B104-CK,0.1UF,A',
 TOLERANCE='10%',
 CLS_PN='G105-0B104-CK',
 VOLTAGE='10V',
 VALUE='0.1UF',
 PRIM_FILE='./archive_libs/passive/capacitor/chips/chips.prt';

PART_NAME
 C109 'CAPACITOR-G105-0B104-CK,0.1UF,A':;

SECTION_NUMBER 1
 '@TIMECARD_LIB.TIMECARD(SCH_1):PAGE164_I186@PASSIVE.CAPACITOR(CHIPS)':
 C_PATH='@timecard_lib.timecard(sch_1):page164_i186@passive.capacitor(chips)',
 P_PATH='@timecard_lib.timecard(sch_1):page14_i186@passive.capacitor(chips)',
 PATH='I186',
 DRAWING='@TIMECARD_LIB.TIMECARD(SCH_1):PAGE164',
 PACKAGE='0402',
 PHYS_PAGE='14',
 XY='(-9450,5700)',
 ROT='0',
 VER='2',
 CDS_LIB='passive',
 CDS_PART_NAME='CAPACITOR-G105-0B104-CK,0.1UF,A',
 TOLERANCE='10%',
 CLS_PN='G105-0B104-CK',
 VOLTAGE='10V',
 VALUE='0.1UF',
 PRIM_FILE='./archive_libs/passive/capacitor/chips/chips.prt';

PART_NAME
 C110 'CAPACITOR-G105-0B104-CK,0.1UF,A':;

SECTION_NUMBER 1
 '@TIMECARD_LIB.TIMECARD(SCH_1):PAGE164_I256@PASSIVE.CAPACITOR(CHIPS)':
 C_PATH='@timecard_lib.timecard(sch_1):page164_i256@passive.capacitor(chips)',
 P_PATH='@timecard_lib.timecard(sch_1):page14_i256@passive.capacitor(chips)',
 PATH='I256',
 DRAWING='@TIMECARD_LIB.TIMECARD(SCH_1):PAGE164',
 PACKAGE='0402',
 PHYS_PAGE='14',
 XY='(-9450,-650)',
 ROT='0',
 VER='2',
 CDS_LIB='passive',
 CDS_PART_NAME='CAPACITOR-G105-0B104-CK,0.1UF,A',
 TOLERANCE='10%',
 CLS_PN='G105-0B104-CK',
 VOLTAGE='10V',
 VALUE='0.1UF',
 PRIM_FILE='./archive_libs/passive/capacitor/chips/chips.prt';

PART_NAME
 C111 'CAPACITOR-G105-0B104-CK,0.1UF,A':;

SECTION_NUMBER 1
 '@TIMECARD_LIB.TIMECARD(SCH_1):PAGE164_I253@PASSIVE.CAPACITOR(CHIPS)':
 C_PATH='@timecard_lib.timecard(sch_1):page164_i253@passive.capacitor(chips)',
 P_PATH='@timecard_lib.timecard(sch_1):page14_i253@passive.capacitor(chips)',
 PATH='I253',
 DRAWING='@TIMECARD_LIB.TIMECARD(SCH_1):PAGE164',
 PACKAGE='0402',
 PHYS_PAGE='14',
 XY='(-9400,450)',
 ROT='0',
 VER='2',
 CDS_LIB='passive',
 CDS_PART_NAME='CAPACITOR-G105-0B104-CK,0.1UF,A',
 TOLERANCE='10%',
 CLS_PN='G105-0B104-CK',
 VOLTAGE='10V',
 VALUE='0.1UF',
 PRIM_FILE='./archive_libs/passive/capacitor/chips/chips.prt';

PART_NAME
 C112 'CAPACITOR-G105-0B104-CK,0.1UF,A':;

SECTION_NUMBER 1
 '@TIMECARD_LIB.TIMECARD(SCH_1):PAGE164_I209@PASSIVE.CAPACITOR(CHIPS)':
 C_PATH='@timecard_lib.timecard(sch_1):page164_i209@passive.capacitor(chips)',
 P_PATH='@timecard_lib.timecard(sch_1):page14_i209@passive.capacitor(chips)',
 PATH='I209',
 DRAWING='@TIMECARD_LIB.TIMECARD(SCH_1):PAGE164',
 PACKAGE='0402',
 PHYS_PAGE='14',
 XY='(-9350,4300)',
 ROT='0',
 VER='2',
 CDS_LIB='passive',
 CDS_PART_NAME='CAPACITOR-G105-0B104-CK,0.1UF,A',
 TOLERANCE='10%',
 CLS_PN='G105-0B104-CK',
 VOLTAGE='10V',
 VALUE='0.1UF',
 PRIM_FILE='./archive_libs/passive/capacitor/chips/chips.prt';

PART_NAME
 C113 'CAPACITOR-G105-0B104-CK,0.1UF,A':;

SECTION_NUMBER 1
 '@TIMECARD_LIB.TIMECARD(SCH_1):PAGE164_I204@PASSIVE.CAPACITOR(CHIPS)':
 C_PATH='@timecard_lib.timecard(sch_1):page164_i204@passive.capacitor(chips)',
 P_PATH='@timecard_lib.timecard(sch_1):page14_i204@passive.capacitor(chips)',
 PATH='I204',
 DRAWING='@TIMECARD_LIB.TIMECARD(SCH_1):PAGE164',
 PACKAGE='0402',
 PHYS_PAGE='14',
 XY='(-9100,7150)',
 ROT='0',
 VER='2',
 CDS_LIB='passive',
 CDS_PART_NAME='CAPACITOR-G105-0B104-CK,0.1UF,A',
 TOLERANCE='10%',
 CLS_PN='G105-0B104-CK',
 VOLTAGE='10V',
 VALUE='0.1UF',
 PRIM_FILE='./archive_libs/passive/capacitor/chips/chips.prt';

PART_NAME
 C114 'CAPACITOR-G105-0B104-CK,0.1UF,A':;

SECTION_NUMBER 1
 '@TIMECARD_LIB.TIMECARD(SCH_1):PAGE164_I187@PASSIVE.CAPACITOR(CHIPS)':
 C_PATH='@timecard_lib.timecard(sch_1):page164_i187@passive.capacitor(chips)',
 P_PATH='@timecard_lib.timecard(sch_1):page14_i187@passive.capacitor(chips)',
 PATH='I187',
 DRAWING='@TIMECARD_LIB.TIMECARD(SCH_1):PAGE164',
 PACKAGE='0402',
 PHYS_PAGE='14',
 XY='(-9100,5700)',
 ROT='0',
 VER='2',
 CDS_LIB='passive',
 CDS_PART_NAME='CAPACITOR-G105-0B104-CK,0.1UF,A',
 TOLERANCE='10%',
 CLS_PN='G105-0B104-CK',
 VOLTAGE='10V',
 VALUE='0.1UF',
 PRIM_FILE='./archive_libs/passive/capacitor/chips/chips.prt';

PART_NAME
 C115 'CAPACITOR-G105-0B104-CK,0.1UF,A':;

SECTION_NUMBER 1
 '@TIMECARD_LIB.TIMECARD(SCH_1):PAGE164_I221@PASSIVE.CAPACITOR(CHIPS)':
 C_PATH='@timecard_lib.timecard(sch_1):page164_i221@passive.capacitor(chips)',
 P_PATH='@timecard_lib.timecard(sch_1):page14_i221@passive.capacitor(chips)',
 PATH='I221',
 DRAWING='@TIMECARD_LIB.TIMECARD(SCH_1):PAGE164',
 PACKAGE='0402',
 PHYS_PAGE='14',
 XY='(-9100,3450)',
 ROT='0',
 VER='2',
 CDS_LIB='passive',
 CDS_PART_NAME='CAPACITOR-G105-0B104-CK,0.1UF,A',
 TOLERANCE='10%',
 CLS_PN='G105-0B104-CK',
 VOLTAGE='10V',
 VALUE='0.1UF',
 PRIM_FILE='./archive_libs/passive/capacitor/chips/chips.prt';

PART_NAME
 C116 'CAPACITOR-G105-0B104-CK,0.1UF,A':;

SECTION_NUMBER 1
 '@TIMECARD_LIB.TIMECARD(SCH_1):PAGE164_I236@PASSIVE.CAPACITOR(CHIPS)':
 C_PATH='@timecard_lib.timecard(sch_1):page164_i236@passive.capacitor(chips)',
 P_PATH='@timecard_lib.timecard(sch_1):page14_i236@passive.capacitor(chips)',
 PATH='I236',
 DRAWING='@TIMECARD_LIB.TIMECARD(SCH_1):PAGE164',
 PACKAGE='0402',
 PHYS_PAGE='14',
 XY='(-9100,2050)',
 ROT='0',
 VER='2',
 CDS_LIB='passive',
 CDS_PART_NAME='CAPACITOR-G105-0B104-CK,0.1UF,A',
 TOLERANCE='10%',
 CLS_PN='G105-0B104-CK',
 VOLTAGE='10V',
 VALUE='0.1UF',
 PRIM_FILE='./archive_libs/passive/capacitor/chips/chips.prt';

PART_NAME
 C117 'CAPACITOR-G105-0F475-BM,4.7UF,A':;

SECTION_NUMBER 1
 '@TIMECARD_LIB.TIMECARD(SCH_1):PAGE164_I246@PASSIVE.CAPACITOR(CHIPS)':
 C_PATH='@timecard_lib.timecard(sch_1):page164_i246@passive.capacitor(chips)',
 P_PATH='@timecard_lib.timecard(sch_1):page14_i246@passive.capacitor(chips)',
 PATH='I246',
 DRAWING='@TIMECARD_LIB.TIMECARD(SCH_1):PAGE164',
 PACKAGE='0402',
 PHYS_PAGE='14',
 XY='(-9100,-650)',
 ROT='0',
 VER='2',
 CDS_LIB='passive',
 CDS_PART_NAME='CAPACITOR-G105-0F475-BM,4.7UF,A',
 TOLERANCE='20%',
 CLS_PN='G105-0F475-BM',
 VOLTAGE='6.3V',
 VALUE='4.7UF',
 PRIM_FILE='./archive_libs/passive/capacitor/chips/chips.prt';

PART_NAME
 C118 'CAPACITOR-G105-0B104-CK,0.1UF,A':;

SECTION_NUMBER 1
 '@TIMECARD_LIB.TIMECARD(SCH_1):PAGE164_I254@PASSIVE.CAPACITOR(CHIPS)':
 C_PATH='@timecard_lib.timecard(sch_1):page164_i254@passive.capacitor(chips)',
 P_PATH='@timecard_lib.timecard(sch_1):page14_i254@passive.capacitor(chips)',
 PATH='I254',
 DRAWING='@TIMECARD_LIB.TIMECARD(SCH_1):PAGE164',
 PACKAGE='0402',
 PHYS_PAGE='14',
 XY='(-9050,450)',
 ROT='0',
 VER='2',
 CDS_LIB='passive',
 CDS_PART_NAME='CAPACITOR-G105-0B104-CK,0.1UF,A',
 TOLERANCE='10%',
 CLS_PN='G105-0B104-CK',
 VOLTAGE='10V',
 VALUE='0.1UF',
 PRIM_FILE='./archive_libs/passive/capacitor/chips/chips.prt';

PART_NAME
 C119 'CAPACITOR-G105-0B104-CK,0.1UF,A':;

SECTION_NUMBER 1
 '@TIMECARD_LIB.TIMECARD(SCH_1):PAGE164_I210@PASSIVE.CAPACITOR(CHIPS)':
 C_PATH='@timecard_lib.timecard(sch_1):page164_i210@passive.capacitor(chips)',
 P_PATH='@timecard_lib.timecard(sch_1):page14_i210@passive.capacitor(chips)',
 PATH='I210',
 DRAWING='@TIMECARD_LIB.TIMECARD(SCH_1):PAGE164',
 PACKAGE='0402',
 PHYS_PAGE='14',
 XY='(-8950,4300)',
 ROT='0',
 VER='2',
 CDS_LIB='passive',
 CDS_PART_NAME='CAPACITOR-G105-0B104-CK,0.1UF,A',
 TOLERANCE='10%',
 CLS_PN='G105-0B104-CK',
 VOLTAGE='10V',
 VALUE='0.1UF',
 PRIM_FILE='./archive_libs/passive/capacitor/chips/chips.prt';

PART_NAME
 C120 'CAPACITOR-G105-0F475-BM,4.7UF,A':;

SECTION_NUMBER 1
 '@TIMECARD_LIB.TIMECARD(SCH_1):PAGE164_I177@PASSIVE.CAPACITOR(CHIPS)':
 C_PATH='@timecard_lib.timecard(sch_1):page164_i177@passive.capacitor(chips)',
 P_PATH='@timecard_lib.timecard(sch_1):page14_i177@passive.capacitor(chips)',
 PATH='I177',
 DRAWING='@TIMECARD_LIB.TIMECARD(SCH_1):PAGE164',
 PACKAGE='0402',
 PHYS_PAGE='14',
 XY='(-8750,7150)',
 ROT='0',
 VER='2',
 CDS_LIB='passive',
 CDS_PART_NAME='CAPACITOR-G105-0F475-BM,4.7UF,A',
 TOLERANCE='20%',
 CLS_PN='G105-0F475-BM',
 VOLTAGE='6.3V',
 VALUE='4.7UF',
 PRIM_FILE='./archive_libs/passive/capacitor/chips/chips.prt';

PART_NAME
 C121 'CAPACITOR-G105-0B104-CK,0.1UF,A':;

SECTION_NUMBER 1
 '@TIMECARD_LIB.TIMECARD(SCH_1):PAGE164_I188@PASSIVE.CAPACITOR(CHIPS)':
 C_PATH='@timecard_lib.timecard(sch_1):page164_i188@passive.capacitor(chips)',
 P_PATH='@timecard_lib.timecard(sch_1):page14_i188@passive.capacitor(chips)',
 PATH='I188',
 DRAWING='@TIMECARD_LIB.TIMECARD(SCH_1):PAGE164',
 PACKAGE='0402',
 PHYS_PAGE='14',
 XY='(-8750,5700)',
 ROT='0',
 VER='2',
 CDS_LIB='passive',
 CDS_PART_NAME='CAPACITOR-G105-0B104-CK,0.1UF,A',
 TOLERANCE='10%',
 CLS_PN='G105-0B104-CK',
 VOLTAGE='10V',
 VALUE='0.1UF',
 PRIM_FILE='./archive_libs/passive/capacitor/chips/chips.prt';

PART_NAME
 C122 'CAPACITOR-G105-0B104-CK,0.1UF,A':;

SECTION_NUMBER 1
 '@TIMECARD_LIB.TIMECARD(SCH_1):PAGE164_I237@PASSIVE.CAPACITOR(CHIPS)':
 C_PATH='@timecard_lib.timecard(sch_1):page164_i237@passive.capacitor(chips)',
 P_PATH='@timecard_lib.timecard(sch_1):page14_i237@passive.capacitor(chips)',
 PATH='I237',
 DRAWING='@TIMECARD_LIB.TIMECARD(SCH_1):PAGE164',
 PACKAGE='0402',
 PHYS_PAGE='14',
 XY='(-8750,2050)',
 ROT='0',
 VER='2',
 CDS_LIB='passive',
 CDS_PART_NAME='CAPACITOR-G105-0B104-CK,0.1UF,A',
 TOLERANCE='10%',
 CLS_PN='G105-0B104-CK',
 VOLTAGE='10V',
 VALUE='0.1UF',
 PRIM_FILE='./archive_libs/passive/capacitor/chips/chips.prt';

PART_NAME
 C123 'CAPACITOR-G105-0B104-EK,0.1UF,A':;

SECTION_NUMBER 1
 '@TIMECARD_LIB.TIMECARD(SCH_1):PAGE524_I486@PASSIVE.CAPACITOR(CHIPS)':
 C_PATH='@timecard_lib.timecard(sch_1):page524_i486@passive.capacitor(chips)',
 P_PATH='@timecard_lib.timecard(sch_1):page24_i486@passive.capacitor(chips)',
 PATH='I486',
 DRAWING='@TIMECARD_LIB.TIMECARD(SCH_1):PAGE524',
 PACKAGE='0402',
 PHYS_PAGE='24',
 XY='(-3000,2550)',
 ROT='2',
 VER='2',
 CDS_LIB='passive',
 CDS_PART_NAME='CAPACITOR-G105-0B104-EK,0.1UF,A',
 TOLERANCE='10%',
 CLS_PN='G105-0B104-EK',
 VOLTAGE='25V',
 VALUE='0.1UF',
 PRIM_FILE='./archive_libs/passive/capacitor/chips/chips.prt';

PART_NAME
 C124 'CAPACITOR-G105-0B104-CK,0.1UF,A':;

SECTION_NUMBER 1
 '@TIMECARD_LIB.TIMECARD(SCH_1):PAGE164_I255@PASSIVE.CAPACITOR(CHIPS)':
 C_PATH='@timecard_lib.timecard(sch_1):page164_i255@passive.capacitor(chips)',
 P_PATH='@timecard_lib.timecard(sch_1):page14_i255@passive.capacitor(chips)',
 PATH='I255',
 DRAWING='@TIMECARD_LIB.TIMECARD(SCH_1):PAGE164',
 PACKAGE='0402',
 PHYS_PAGE='14',
 XY='(-8700,450)',
 ROT='0',
 VER='2',
 CDS_LIB='passive',
 CDS_PART_NAME='CAPACITOR-G105-0B104-CK,0.1UF,A',
 TOLERANCE='10%',
 CLS_PN='G105-0B104-CK',
 VOLTAGE='10V',
 VALUE='0.1UF',
 PRIM_FILE='./archive_libs/passive/capacitor/chips/chips.prt';

PART_NAME
 C125 'CAPACITOR-G107-0F476-AM,47UF,2A':;

SECTION_NUMBER 1
 '@TIMECARD_LIB.TIMECARD(SCH_1):PAGE164_I264@PASSIVE.CAPACITOR(CHIPS)':
 C_PATH='@timecard_lib.timecard(sch_1):page164_i264@passive.capacitor(chips)',
 P_PATH='@timecard_lib.timecard(sch_1):page14_i264@passive.capacitor(chips)',
 PATH='I264',
 DRAWING='@TIMECARD_LIB.TIMECARD(SCH_1):PAGE164',
 PACKAGE='0805',
 PHYS_PAGE='14',
 XY='(-8650,-650)',
 ROT='0',
 VER='2',
 CDS_LIB='passive',
 CDS_PART_NAME='CAPACITOR-G107-0F476-AM,47UF,2A',
 TOLERANCE='20%',
 CLS_PN='G107-0F476-AM',
 VOLTAGE='4V',
 VALUE='47UF',
 PRIM_FILE='./archive_libs/passive/capacitor/chips/chips.prt';

PART_NAME
 C126 'CAPACITOR-G105-0B104-CK,0.1UF,A':;

SECTION_NUMBER 1
 '@TIMECARD_LIB.TIMECARD(SCH_1):PAGE164_I211@PASSIVE.CAPACITOR(CHIPS)':
 C_PATH='@timecard_lib.timecard(sch_1):page164_i211@passive.capacitor(chips)',
 P_PATH='@timecard_lib.timecard(sch_1):page14_i211@passive.capacitor(chips)',
 PATH='I211',
 DRAWING='@TIMECARD_LIB.TIMECARD(SCH_1):PAGE164',
 PACKAGE='0402',
 PHYS_PAGE='14',
 XY='(-8600,4300)',
 ROT='0',
 VER='2',
 CDS_LIB='passive',
 CDS_PART_NAME='CAPACITOR-G105-0B104-CK,0.1UF,A',
 TOLERANCE='10%',
 CLS_PN='G105-0B104-CK',
 VOLTAGE='10V',
 VALUE='0.1UF',
 PRIM_FILE='./archive_libs/passive/capacitor/chips/chips.prt';

PART_NAME
 C127 'CAPACITOR-G105-0B104-CK,0.1UF,A':;

SECTION_NUMBER 1
 '@TIMECARD_LIB.TIMECARD(SCH_1):PAGE164_I238@PASSIVE.CAPACITOR(CHIPS)':
 C_PATH='@timecard_lib.timecard(sch_1):page164_i238@passive.capacitor(chips)',
 P_PATH='@timecard_lib.timecard(sch_1):page14_i238@passive.capacitor(chips)',
 PATH='I238',
 DRAWING='@TIMECARD_LIB.TIMECARD(SCH_1):PAGE164',
 PACKAGE='0402',
 PHYS_PAGE='14',
 XY='(-8400,2050)',
 ROT='0',
 VER='2',
 CDS_LIB='passive',
 CDS_PART_NAME='CAPACITOR-G105-0B104-CK,0.1UF,A',
 TOLERANCE='10%',
 CLS_PN='G105-0B104-CK',
 VOLTAGE='10V',
 VALUE='0.1UF',
 PRIM_FILE='./archive_libs/passive/capacitor/chips/chips.prt';

PART_NAME
 C128 'CAPACITOR-G105-0F475-BM,4.7UF,A':;

SECTION_NUMBER 1
 '@TIMECARD_LIB.TIMECARD(SCH_1):PAGE164_I243@PASSIVE.CAPACITOR(CHIPS)':
 C_PATH='@timecard_lib.timecard(sch_1):page164_i243@passive.capacitor(chips)',
 P_PATH='@timecard_lib.timecard(sch_1):page14_i243@passive.capacitor(chips)',
 PATH='I243',
 DRAWING='@TIMECARD_LIB.TIMECARD(SCH_1):PAGE164',
 PACKAGE='0402',
 PHYS_PAGE='14',
 XY='(-8350,7150)',
 ROT='0',
 VER='2',
 CDS_LIB='passive',
 CDS_PART_NAME='CAPACITOR-G105-0F475-BM,4.7UF,A',
 TOLERANCE='20%',
 CLS_PN='G105-0F475-BM',
 VOLTAGE='6.3V',
 VALUE='4.7UF',
 PRIM_FILE='./archive_libs/passive/capacitor/chips/chips.prt';

PART_NAME
 C129 'CAPACITOR-G105-0B104-CK,0.1UF,A':;

SECTION_NUMBER 1
 '@TIMECARD_LIB.TIMECARD(SCH_1):PAGE164_I189@PASSIVE.CAPACITOR(CHIPS)':
 C_PATH='@timecard_lib.timecard(sch_1):page164_i189@passive.capacitor(chips)',
 P_PATH='@timecard_lib.timecard(sch_1):page14_i189@passive.capacitor(chips)',
 PATH='I189',
 DRAWING='@TIMECARD_LIB.TIMECARD(SCH_1):PAGE164',
 PACKAGE='0402',
 PHYS_PAGE='14',
 XY='(-8350,5700)',
 ROT='0',
 VER='2',
 CDS_LIB='passive',
 CDS_PART_NAME='CAPACITOR-G105-0B104-CK,0.1UF,A',
 TOLERANCE='10%',
 CLS_PN='G105-0B104-CK',
 VOLTAGE='10V',
 VALUE='0.1UF',
 PRIM_FILE='./archive_libs/passive/capacitor/chips/chips.prt';

PART_NAME
 C130 'CAPACITOR-G105-0B104-CK,0.1UF,A':;

SECTION_NUMBER 1
 '@TIMECARD_LIB.TIMECARD(SCH_1):PAGE164_I223@PASSIVE.CAPACITOR(CHIPS)':
 C_PATH='@timecard_lib.timecard(sch_1):page164_i223@passive.capacitor(chips)',
 P_PATH='@timecard_lib.timecard(sch_1):page14_i223@passive.capacitor(chips)',
 PATH='I223',
 DRAWING='@TIMECARD_LIB.TIMECARD(SCH_1):PAGE164',
 PACKAGE='0402',
 PHYS_PAGE='14',
 XY='(-8350,3450)',
 ROT='0',
 VER='2',
 CDS_LIB='passive',
 CDS_PART_NAME='CAPACITOR-G105-0B104-CK,0.1UF,A',
 TOLERANCE='10%',
 CLS_PN='G105-0B104-CK',
 VOLTAGE='10V',
 VALUE='0.1UF',
 PRIM_FILE='./archive_libs/passive/capacitor/chips/chips.prt';

PART_NAME
 C131 'CAPACITOR-G105-0F475-BM,4.7UF,A':;

SECTION_NUMBER 1
 '@TIMECARD_LIB.TIMECARD(SCH_1):PAGE164_I248@PASSIVE.CAPACITOR(CHIPS)':
 C_PATH='@timecard_lib.timecard(sch_1):page164_i248@passive.capacitor(chips)',
 P_PATH='@timecard_lib.timecard(sch_1):page14_i248@passive.capacitor(chips)',
 PATH='I248',
 DRAWING='@TIMECARD_LIB.TIMECARD(SCH_1):PAGE164',
 PACKAGE='0402',
 PHYS_PAGE='14',
 XY='(-8350,450)',
 ROT='0',
 VER='2',
 CDS_LIB='passive',
 CDS_PART_NAME='CAPACITOR-G105-0F475-BM,4.7UF,A',
 TOLERANCE='20%',
 CLS_PN='G105-0F475-BM',
 VOLTAGE='6.3V',
 VALUE='4.7UF',
 PRIM_FILE='./archive_libs/passive/capacitor/chips/chips.prt';

PART_NAME
 C132 'CAPACITOR-G105-0B104-CK,0.1UF,A':;

SECTION_NUMBER 1
 '@TIMECARD_LIB.TIMECARD(SCH_1):PAGE164_I212@PASSIVE.CAPACITOR(CHIPS)':
 C_PATH='@timecard_lib.timecard(sch_1):page164_i212@passive.capacitor(chips)',
 P_PATH='@timecard_lib.timecard(sch_1):page14_i212@passive.capacitor(chips)',
 PATH='I212',
 DRAWING='@TIMECARD_LIB.TIMECARD(SCH_1):PAGE164',
 PACKAGE='0402',
 PHYS_PAGE='14',
 XY='(-8250,4300)',
 ROT='0',
 VER='2',
 CDS_LIB='passive',
 CDS_PART_NAME='CAPACITOR-G105-0B104-CK,0.1UF,A',
 TOLERANCE='10%',
 CLS_PN='G105-0B104-CK',
 VOLTAGE='10V',
 VALUE='0.1UF',
 PRIM_FILE='./archive_libs/passive/capacitor/chips/chips.prt';

PART_NAME
 C133 'CAPACITOR-G105-0B104-CK,0.1UF,A':;

SECTION_NUMBER 1
 '@TIMECARD_LIB.TIMECARD(SCH_1):PAGE164_I190@PASSIVE.CAPACITOR(CHIPS)':
 C_PATH='@timecard_lib.timecard(sch_1):page164_i190@passive.capacitor(chips)',
 P_PATH='@timecard_lib.timecard(sch_1):page14_i190@passive.capacitor(chips)',
 PATH='I190',
 DRAWING='@TIMECARD_LIB.TIMECARD(SCH_1):PAGE164',
 PACKAGE='0402',
 PHYS_PAGE='14',
 XY='(-8000,5700)',
 ROT='0',
 VER='2',
 CDS_LIB='passive',
 CDS_PART_NAME='CAPACITOR-G105-0B104-CK,0.1UF,A',
 TOLERANCE='10%',
 CLS_PN='G105-0B104-CK',
 VOLTAGE='10V',
 VALUE='0.1UF',
 PRIM_FILE='./archive_libs/passive/capacitor/chips/chips.prt';

PART_NAME
 C134 'CAPACITOR-G105-0B104-CK,0.1UF,A':;

SECTION_NUMBER 1
 '@TIMECARD_LIB.TIMECARD(SCH_1):PAGE164_I224@PASSIVE.CAPACITOR(CHIPS)':
 C_PATH='@timecard_lib.timecard(sch_1):page164_i224@passive.capacitor(chips)',
 P_PATH='@timecard_lib.timecard(sch_1):page14_i224@passive.capacitor(chips)',
 PATH='I224',
 DRAWING='@TIMECARD_LIB.TIMECARD(SCH_1):PAGE164',
 PACKAGE='0402',
 PHYS_PAGE='14',
 XY='(-8000,3450)',
 ROT='0',
 VER='2',
 CDS_LIB='passive',
 CDS_PART_NAME='CAPACITOR-G105-0B104-CK,0.1UF,A',
 TOLERANCE='10%',
 CLS_PN='G105-0B104-CK',
 VOLTAGE='10V',
 VALUE='0.1UF',
 PRIM_FILE='./archive_libs/passive/capacitor/chips/chips.prt';

PART_NAME
 C135 'CAPACITOR-G105-0B104-CK,0.1UF,A':;

SECTION_NUMBER 1
 '@TIMECARD_LIB.TIMECARD(SCH_1):PAGE164_I239@PASSIVE.CAPACITOR(CHIPS)':
 C_PATH='@timecard_lib.timecard(sch_1):page164_i239@passive.capacitor(chips)',
 P_PATH='@timecard_lib.timecard(sch_1):page14_i239@passive.capacitor(chips)',
 PATH='I239',
 DRAWING='@TIMECARD_LIB.TIMECARD(SCH_1):PAGE164',
 PACKAGE='0402',
 PHYS_PAGE='14',
 XY='(-8000,2050)',
 ROT='0',
 VER='2',
 CDS_LIB='passive',
 CDS_PART_NAME='CAPACITOR-G105-0B104-CK,0.1UF,A',
 TOLERANCE='10%',
 CLS_PN='G105-0B104-CK',
 VOLTAGE='10V',
 VALUE='0.1UF',
 PRIM_FILE='./archive_libs/passive/capacitor/chips/chips.prt';

PART_NAME
 C136 'CAPACITOR-G105-0B104-CK,0.1UF,A':;

SECTION_NUMBER 1
 '@TIMECARD_LIB.TIMECARD(SCH_1):PAGE164_I249@PASSIVE.CAPACITOR(CHIPS)':
 C_PATH='@timecard_lib.timecard(sch_1):page164_i249@passive.capacitor(chips)',
 P_PATH='@timecard_lib.timecard(sch_1):page14_i249@passive.capacitor(chips)',
 PATH='I249',
 DRAWING='@TIMECARD_LIB.TIMECARD(SCH_1):PAGE164',
 PACKAGE='0402',
 PHYS_PAGE='14',
 XY='(-8000,-650)',
 ROT='0',
 VER='2',
 CDS_LIB='passive',
 CDS_PART_NAME='CAPACITOR-G105-0B104-CK,0.1UF,A',
 TOLERANCE='10%',
 CLS_PN='G105-0B104-CK',
 VOLTAGE='10V',
 VALUE='0.1UF',
 PRIM_FILE='./archive_libs/passive/capacitor/chips/chips.prt';

PART_NAME
 C137 'CAPACITOR-G107-0F476-AM,47UF,2A':;

SECTION_NUMBER 1
 '@TIMECARD_LIB.TIMECARD(SCH_1):PAGE164_I281@PASSIVE.CAPACITOR(CHIPS)':
 C_PATH='@timecard_lib.timecard(sch_1):page164_i281@passive.capacitor(chips)',
 P_PATH='@timecard_lib.timecard(sch_1):page14_i281@passive.capacitor(chips)',
 PATH='I281',
 DRAWING='@TIMECARD_LIB.TIMECARD(SCH_1):PAGE164',
 PHYS_PAGE='14',
 XY='(-7950,450)',
 ROT='0',
 VER='2',
 CDS_LIB='passive',
 CDS_PART_NAME='CAPACITOR-G107-0F476-AM,47UF,2A',
 TOLERANCE='20%',
 CLS_PN='G107-0F476-AM',
 VOLTAGE='4V',
 VALUE='47UF',
 PRIM_FILE='./archive_libs/passive/capacitor/chips/chips.prt';

PART_NAME
 C138 'CAPACITOR-G105-0F475-BM,4.7UF,A':;

SECTION_NUMBER 1
 '@TIMECARD_LIB.TIMECARD(SCH_1):PAGE164_I275@PASSIVE.CAPACITOR(CHIPS)':
 C_PATH='@timecard_lib.timecard(sch_1):page164_i275@passive.capacitor(chips)',
 P_PATH='@timecard_lib.timecard(sch_1):page14_i275@passive.capacitor(chips)',
 PATH='I275',
 DRAWING='@TIMECARD_LIB.TIMECARD(SCH_1):PAGE164',
 PACKAGE='0402',
 PHYS_PAGE='14',
 XY='(-7900,7150)',
 ROT='0',
 VER='2',
 CDS_LIB='passive',
 CDS_PART_NAME='CAPACITOR-G105-0F475-BM,4.7UF,A',
 TOLERANCE='20%',
 CLS_PN='G105-0F475-BM',
 VOLTAGE='6.3V',
 VALUE='4.7UF',
 PRIM_FILE='./archive_libs/passive/capacitor/chips/chips.prt';

PART_NAME
 C139 'CAPACITOR-G105-0B104-CK,0.1UF,A':;

SECTION_NUMBER 1
 '@TIMECARD_LIB.TIMECARD(SCH_1):PAGE164_I213@PASSIVE.CAPACITOR(CHIPS)':
 C_PATH='@timecard_lib.timecard(sch_1):page164_i213@passive.capacitor(chips)',
 P_PATH='@timecard_lib.timecard(sch_1):page14_i213@passive.capacitor(chips)',
 PATH='I213',
 DRAWING='@TIMECARD_LIB.TIMECARD(SCH_1):PAGE164',
 PACKAGE='0402',
 PHYS_PAGE='14',
 XY='(-7900,4300)',
 ROT='0',
 VER='2',
 CDS_LIB='passive',
 CDS_PART_NAME='CAPACITOR-G105-0B104-CK,0.1UF,A',
 TOLERANCE='10%',
 CLS_PN='G105-0B104-CK',
 VOLTAGE='10V',
 VALUE='0.1UF',
 PRIM_FILE='./archive_libs/passive/capacitor/chips/chips.prt';

PART_NAME
 C140 'CAPACITOR-G105-0B104-CK,0.1UF,A':;

SECTION_NUMBER 1
 '@TIMECARD_LIB.TIMECARD(SCH_1):PAGE164_I225@PASSIVE.CAPACITOR(CHIPS)':
 C_PATH='@timecard_lib.timecard(sch_1):page164_i225@passive.capacitor(chips)',
 P_PATH='@timecard_lib.timecard(sch_1):page14_i225@passive.capacitor(chips)',
 PATH='I225',
 DRAWING='@TIMECARD_LIB.TIMECARD(SCH_1):PAGE164',
 PACKAGE='0402',
 PHYS_PAGE='14',
 XY='(-7650,3450)',
 ROT='0',
 VER='2',
 CDS_LIB='passive',
 CDS_PART_NAME='CAPACITOR-G105-0B104-CK,0.1UF,A',
 TOLERANCE='10%',
 CLS_PN='G105-0B104-CK',
 VOLTAGE='10V',
 VALUE='0.1UF',
 PRIM_FILE='./archive_libs/passive/capacitor/chips/chips.prt';

PART_NAME
 C141 'CAPACITOR-G105-0B104-CK,0.1UF,A':;

SECTION_NUMBER 1
 '@TIMECARD_LIB.TIMECARD(SCH_1):PAGE164_I191@PASSIVE.CAPACITOR(CHIPS)':
 C_PATH='@timecard_lib.timecard(sch_1):page164_i191@passive.capacitor(chips)',
 P_PATH='@timecard_lib.timecard(sch_1):page14_i191@passive.capacitor(chips)',
 PATH='I191',
 DRAWING='@TIMECARD_LIB.TIMECARD(SCH_1):PAGE164',
 PACKAGE='0402',
 PHYS_PAGE='14',
 XY='(-7600,5700)',
 ROT='0',
 VER='2',
 CDS_LIB='passive',
 CDS_PART_NAME='CAPACITOR-G105-0B104-CK,0.1UF,A',
 TOLERANCE='10%',
 CLS_PN='G105-0B104-CK',
 VOLTAGE='10V',
 VALUE='0.1UF',
 PRIM_FILE='./archive_libs/passive/capacitor/chips/chips.prt';

PART_NAME
 C142 'CAPACITOR-G105-0B104-CK,0.1UF,A':;

SECTION_NUMBER 1
 '@TIMECARD_LIB.TIMECARD(SCH_1):PAGE164_I240@PASSIVE.CAPACITOR(CHIPS)':
 C_PATH='@timecard_lib.timecard(sch_1):page164_i240@passive.capacitor(chips)',
 P_PATH='@timecard_lib.timecard(sch_1):page14_i240@passive.capacitor(chips)',
 PATH='I240',
 DRAWING='@TIMECARD_LIB.TIMECARD(SCH_1):PAGE164',
 PACKAGE='0402',
 PHYS_PAGE='14',
 XY='(-7600,2050)',
 ROT='0',
 VER='2',
 CDS_LIB='passive',
 CDS_PART_NAME='CAPACITOR-G105-0B104-CK,0.1UF,A',
 TOLERANCE='10%',
 CLS_PN='G105-0B104-CK',
 VOLTAGE='10V',
 VALUE='0.1UF',
 PRIM_FILE='./archive_libs/passive/capacitor/chips/chips.prt';

PART_NAME
 C143 'CAPACITOR-G107-0F476-AM,47UF,2A':;

SECTION_NUMBER 1
 '@TIMECARD_LIB.TIMECARD(SCH_1):PAGE164_I265@PASSIVE.CAPACITOR(CHIPS)':
 C_PATH='@timecard_lib.timecard(sch_1):page164_i265@passive.capacitor(chips)',
 P_PATH='@timecard_lib.timecard(sch_1):page14_i265@passive.capacitor(chips)',
 PATH='I265',
 DRAWING='@TIMECARD_LIB.TIMECARD(SCH_1):PAGE164',
 PACKAGE='0805',
 PHYS_PAGE='14',
 XY='(-7550,-650)',
 ROT='0',
 VER='2',
 CDS_LIB='passive',
 CDS_PART_NAME='CAPACITOR-G107-0F476-AM,47UF,2A',
 TOLERANCE='20%',
 CLS_PN='G107-0F476-AM',
 VOLTAGE='4V',
 VALUE='47UF',
 PRIM_FILE='./archive_libs/passive/capacitor/chips/chips.prt';

PART_NAME
 C144 'CAPACITOR-G105-0B104-CK,0.1UF,A':;

SECTION_NUMBER 1
 '@TIMECARD_LIB.TIMECARD(SCH_1):PAGE164_I214@PASSIVE.CAPACITOR(CHIPS)':
 C_PATH='@timecard_lib.timecard(sch_1):page164_i214@passive.capacitor(chips)',
 P_PATH='@timecard_lib.timecard(sch_1):page14_i214@passive.capacitor(chips)',
 PATH='I214',
 DRAWING='@TIMECARD_LIB.TIMECARD(SCH_1):PAGE164',
 PACKAGE='0402',
 PHYS_PAGE='14',
 XY='(-7500,4300)',
 ROT='0',
 VER='2',
 CDS_LIB='passive',
 CDS_PART_NAME='CAPACITOR-G105-0B104-CK,0.1UF,A',
 TOLERANCE='10%',
 CLS_PN='G105-0B104-CK',
 VOLTAGE='10V',
 VALUE='0.1UF',
 PRIM_FILE='./archive_libs/passive/capacitor/chips/chips.prt';

PART_NAME
 C145 'CAPACITOR-G105-0B104-CK,0.1UF,A':;

SECTION_NUMBER 1
 '@TIMECARD_LIB.TIMECARD(SCH_1):PAGE164_I226@PASSIVE.CAPACITOR(CHIPS)':
 C_PATH='@timecard_lib.timecard(sch_1):page164_i226@passive.capacitor(chips)',
 P_PATH='@timecard_lib.timecard(sch_1):page14_i226@passive.capacitor(chips)',
 PATH='I226',
 DRAWING='@TIMECARD_LIB.TIMECARD(SCH_1):PAGE164',
 PACKAGE='0402',
 PHYS_PAGE='14',
 XY='(-7250,3450)',
 ROT='0',
 VER='2',
 CDS_LIB='passive',
 CDS_PART_NAME='CAPACITOR-G105-0B104-CK,0.1UF,A',
 TOLERANCE='10%',
 CLS_PN='G105-0B104-CK',
 VOLTAGE='10V',
 VALUE='0.1UF',
 PRIM_FILE='./archive_libs/passive/capacitor/chips/chips.prt';

PART_NAME
 C146 'CAPACITOR-G105-0B104-CK,0.1UF,A':;

SECTION_NUMBER 1
 '@TIMECARD_LIB.TIMECARD(SCH_1):PAGE164_I241@PASSIVE.CAPACITOR(CHIPS)':
 C_PATH='@timecard_lib.timecard(sch_1):page164_i241@passive.capacitor(chips)',
 P_PATH='@timecard_lib.timecard(sch_1):page14_i241@passive.capacitor(chips)',
 PATH='I241',
 DRAWING='@TIMECARD_LIB.TIMECARD(SCH_1):PAGE164',
 PACKAGE='0402',
 PHYS_PAGE='14',
 XY='(-7250,2050)',
 ROT='0',
 VER='2',
 CDS_LIB='passive',
 CDS_PART_NAME='CAPACITOR-G105-0B104-CK,0.1UF,A',
 TOLERANCE='10%',
 CLS_PN='G105-0B104-CK',
 VOLTAGE='10V',
 VALUE='0.1UF',
 PRIM_FILE='./archive_libs/passive/capacitor/chips/chips.prt';

PART_NAME
 C147 'CAPACITOR-G105-0B104-CK,0.1UF,A':;

SECTION_NUMBER 1
 '@TIMECARD_LIB.TIMECARD(SCH_1):PAGE164_I192@PASSIVE.CAPACITOR(CHIPS)':
 C_PATH='@timecard_lib.timecard(sch_1):page164_i192@passive.capacitor(chips)',
 P_PATH='@timecard_lib.timecard(sch_1):page14_i192@passive.capacitor(chips)',
 PATH='I192',
 DRAWING='@TIMECARD_LIB.TIMECARD(SCH_1):PAGE164',
 PACKAGE='0402',
 PHYS_PAGE='14',
 XY='(-7200,5700)',
 ROT='0',
 VER='2',
 CDS_LIB='passive',
 CDS_PART_NAME='CAPACITOR-G105-0B104-CK,0.1UF,A',
 TOLERANCE='10%',
 CLS_PN='G105-0B104-CK',
 VOLTAGE='10V',
 VALUE='0.1UF',
 PRIM_FILE='./archive_libs/passive/capacitor/chips/chips.prt';

PART_NAME
 C148 'CAPACITOR-G105-0B104-CK,0.1UF,A':;

SECTION_NUMBER 1
 '@TIMECARD_LIB.TIMECARD(SCH_1):PAGE164_I250@PASSIVE.CAPACITOR(CHIPS)':
 C_PATH='@timecard_lib.timecard(sch_1):page164_i250@passive.capacitor(chips)',
 P_PATH='@timecard_lib.timecard(sch_1):page14_i250@passive.capacitor(chips)',
 PATH='I250',
 DRAWING='@TIMECARD_LIB.TIMECARD(SCH_1):PAGE164',
 PACKAGE='0402',
 PHYS_PAGE='14',
 XY='(-7200,450)',
 ROT='0',
 VER='2',
 CDS_LIB='passive',
 CDS_PART_NAME='CAPACITOR-G105-0B104-CK,0.1UF,A',
 TOLERANCE='10%',
 CLS_PN='G105-0B104-CK',
 VOLTAGE='10V',
 VALUE='0.1UF',
 PRIM_FILE='./archive_libs/passive/capacitor/chips/chips.prt';

PART_NAME
 C149 'CAPACITOR-G105-0B104-CK,0.1UF,A':;

SECTION_NUMBER 1
 '@TIMECARD_LIB.TIMECARD(SCH_1):PAGE164_I215@PASSIVE.CAPACITOR(CHIPS)':
 C_PATH='@timecard_lib.timecard(sch_1):page164_i215@passive.capacitor(chips)',
 P_PATH='@timecard_lib.timecard(sch_1):page14_i215@passive.capacitor(chips)',
 PATH='I215',
 DRAWING='@TIMECARD_LIB.TIMECARD(SCH_1):PAGE164',
 PACKAGE='0402',
 PHYS_PAGE='14',
 XY='(-7150,4300)',
 ROT='0',
 VER='2',
 CDS_LIB='passive',
 CDS_PART_NAME='CAPACITOR-G105-0B104-CK,0.1UF,A',
 TOLERANCE='10%',
 CLS_PN='G105-0B104-CK',
 VOLTAGE='10V',
 VALUE='0.1UF',
 PRIM_FILE='./archive_libs/passive/capacitor/chips/chips.prt';

PART_NAME
 C150 'CAPACITOR-G105-0B104-CK,0.1UF,A':;

SECTION_NUMBER 1
 '@TIMECARD_LIB.TIMECARD(SCH_1):PAGE164_I276@PASSIVE.CAPACITOR(CHIPS)':
 C_PATH='@timecard_lib.timecard(sch_1):page164_i276@passive.capacitor(chips)',
 P_PATH='@timecard_lib.timecard(sch_1):page14_i276@passive.capacitor(chips)',
 PATH='I276',
 DRAWING='@TIMECARD_LIB.TIMECARD(SCH_1):PAGE164',
 PACKAGE='0402',
 PHYS_PAGE='14',
 XY='(-6900,7150)',
 ROT='0',
 VER='2',
 CDS_LIB='passive',
 CDS_PART_NAME='CAPACITOR-G105-0B104-CK,0.1UF,A',
 TOLERANCE='10%',
 CLS_PN='G105-0B104-CK',
 VOLTAGE='10V',
 VALUE='0.1UF',
 PRIM_FILE='./archive_libs/passive/capacitor/chips/chips.prt';

PART_NAME
 C151 'CAPACITOR-G105-0B104-CK,0.1UF,A':;

SECTION_NUMBER 1
 '@TIMECARD_LIB.TIMECARD(SCH_1):PAGE164_I242@PASSIVE.CAPACITOR(CHIPS)':
 C_PATH='@timecard_lib.timecard(sch_1):page164_i242@passive.capacitor(chips)',
 P_PATH='@timecard_lib.timecard(sch_1):page14_i242@passive.capacitor(chips)',
 PATH='I242',
 DRAWING='@TIMECARD_LIB.TIMECARD(SCH_1):PAGE164',
 PACKAGE='0402',
 PHYS_PAGE='14',
 XY='(-6900,2050)',
 ROT='0',
 VER='2',
 CDS_LIB='passive',
 CDS_PART_NAME='CAPACITOR-G105-0B104-CK,0.1UF,A',
 TOLERANCE='10%',
 CLS_PN='G105-0B104-CK',
 VOLTAGE='10V',
 VALUE='0.1UF',
 PRIM_FILE='./archive_libs/passive/capacitor/chips/chips.prt';

PART_NAME
 C152 'CAPACITOR-G105-0B104-CK,0.1UF,A':;

SECTION_NUMBER 1
 '@TIMECARD_LIB.TIMECARD(SCH_1):PAGE164_I193@PASSIVE.CAPACITOR(CHIPS)':
 C_PATH='@timecard_lib.timecard(sch_1):page164_i193@passive.capacitor(chips)',
 P_PATH='@timecard_lib.timecard(sch_1):page14_i193@passive.capacitor(chips)',
 PATH='I193',
 DRAWING='@TIMECARD_LIB.TIMECARD(SCH_1):PAGE164',
 PACKAGE='0402',
 PHYS_PAGE='14',
 XY='(-6850,5700)',
 ROT='0',
 VER='2',
 CDS_LIB='passive',
 CDS_PART_NAME='CAPACITOR-G105-0B104-CK,0.1UF,A',
 TOLERANCE='10%',
 CLS_PN='G105-0B104-CK',
 VOLTAGE='10V',
 VALUE='0.1UF',
 PRIM_FILE='./archive_libs/passive/capacitor/chips/chips.prt';

PART_NAME
 C153 'CAPACITOR-G105-0B104-CK,0.1UF,A':;

SECTION_NUMBER 1
 '@TIMECARD_LIB.TIMECARD(SCH_1):PAGE164_I227@PASSIVE.CAPACITOR(CHIPS)':
 C_PATH='@timecard_lib.timecard(sch_1):page164_i227@passive.capacitor(chips)',
 P_PATH='@timecard_lib.timecard(sch_1):page14_i227@passive.capacitor(chips)',
 PATH='I227',
 DRAWING='@TIMECARD_LIB.TIMECARD(SCH_1):PAGE164',
 PACKAGE='0402',
 PHYS_PAGE='14',
 XY='(-6850,3450)',
 ROT='0',
 VER='2',
 CDS_LIB='passive',
 CDS_PART_NAME='CAPACITOR-G105-0B104-CK,0.1UF,A',
 TOLERANCE='10%',
 CLS_PN='G105-0B104-CK',
 VOLTAGE='10V',
 VALUE='0.1UF',
 PRIM_FILE='./archive_libs/passive/capacitor/chips/chips.prt';

PART_NAME
 C154 'CAPACITOR-G105-0F475-BM,4.7UF,A':;

SECTION_NUMBER 1
 '@TIMECARD_LIB.TIMECARD(SCH_1):PAGE164_I270@PASSIVE.CAPACITOR(CHIPS)':
 C_PATH='@timecard_lib.timecard(sch_1):page164_i270@passive.capacitor(chips)',
 P_PATH='@timecard_lib.timecard(sch_1):page14_i270@passive.capacitor(chips)',
 PATH='I270',
 DRAWING='@TIMECARD_LIB.TIMECARD(SCH_1):PAGE164',
 PACKAGE='0402',
 PHYS_PAGE='14',
 XY='(-6750,4300)',
 ROT='0',
 VER='2',
 CDS_LIB='passive',
 CDS_PART_NAME='CAPACITOR-G105-0F475-BM,4.7UF,A',
 TOLERANCE='20%',
 CLS_PN='G105-0F475-BM',
 VOLTAGE='6.3V',
 VALUE='4.7UF',
 PRIM_FILE='./archive_libs/passive/capacitor/chips/chips.prt';

PART_NAME
 C155 'CAPACITOR-G107-0F476-AM,47UF,2A':;

SECTION_NUMBER 1
 '@TIMECARD_LIB.TIMECARD(SCH_1):PAGE164_I266@PASSIVE.CAPACITOR(CHIPS)':
 C_PATH='@timecard_lib.timecard(sch_1):page164_i266@passive.capacitor(chips)',
 P_PATH='@timecard_lib.timecard(sch_1):page14_i266@passive.capacitor(chips)',
 PATH='I266',
 DRAWING='@TIMECARD_LIB.TIMECARD(SCH_1):PAGE164',
 PACKAGE='0805',
 PHYS_PAGE='14',
 XY='(-6750,450)',
 ROT='0',
 VER='2',
 CDS_LIB='passive',
 CDS_PART_NAME='CAPACITOR-G107-0F476-AM,47UF,2A',
 TOLERANCE='20%',
 CLS_PN='G107-0F476-AM',
 VOLTAGE='4V',
 VALUE='47UF',
 PRIM_FILE='./archive_libs/passive/capacitor/chips/chips.prt';

PART_NAME
 C156 'CAPACITOR-G105-0B104-CK,0.1UF,A':;

SECTION_NUMBER 1
 '@TIMECARD_LIB.TIMECARD(SCH_1):PAGE164_I194@PASSIVE.CAPACITOR(CHIPS)':
 C_PATH='@timecard_lib.timecard(sch_1):page164_i194@passive.capacitor(chips)',
 P_PATH='@timecard_lib.timecard(sch_1):page14_i194@passive.capacitor(chips)',
 PATH='I194',
 DRAWING='@TIMECARD_LIB.TIMECARD(SCH_1):PAGE164',
 PACKAGE='0402',
 PHYS_PAGE='14',
 XY='(-6500,5700)',
 ROT='0',
 VER='2',
 CDS_LIB='passive',
 CDS_PART_NAME='CAPACITOR-G105-0B104-CK,0.1UF,A',
 TOLERANCE='10%',
 CLS_PN='G105-0B104-CK',
 VOLTAGE='10V',
 VALUE='0.1UF',
 PRIM_FILE='./archive_libs/passive/capacitor/chips/chips.prt';

PART_NAME
 C157 'CAPACITOR-G105-0B104-CK,0.1UF,A':;

SECTION_NUMBER 1
 '@TIMECARD_LIB.TIMECARD(SCH_1):PAGE164_I228@PASSIVE.CAPACITOR(CHIPS)':
 C_PATH='@timecard_lib.timecard(sch_1):page164_i228@passive.capacitor(chips)',
 P_PATH='@timecard_lib.timecard(sch_1):page14_i228@passive.capacitor(chips)',
 PATH='I228',
 DRAWING='@TIMECARD_LIB.TIMECARD(SCH_1):PAGE164',
 PACKAGE='0402',
 PHYS_PAGE='14',
 XY='(-6500,3450)',
 ROT='0',
 VER='2',
 CDS_LIB='passive',
 CDS_PART_NAME='CAPACITOR-G105-0B104-CK,0.1UF,A',
 TOLERANCE='10%',
 CLS_PN='G105-0B104-CK',
 VOLTAGE='10V',
 VALUE='0.1UF',
 PRIM_FILE='./archive_libs/passive/capacitor/chips/chips.prt';

PART_NAME
 C158 'CAPACITOR-G107-0F226-CM,22UF,2A':;

SECTION_NUMBER 1
 '@TIMECARD_LIB.TIMECARD(SCH_1):PAGE164_I176@PASSIVE.CAPACITOR(CHIPS)':
 C_PATH='@timecard_lib.timecard(sch_1):page164_i176@passive.capacitor(chips)',
 P_PATH='@timecard_lib.timecard(sch_1):page14_i176@passive.capacitor(chips)',
 PATH='I176',
 DRAWING='@TIMECARD_LIB.TIMECARD(SCH_1):PAGE164',
 PACKAGE='0805',
 PHYS_PAGE='14',
 XY='(-6400,7150)',
 ROT='0',
 VER='2',
 CDS_LIB='passive',
 CDS_PART_NAME='CAPACITOR-G107-0F226-CM,22UF,2A',
 TOLERANCE='20%',
 CLS_PN='G107-0F226-CM',
 VOLTAGE='10V',
 VALUE='22UF',
 PRIM_FILE='./archive_libs/passive/capacitor/chips/chips.prt';

PART_NAME
 C159 'CAPACITOR-G105-0F475-BM,4.7UF,A':;

SECTION_NUMBER 1
 '@TIMECARD_LIB.TIMECARD(SCH_1):PAGE164_I271@PASSIVE.CAPACITOR(CHIPS)':
 C_PATH='@timecard_lib.timecard(sch_1):page164_i271@passive.capacitor(chips)',
 P_PATH='@timecard_lib.timecard(sch_1):page14_i271@passive.capacitor(chips)',
 PATH='I271',
 DRAWING='@TIMECARD_LIB.TIMECARD(SCH_1):PAGE164',
 PACKAGE='0402',
 PHYS_PAGE='14',
 XY='(-6400,4300)',
 ROT='0',
 VER='2',
 CDS_LIB='passive',
 CDS_PART_NAME='CAPACITOR-G105-0F475-BM,4.7UF,A',
 TOLERANCE='20%',
 CLS_PN='G105-0F475-BM',
 VOLTAGE='6.3V',
 VALUE='4.7UF',
 PRIM_FILE='./archive_libs/passive/capacitor/chips/chips.prt';

PART_NAME
 C160 'CAPACITOR-G105-0F475-BM,4.7UF,A':;

SECTION_NUMBER 1
 '@TIMECARD_LIB.TIMECARD(SCH_1):PAGE164_I245@PASSIVE.CAPACITOR(CHIPS)':
 C_PATH='@timecard_lib.timecard(sch_1):page164_i245@passive.capacitor(chips)',
 P_PATH='@timecard_lib.timecard(sch_1):page14_i245@passive.capacitor(chips)',
 PATH='I245',
 DRAWING='@TIMECARD_LIB.TIMECARD(SCH_1):PAGE164',
 PACKAGE='0402',
 PHYS_PAGE='14',
 XY='(-6450,2050)',
 ROT='0',
 VER='2',
 CDS_LIB='passive',
 CDS_PART_NAME='CAPACITOR-G105-0F475-BM,4.7UF,A',
 TOLERANCE='20%',
 CLS_PN='G105-0F475-BM',
 VOLTAGE='6.3V',
 VALUE='4.7UF',
 PRIM_FILE='./archive_libs/passive/capacitor/chips/chips.prt';

PART_NAME
 C161 'CAPACITOR-G105-0B104-CK,0.1UF,A':;

SECTION_NUMBER 1
 '@TIMECARD_LIB.TIMECARD(SCH_1):PAGE164_I195@PASSIVE.CAPACITOR(CHIPS)':
 C_PATH='@timecard_lib.timecard(sch_1):page164_i195@passive.capacitor(chips)',
 P_PATH='@timecard_lib.timecard(sch_1):page14_i195@passive.capacitor(chips)',
 PATH='I195',
 DRAWING='@TIMECARD_LIB.TIMECARD(SCH_1):PAGE164',
 PACKAGE='0402',
 PHYS_PAGE='14',
 XY='(-6150,5700)',
 ROT='0',
 VER='2',
 CDS_LIB='passive',
 CDS_PART_NAME='CAPACITOR-G105-0B104-CK,0.1UF,A',
 TOLERANCE='10%',
 CLS_PN='G105-0B104-CK',
 VOLTAGE='10V',
 VALUE='0.1UF',
 PRIM_FILE='./archive_libs/passive/capacitor/chips/chips.prt';

PART_NAME
 C162 'CAPACITOR-G105-0B104-CK,0.1UF,A':;

SECTION_NUMBER 1
 '@TIMECARD_LIB.TIMECARD(SCH_1):PAGE164_I229@PASSIVE.CAPACITOR(CHIPS)':
 C_PATH='@timecard_lib.timecard(sch_1):page164_i229@passive.capacitor(chips)',
 P_PATH='@timecard_lib.timecard(sch_1):page14_i229@passive.capacitor(chips)',
 PATH='I229',
 DRAWING='@TIMECARD_LIB.TIMECARD(SCH_1):PAGE164',
 PACKAGE='0402',
 PHYS_PAGE='14',
 XY='(-6150,3450)',
 ROT='0',
 VER='2',
 CDS_LIB='passive',
 CDS_PART_NAME='CAPACITOR-G105-0B104-CK,0.1UF,A',
 TOLERANCE='10%',
 CLS_PN='G105-0B104-CK',
 VOLTAGE='10V',
 VALUE='0.1UF',
 PRIM_FILE='./archive_libs/passive/capacitor/chips/chips.prt';

PART_NAME
 C163 'CAPACITOR-G105-0F475-BM,4.7UF,A':;

SECTION_NUMBER 1
 '@TIMECARD_LIB.TIMECARD(SCH_1):PAGE164_I272@PASSIVE.CAPACITOR(CHIPS)':
 C_PATH='@timecard_lib.timecard(sch_1):page164_i272@passive.capacitor(chips)',
 P_PATH='@timecard_lib.timecard(sch_1):page14_i272@passive.capacitor(chips)',
 PATH='I272',
 DRAWING='@TIMECARD_LIB.TIMECARD(SCH_1):PAGE164',
 PACKAGE='0402',
 PHYS_PAGE='14',
 XY='(-6050,4300)',
 ROT='0',
 VER='2',
 CDS_LIB='passive',
 CDS_PART_NAME='CAPACITOR-G105-0F475-BM,4.7UF,A',
 TOLERANCE='20%',
 CLS_PN='G105-0F475-BM',
 VOLTAGE='6.3V',
 VALUE='4.7UF',
 PRIM_FILE='./archive_libs/passive/capacitor/chips/chips.prt';

PART_NAME
 C164 'CAPACITOR-G107-0F226-CM,22UF,2A':;

SECTION_NUMBER 1
 '@TIMECARD_LIB.TIMECARD(SCH_1):PAGE164_I268@PASSIVE.CAPACITOR(CHIPS)':
 C_PATH='@timecard_lib.timecard(sch_1):page164_i268@passive.capacitor(chips)',
 P_PATH='@timecard_lib.timecard(sch_1):page14_i268@passive.capacitor(chips)',
 PATH='I268',
 DRAWING='@TIMECARD_LIB.TIMECARD(SCH_1):PAGE164',
 PACKAGE='0805',
 PHYS_PAGE='14',
 XY='(-5700,2050)',
 ROT='0',
 VER='2',
 CDS_LIB='passive',
 CDS_PART_NAME='CAPACITOR-G107-0F226-CM,22UF,2A',
 TOLERANCE='20%',
 CLS_PN='G107-0F226-CM',
 VOLTAGE='10V',
 VALUE='22UF',
 PRIM_FILE='./archive_libs/passive/capacitor/chips/chips.prt';

PART_NAME
 C165 'CAPACITOR-G105-0B104-CK,0.1UF,A':;

SECTION_NUMBER 1
 '@TIMECARD_LIB.TIMECARD(SCH_1):PAGE164_I230@PASSIVE.CAPACITOR(CHIPS)':
 C_PATH='@timecard_lib.timecard(sch_1):page164_i230@passive.capacitor(chips)',
 P_PATH='@timecard_lib.timecard(sch_1):page14_i230@passive.capacitor(chips)',
 PATH='I230',
 DRAWING='@TIMECARD_LIB.TIMECARD(SCH_1):PAGE164',
 PACKAGE='0402',
 PHYS_PAGE='14',
 XY='(-5800,3450)',
 ROT='0',
 VER='2',
 CDS_LIB='passive',
 CDS_PART_NAME='CAPACITOR-G105-0B104-CK,0.1UF,A',
 TOLERANCE='10%',
 CLS_PN='G105-0B104-CK',
 VOLTAGE='10V',
 VALUE='0.1UF',
 PRIM_FILE='./archive_libs/passive/capacitor/chips/chips.prt';

PART_NAME
 C166 'CAPACITOR-G105-0B104-CK,0.1UF,A':;

SECTION_NUMBER 1
 '@TIMECARD_LIB.TIMECARD(SCH_1):PAGE164_I196@PASSIVE.CAPACITOR(CHIPS)':
 C_PATH='@timecard_lib.timecard(sch_1):page164_i196@passive.capacitor(chips)',
 P_PATH='@timecard_lib.timecard(sch_1):page14_i196@passive.capacitor(chips)',
 PATH='I196',
 DRAWING='@TIMECARD_LIB.TIMECARD(SCH_1):PAGE164',
 PACKAGE='0402',
 PHYS_PAGE='14',
 XY='(-5750,5700)',
 ROT='0',
 VER='2',
 CDS_LIB='passive',
 CDS_PART_NAME='CAPACITOR-G105-0B104-CK,0.1UF,A',
 TOLERANCE='10%',
 CLS_PN='G105-0B104-CK',
 VOLTAGE='10V',
 VALUE='0.1UF',
 PRIM_FILE='./archive_libs/passive/capacitor/chips/chips.prt';

PART_NAME
 C167 'CAPACITOR-G105-0F475-BM,4.7UF,A':;

SECTION_NUMBER 1
 '@TIMECARD_LIB.TIMECARD(SCH_1):PAGE164_I273@PASSIVE.CAPACITOR(CHIPS)':
 C_PATH='@timecard_lib.timecard(sch_1):page164_i273@passive.capacitor(chips)',
 P_PATH='@timecard_lib.timecard(sch_1):page14_i273@passive.capacitor(chips)',
 PATH='I273',
 DRAWING='@TIMECARD_LIB.TIMECARD(SCH_1):PAGE164',
 PACKAGE='0402',
 PHYS_PAGE='14',
 XY='(-5700,4300)',
 ROT='0',
 VER='2',
 CDS_LIB='passive',
 CDS_PART_NAME='CAPACITOR-G105-0F475-BM,4.7UF,A',
 TOLERANCE='20%',
 CLS_PN='G105-0F475-BM',
 VOLTAGE='6.3V',
 VALUE='4.7UF',
 PRIM_FILE='./archive_libs/passive/capacitor/chips/chips.prt';

PART_NAME
 C168 'CAPACITOR-G107-0F226-CM,22UF,2A':;

SECTION_NUMBER 1
 '@TIMECARD_LIB.TIMECARD(SCH_1):PAGE164_I267@PASSIVE.CAPACITOR(CHIPS)':
 C_PATH='@timecard_lib.timecard(sch_1):page164_i267@passive.capacitor(chips)',
 P_PATH='@timecard_lib.timecard(sch_1):page14_i267@passive.capacitor(chips)',
 PATH='I267',
 DRAWING='@TIMECARD_LIB.TIMECARD(SCH_1):PAGE164',
 PACKAGE='0805',
 PHYS_PAGE='14',
 XY='(-5350,2050)',
 ROT='0',
 VER='2',
 CDS_LIB='passive',
 CDS_PART_NAME='CAPACITOR-G107-0F226-CM,22UF,2A',
 TOLERANCE='20%',
 CLS_PN='G107-0F226-CM',
 VOLTAGE='10V',
 VALUE='22UF',
 PRIM_FILE='./archive_libs/passive/capacitor/chips/chips.prt';

PART_NAME
 C169 'CAPACITOR-G105-0B104-CK,0.1UF,A':;

SECTION_NUMBER 1
 '@TIMECARD_LIB.TIMECARD(SCH_1):PAGE164_I197@PASSIVE.CAPACITOR(CHIPS)':
 C_PATH='@timecard_lib.timecard(sch_1):page164_i197@passive.capacitor(chips)',
 P_PATH='@timecard_lib.timecard(sch_1):page14_i197@passive.capacitor(chips)',
 PATH='I197',
 DRAWING='@TIMECARD_LIB.TIMECARD(SCH_1):PAGE164',
 PACKAGE='0402',
 PHYS_PAGE='14',
 XY='(-5400,5700)',
 ROT='0',
 VER='2',
 CDS_LIB='passive',
 CDS_PART_NAME='CAPACITOR-G105-0B104-CK,0.1UF,A',
 TOLERANCE='10%',
 CLS_PN='G105-0B104-CK',
 VOLTAGE='10V',
 VALUE='0.1UF',
 PRIM_FILE='./archive_libs/passive/capacitor/chips/chips.prt';

PART_NAME
 C170 'CAPACITOR-G105-0F475-BM,4.7UF,A':;

SECTION_NUMBER 1
 '@TIMECARD_LIB.TIMECARD(SCH_1):PAGE164_I282@PASSIVE.CAPACITOR(CHIPS)':
 C_PATH='@timecard_lib.timecard(sch_1):page164_i282@passive.capacitor(chips)',
 P_PATH='@timecard_lib.timecard(sch_1):page14_i282@passive.capacitor(chips)',
 PATH='I282',
 DRAWING='@TIMECARD_LIB.TIMECARD(SCH_1):PAGE164',
 PACKAGE='0402',
 PHYS_PAGE='14',
 XY='(-5350,4300)',
 ROT='0',
 VER='2',
 CDS_LIB='passive',
 CDS_PART_NAME='CAPACITOR-G105-0F475-BM,4.7UF,A',
 TOLERANCE='20%',
 CLS_PN='G105-0F475-BM',
 VOLTAGE='6.3V',
 VALUE='4.7UF',
 PRIM_FILE='./archive_libs/passive/capacitor/chips/chips.prt';

PART_NAME
 C171 'CAPACITOR-G105-0B104-CK,0.1UF,A':;

SECTION_NUMBER 1
 '@TIMECARD_LIB.TIMECARD(SCH_1):PAGE164_I198@PASSIVE.CAPACITOR(CHIPS)':
 C_PATH='@timecard_lib.timecard(sch_1):page164_i198@passive.capacitor(chips)',
 P_PATH='@timecard_lib.timecard(sch_1):page14_i198@passive.capacitor(chips)',
 PATH='I198',
 DRAWING='@TIMECARD_LIB.TIMECARD(SCH_1):PAGE164',
 PACKAGE='0402',
 PHYS_PAGE='14',
 XY='(-5000,5700)',
 ROT='0',
 VER='2',
 CDS_LIB='passive',
 CDS_PART_NAME='CAPACITOR-G105-0B104-CK,0.1UF,A',
 TOLERANCE='10%',
 CLS_PN='G105-0B104-CK',
 VOLTAGE='10V',
 VALUE='0.1UF',
 PRIM_FILE='./archive_libs/passive/capacitor/chips/chips.prt';

PART_NAME
 C172 'CAPACITOR-G109-0G107-BM,100UF,A':;

SECTION_NUMBER 1
 '@TIMECARD_LIB.TIMECARD(SCH_1):PAGE164_I174@PASSIVE.CAPACITOR(CHIPS)':
 C_PATH='@timecard_lib.timecard(sch_1):page164_i174@passive.capacitor(chips)',
 P_PATH='@timecard_lib.timecard(sch_1):page14_i174@passive.capacitor(chips)',
 PATH='I174',
 DRAWING='@TIMECARD_LIB.TIMECARD(SCH_1):PAGE164',
 PACKAGE='1210',
 PHYS_PAGE='14',
 XY='(-5000,4300)',
 ROT='0',
 VER='2',
 CDS_LIB='passive',
 CDS_PART_NAME='CAPACITOR-G109-0G107-BM,100UF,A',
 TOLERANCE='20%',
 CLS_PN='G109-0G107-BM',
 VOLTAGE='6.3V',
 VALUE='100UF',
 PRIM_FILE='./archive_libs/passive/capacitor/chips/chips.prt';

PART_NAME
 C173 'CAPACITOR-G107-0F476-AM,47UF,2A':;

SECTION_NUMBER 1
 '@TIMECARD_LIB.TIMECARD(SCH_1):PAGE164_I280@PASSIVE.CAPACITOR(CHIPS)':
 C_PATH='@timecard_lib.timecard(sch_1):page164_i280@passive.capacitor(chips)',
 P_PATH='@timecard_lib.timecard(sch_1):page14_i280@passive.capacitor(chips)',
 PATH='I280',
 DRAWING='@TIMECARD_LIB.TIMECARD(SCH_1):PAGE164',
 PACKAGE='0805',
 PHYS_PAGE='14',
 XY='(-4650,5700)',
 ROT='0',
 VER='2',
 CDS_LIB='passive',
 CDS_PART_NAME='CAPACITOR-G107-0F476-AM,47UF,2A',
 TOLERANCE='20%',
 CLS_PN='G107-0F476-AM',
 VOLTAGE='4V',
 VALUE='47UF',
 PRIM_FILE='./archive_libs/passive/capacitor/chips/chips.prt';

PART_NAME
 C174 'CAPACITOR-G109-0G107-BM,100UF,A':;

SECTION_NUMBER 1
 '@TIMECARD_LIB.TIMECARD(SCH_1):PAGE164_I178@PASSIVE.CAPACITOR(CHIPS)':
 C_PATH='@timecard_lib.timecard(sch_1):page164_i178@passive.capacitor(chips)',
 P_PATH='@timecard_lib.timecard(sch_1):page14_i178@passive.capacitor(chips)',
 PATH='I178',
 DRAWING='@TIMECARD_LIB.TIMECARD(SCH_1):PAGE164',
 PACKAGE='1210',
 PHYS_PAGE='14',
 XY='(-4600,4300)',
 ROT='0',
 VER='2',
 CDS_LIB='passive',
 CDS_PART_NAME='CAPACITOR-G109-0G107-BM,100UF,A',
 TOLERANCE='20%',
 CLS_PN='G109-0G107-BM',
 VOLTAGE='6.3V',
 VALUE='100UF',
 PRIM_FILE='./archive_libs/passive/capacitor/chips/chips.prt';

PART_NAME
 C175 'CAPACITOR-G109-0G107-BM,100UF,A':;

SECTION_NUMBER 1
 '@TIMECARD_LIB.TIMECARD(SCH_1):PAGE164_I173@PASSIVE.CAPACITOR(CHIPS)':
 C_PATH='@timecard_lib.timecard(sch_1):page164_i173@passive.capacitor(chips)',
 P_PATH='@timecard_lib.timecard(sch_1):page14_i173@passive.capacitor(chips)',
 PATH='I173',
 DRAWING='@TIMECARD_LIB.TIMECARD(SCH_1):PAGE164',
 PACKAGE='1210',
 PHYS_PAGE='14',
 XY='(-4300,5700)',
 ROT='0',
 VER='2',
 CDS_LIB='passive',
 CDS_PART_NAME='CAPACITOR-G109-0G107-BM,100UF,A',
 TOLERANCE='20%',
 CLS_PN='G109-0G107-BM',
 VOLTAGE='6.3V',
 VALUE='100UF',
 PRIM_FILE='./archive_libs/passive/capacitor/chips/chips.prt';

PART_NAME
 C176 'CAPACITOR-G109-0G107-BM,100UF,A':;

SECTION_NUMBER 1
 '@TIMECARD_LIB.TIMECARD(SCH_1):PAGE164_I172@PASSIVE.CAPACITOR(CHIPS)':
 C_PATH='@timecard_lib.timecard(sch_1):page164_i172@passive.capacitor(chips)',
 P_PATH='@timecard_lib.timecard(sch_1):page14_i172@passive.capacitor(chips)',
 PATH='I172',
 DRAWING='@TIMECARD_LIB.TIMECARD(SCH_1):PAGE164',
 PACKAGE='1210',
 PHYS_PAGE='14',
 XY='(-3950,5700)',
 ROT='0',
 VER='2',
 CDS_LIB='passive',
 CDS_PART_NAME='CAPACITOR-G109-0G107-BM,100UF,A',
 TOLERANCE='20%',
 CLS_PN='G109-0G107-BM',
 VOLTAGE='6.3V',
 VALUE='100UF',
 PRIM_FILE='./archive_libs/passive/capacitor/chips/chips.prt';

PART_NAME
 C177 'CAPACITOR-G109-0G107-BM,100UF,A':;

SECTION_NUMBER 1
 '@TIMECARD_LIB.TIMECARD(SCH_1):PAGE164_I277@PASSIVE.CAPACITOR(CHIPS)':
 C_PATH='@timecard_lib.timecard(sch_1):page164_i277@passive.capacitor(chips)',
 P_PATH='@timecard_lib.timecard(sch_1):page14_i277@passive.capacitor(chips)',
 PATH='I277',
 DRAWING='@TIMECARD_LIB.TIMECARD(SCH_1):PAGE164',
 PACKAGE='1210',
 PHYS_PAGE='14',
 XY='(-3600,5700)',
 ROT='0',
 VER='2',
 CDS_LIB='passive',
 CDS_PART_NAME='CAPACITOR-G109-0G107-BM,100UF,A',
 TOLERANCE='20%',
 CLS_PN='G109-0G107-BM',
 VOLTAGE='6.3V',
 VALUE='100UF',
 PRIM_FILE='./archive_libs/passive/capacitor/chips/chips.prt';

PART_NAME
 C178 'CAPACITOR-G105-0B104-CK,0.1UF,A':;

SECTION_NUMBER 1
 '@TIMECARD_LIB.TIMECARD(SCH_1):PAGE164_I283@PASSIVE.CAPACITOR(CHIPS)':
 C_PATH='@timecard_lib.timecard(sch_1):page164_i283@passive.capacitor(chips)',
 P_PATH='@timecard_lib.timecard(sch_1):page14_i283@passive.capacitor(chips)',
 PATH='I283',
 DRAWING='@TIMECARD_LIB.TIMECARD(SCH_1):PAGE164',
 PACKAGE='0402',
 PHYS_PAGE='14',
 XY='(-2950,5700)',
 ROT='0',
 VER='2',
 CDS_LIB='passive',
 CDS_PART_NAME='CAPACITOR-G105-0B104-CK,0.1UF,A',
 TOLERANCE='10%',
 CLS_PN='G105-0B104-CK',
 VOLTAGE='10V',
 VALUE='0.1UF',
 PRIM_FILE='./archive_libs/passive/capacitor/chips/chips.prt';

PART_NAME
 C179 'CAPACITOR-G107-0F476-AM,47UF,2A':;

SECTION_NUMBER 1
 '@TIMECARD_LIB.TIMECARD(SCH_1):PAGE164_I274@PASSIVE.CAPACITOR(CHIPS)':
 C_PATH='@timecard_lib.timecard(sch_1):page164_i274@passive.capacitor(chips)',
 P_PATH='@timecard_lib.timecard(sch_1):page14_i274@passive.capacitor(chips)',
 PATH='I274',
 DRAWING='@TIMECARD_LIB.TIMECARD(SCH_1):PAGE164',
 PACKAGE='0805',
 PHYS_PAGE='14',
 XY='(-2400,5700)',
 ROT='0',
 VER='2',
 CDS_LIB='passive',
 CDS_PART_NAME='CAPACITOR-G107-0F476-AM,47UF,2A',
 TOLERANCE='20%',
 CLS_PN='G107-0F476-AM',
 VOLTAGE='4V',
 VALUE='47UF',
 PRIM_FILE='./archive_libs/passive/capacitor/chips/chips.prt';

PART_NAME
 C180 'CAPACITOR-G107-0F226-CM,22UF,2A':;

SECTION_NUMBER 1
 '@TIMECARD_LIB.TIMECARD(SCH_1):PAGE68_I93@PASSIVE.CAPACITOR(CHIPS)':
 C_PATH='@timecard_lib.timecard(sch_1):page68_i93@passive.capacitor(chips)',
 P_PATH='@timecard_lib.timecard(sch_1):page30_i93@passive.capacitor(chips)',
 PATH='I93',
 DRAWING='@TIMECARD_LIB.TIMECARD(SCH_1):PAGE68',
 PACKAGE='0805',
 PHYS_PAGE='30',
 XY='(-13200,8450)',
 ROT='0',
 VER='2',
 CDS_LIB='passive',
 CDS_PART_NAME='CAPACITOR-G107-0F226-CM,22UF,2A',
 TOLERANCE='20%',
 CLS_PN='G107-0F226-CM',
 VOLTAGE='10V',
 VALUE='22UF',
 PRIM_FILE='./archive_libs/passive/capacitor/chips/chips.prt';

PART_NAME
 C181 'CAPACITOR-G107-0F226-CM,22UF,2A':;

SECTION_NUMBER 1
 '@TIMECARD_LIB.TIMECARD(SCH_1):PAGE68_I97@PASSIVE.CAPACITOR(CHIPS)':
 C_PATH='@timecard_lib.timecard(sch_1):page68_i97@passive.capacitor(chips)',
 P_PATH='@timecard_lib.timecard(sch_1):page30_i97@passive.capacitor(chips)',
 PATH='I97',
 DRAWING='@TIMECARD_LIB.TIMECARD(SCH_1):PAGE68',
 PACKAGE='0805',
 PHYS_PAGE='30',
 XY='(-13100,3550)',
 ROT='0',
 VER='2',
 CDS_LIB='passive',
 CDS_PART_NAME='CAPACITOR-G107-0F226-CM,22UF,2A',
 TOLERANCE='20%',
 CLS_PN='G107-0F226-CM',
 VOLTAGE='10V',
 VALUE='22UF',
 PRIM_FILE='./archive_libs/passive/capacitor/chips/chips.prt';

PART_NAME
 C182 'CAPACITOR-G105-0B104-EK,0.1UF,A':;

SECTION_NUMBER 1
 '@TIMECARD_LIB.TIMECARD(SCH_1):PAGE68_I94@PASSIVE.CAPACITOR(CHIPS)':
 C_PATH='@timecard_lib.timecard(sch_1):page68_i94@passive.capacitor(chips)',
 P_PATH='@timecard_lib.timecard(sch_1):page30_i94@passive.capacitor(chips)',
 PATH='I94',
 DRAWING='@TIMECARD_LIB.TIMECARD(SCH_1):PAGE68',
 PACKAGE='0402',
 PHYS_PAGE='30',
 XY='(-12750,8450)',
 ROT='0',
 VER='2',
 CDS_LIB='passive',
 CDS_PART_NAME='CAPACITOR-G105-0B104-EK,0.1UF,A',
 TOLERANCE='10%',
 CLS_PN='G105-0B104-EK',
 VOLTAGE='25V',
 VALUE='0.1UF',
 PRIM_FILE='./archive_libs/passive/capacitor/chips/chips.prt';

PART_NAME
 C183 'CAPACITOR-G105-0B104-EK,0.1UF,A':;

SECTION_NUMBER 1
 '@TIMECARD_LIB.TIMECARD(SCH_1):PAGE68_I98@PASSIVE.CAPACITOR(CHIPS)':
 C_PATH='@timecard_lib.timecard(sch_1):page68_i98@passive.capacitor(chips)',
 P_PATH='@timecard_lib.timecard(sch_1):page30_i98@passive.capacitor(chips)',
 PATH='I98',
 DRAWING='@TIMECARD_LIB.TIMECARD(SCH_1):PAGE68',
 MATERIAL='X7R',
 PACKAGE='0402',
 PHYS_PAGE='30',
 XY='(-12650,3550)',
 ROT='0',
 VER='2',
 CDS_LIB='passive',
 CDS_PART_NAME='CAPACITOR-G105-0B104-EK,0.1UF,A',
 TOLERANCE='10%',
 CLS_PN='G105-0B104-EK',
 VOLTAGE='25V',
 VALUE='0.1UF',
 PRIM_FILE='./archive_libs/passive/capacitor/chips/chips.prt';

PART_NAME
 C184 'CAPACITOR-G105-0B104-EK,0.1UF,A':;

SECTION_NUMBER 1
 '@TIMECARD_LIB.TIMECARD(SCH_1):PAGE68_I3@PASSIVE.CAPACITOR(CHIPS)':
 C_PATH='@timecard_lib.timecard(sch_1):page68_i3@passive.capacitor(chips)',
 P_PATH='@timecard_lib.timecard(sch_1):page30_i3@passive.capacitor(chips)',
 PATH='I3',
 DRAWING='@TIMECARD_LIB.TIMECARD(SCH_1):PAGE68',
 PACKAGE='0402',
 PHYS_PAGE='30',
 XY='(-11300,7500)',
 ROT='0',
 VER='2',
 CDS_LIB='passive',
 CDS_PART_NAME='CAPACITOR-G105-0B104-EK,0.1UF,A',
 TOLERANCE='10%',
 CLS_PN='G105-0B104-EK',
 VOLTAGE='25V',
 VALUE='0.1UF',
 PRIM_FILE='./archive_libs/passive/capacitor/chips/chips.prt';

PART_NAME
 C185 'CAPACITOR-G107-0F106-EM,10UF,2A':;

SECTION_NUMBER 1
 '@TIMECARD_LIB.TIMECARD(SCH_1):PAGE68_I27@PASSIVE.CAPACITOR(CHIPS)':
 C_PATH='@timecard_lib.timecard(sch_1):page68_i27@passive.capacitor(chips)',
 P_PATH='@timecard_lib.timecard(sch_1):page30_i27@passive.capacitor(chips)',
 PATH='I27',
 DRAWING='@TIMECARD_LIB.TIMECARD(SCH_1):PAGE68',
 PACKAGE='0805',
 PHYS_PAGE='30',
 XY='(-11250,8450)',
 ROT='0',
 VER='2',
 CDS_LIB='passive',
 CDS_PART_NAME='CAPACITOR-G107-0F106-EM,10UF,2A',
 TOLERANCE='20%',
 CLS_PN='G107-0F106-EM',
 VOLTAGE='25V',
 VALUE='10UF',
 PRIM_FILE='./archive_libs/passive/capacitor/chips/chips.prt';

PART_NAME
 C186 'CAPACITOR-G107-0F106-EM,10UF,2A':;

SECTION_NUMBER 1
 '@TIMECARD_LIB.TIMECARD(SCH_1):PAGE68_I47@PASSIVE.CAPACITOR(CHIPS)':
 C_PATH='@timecard_lib.timecard(sch_1):page68_i47@passive.capacitor(chips)',
 P_PATH='@timecard_lib.timecard(sch_1):page30_i47@passive.capacitor(chips)',
 PATH='I47',
 DRAWING='@TIMECARD_LIB.TIMECARD(SCH_1):PAGE68',
 PACKAGE='0805',
 PHYS_PAGE='30',
 XY='(-11200,3550)',
 ROT='0',
 VER='2',
 CDS_LIB='passive',
 CDS_PART_NAME='CAPACITOR-G107-0F106-EM,10UF,2A',
 TOLERANCE='20%',
 CLS_PN='G107-0F106-EM',
 VOLTAGE='25V',
 VALUE='10UF',
 PRIM_FILE='./archive_libs/passive/capacitor/chips/chips.prt';

PART_NAME
 C187 'CAPACITOR-G105-0B104-EK,0.1UF,A':;

SECTION_NUMBER 1
 '@TIMECARD_LIB.TIMECARD(SCH_1):PAGE68_I46@PASSIVE.CAPACITOR(CHIPS)':
 C_PATH='@timecard_lib.timecard(sch_1):page68_i46@passive.capacitor(chips)',
 P_PATH='@timecard_lib.timecard(sch_1):page30_i46@passive.capacitor(chips)',
 PATH='I46',
 DRAWING='@TIMECARD_LIB.TIMECARD(SCH_1):PAGE68',
 PACKAGE='0402',
 PHYS_PAGE='30',
 XY='(-11200,2600)',
 ROT='0',
 VER='2',
 CDS_LIB='passive',
 CDS_PART_NAME='CAPACITOR-G105-0B104-EK,0.1UF,A',
 TOLERANCE='10%',
 CLS_PN='G105-0B104-EK',
 VOLTAGE='25V',
 VALUE='0.1UF',
 PRIM_FILE='./archive_libs/passive/capacitor/chips/chips.prt';

PART_NAME
 C188 'CAPACITOR-G105-0B104-EK,0.1UF,A':;

SECTION_NUMBER 1
 '@TIMECARD_LIB.TIMECARD(SCH_1):PAGE68_I35@PASSIVE.CAPACITOR(CHIPS)':
 C_PATH='@timecard_lib.timecard(sch_1):page68_i35@passive.capacitor(chips)',
 P_PATH='@timecard_lib.timecard(sch_1):page30_i35@passive.capacitor(chips)',
 PATH='I35',
 DRAWING='@TIMECARD_LIB.TIMECARD(SCH_1):PAGE68',
 PACKAGE='0402',
 PHYS_PAGE='30',
 XY='(-10800,8450)',
 ROT='0',
 VER='2',
 CDS_LIB='passive',
 CDS_PART_NAME='CAPACITOR-G105-0B104-EK,0.1UF,A',
 TOLERANCE='10%',
 CLS_PN='G105-0B104-EK',
 VOLTAGE='25V',
 VALUE='0.1UF',
 PRIM_FILE='./archive_libs/passive/capacitor/chips/chips.prt';

PART_NAME
 C189 'CAPACITOR-G105-0B104-EK,0.1UF,A':;

SECTION_NUMBER 1
 '@TIMECARD_LIB.TIMECARD(SCH_1):PAGE68_I51@PASSIVE.CAPACITOR(CHIPS)':
 C_PATH='@timecard_lib.timecard(sch_1):page68_i51@passive.capacitor(chips)',
 P_PATH='@timecard_lib.timecard(sch_1):page30_i51@passive.capacitor(chips)',
 PATH='I51',
 DRAWING='@TIMECARD_LIB.TIMECARD(SCH_1):PAGE68',
 PACKAGE='0402',
 PHYS_PAGE='30',
 XY='(-10750,3550)',
 ROT='0',
 VER='2',
 CDS_LIB='passive',
 CDS_PART_NAME='CAPACITOR-G105-0B104-EK,0.1UF,A',
 TOLERANCE='10%',
 CLS_PN='G105-0B104-EK',
 VOLTAGE='25V',
 VALUE='0.1UF',
 PRIM_FILE='./archive_libs/passive/capacitor/chips/chips.prt';

PART_NAME
 C190 'CAPACITOR-G104-0B103-EK,0.01UFA':;

SECTION_NUMBER 1
 '@TIMECARD_LIB.TIMECARD(SCH_1):PAGE68_I5@PASSIVE.CAPACITOR(CHIPS)':
 C_PATH='@timecard_lib.timecard(sch_1):page68_i5@passive.capacitor(chips)',
 P_PATH='@timecard_lib.timecard(sch_1):page30_i5@passive.capacitor(chips)',
 PATH='I5',
 DRAWING='@TIMECARD_LIB.TIMECARD(SCH_1):PAGE68',
 PACKAGE='0201',
 PHYS_PAGE='30',
 XY='(-10700,7250)',
 ROT='0',
 VER='2',
 CDS_LIB='passive',
 CDS_PART_NAME='CAPACITOR-G104-0B103-EK,0.01UFA',
 TOLERANCE='10%',
 CLS_PN='G104-0B103-EK',
 VOLTAGE='25V',
 VALUE='0.01UF',
 PRIM_FILE='./archive_libs/passive/capacitor/chips/chips.prt';

PART_NAME
 C191 'CAPACITOR-G104-0B103-EK,0.01UFA':;

SECTION_NUMBER 1
 '@TIMECARD_LIB.TIMECARD(SCH_1):PAGE68_I49@PASSIVE.CAPACITOR(CHIPS)':
 C_PATH='@timecard_lib.timecard(sch_1):page68_i49@passive.capacitor(chips)',
 P_PATH='@timecard_lib.timecard(sch_1):page30_i49@passive.capacitor(chips)',
 PATH='I49',
 DRAWING='@TIMECARD_LIB.TIMECARD(SCH_1):PAGE68',
 PACKAGE='0201',
 PHYS_PAGE='30',
 XY='(-10650,2350)',
 ROT='0',
 VER='2',
 CDS_LIB='passive',
 CDS_PART_NAME='CAPACITOR-G104-0B103-EK,0.01UFA',
 TOLERANCE='10%',
 CLS_PN='G104-0B103-EK',
 VOLTAGE='25V',
 VALUE='0.01UF',
 PRIM_FILE='./archive_libs/passive/capacitor/chips/chips.prt';

PART_NAME
 C192 'CAPACITOR-G104-0B103-EK,0.01UFA':;

SECTION_NUMBER 1
 '@TIMECARD_LIB.TIMECARD(SCH_1):PAGE68_I9@PASSIVE.CAPACITOR(CHIPS)':
 C_PATH='@timecard_lib.timecard(sch_1):page68_i9@passive.capacitor(chips)',
 P_PATH='@timecard_lib.timecard(sch_1):page30_i9@passive.capacitor(chips)',
 PATH='I9',
 DRAWING='@TIMECARD_LIB.TIMECARD(SCH_1):PAGE68',
 PACKAGE='0201',
 PHYS_PAGE='30',
 XY='(-7650,6800)',
 ROT='0',
 VER='2',
 CDS_LIB='passive',
 CDS_PART_NAME='CAPACITOR-G104-0B103-EK,0.01UFA',
 TOLERANCE='10%',
 CLS_PN='G104-0B103-EK',
 VOLTAGE='25V',
 VALUE='0.01UF',
 PRIM_FILE='./archive_libs/passive/capacitor/chips/chips.prt';

PART_NAME
 C193 'CAPACITOR-G104-0B103-EK,0.01UFA':;

SECTION_NUMBER 1
 '@TIMECARD_LIB.TIMECARD(SCH_1):PAGE68_I71@PASSIVE.CAPACITOR(CHIPS)':
 C_PATH='@timecard_lib.timecard(sch_1):page68_i71@passive.capacitor(chips)',
 P_PATH='@timecard_lib.timecard(sch_1):page30_i71@passive.capacitor(chips)',
 PATH='I71',
 DRAWING='@TIMECARD_LIB.TIMECARD(SCH_1):PAGE68',
 PACKAGE='0201',
 PHYS_PAGE='30',
 XY='(-7650,1900)',
 ROT='0',
 VER='2',
 CDS_LIB='passive',
 CDS_PART_NAME='CAPACITOR-G104-0B103-EK,0.01UFA',
 TOLERANCE='10%',
 CLS_PN='G104-0B103-EK',
 VOLTAGE='25V',
 VALUE='0.01UF',
 PRIM_FILE='./archive_libs/passive/capacitor/chips/chips.prt';

PART_NAME
 C194 'CAPACITOR-G107-0F106-EM,10UF,2A':;

SECTION_NUMBER 1
 '@TIMECARD_LIB.TIMECARD(SCH_1):PAGE68_I60@PASSIVE.CAPACITOR(CHIPS)':
 C_PATH='@timecard_lib.timecard(sch_1):page68_i60@passive.capacitor(chips)',
 P_PATH='@timecard_lib.timecard(sch_1):page30_i60@passive.capacitor(chips)',
 PATH='I60',
 DRAWING='@TIMECARD_LIB.TIMECARD(SCH_1):PAGE68',
 PACKAGE='0805',
 PHYS_PAGE='30',
 XY='(-5750,8350)',
 ROT='0',
 VER='2',
 CDS_LIB='passive',
 CDS_PART_NAME='CAPACITOR-G107-0F106-EM,10UF,2A',
 TOLERANCE='20%',
 CLS_PN='G107-0F106-EM',
 VOLTAGE='25V',
 VALUE='10UF',
 PRIM_FILE='./archive_libs/passive/capacitor/chips/chips.prt';

PART_NAME
 C195 'CAPACITOR-G107-0F106-EM,10UF,2A':;

SECTION_NUMBER 1
 '@TIMECARD_LIB.TIMECARD(SCH_1):PAGE68_I81@PASSIVE.CAPACITOR(CHIPS)':
 C_PATH='@timecard_lib.timecard(sch_1):page68_i81@passive.capacitor(chips)',
 P_PATH='@timecard_lib.timecard(sch_1):page30_i81@passive.capacitor(chips)',
 PATH='I81',
 DRAWING='@TIMECARD_LIB.TIMECARD(SCH_1):PAGE68',
 PACKAGE='0805',
 PHYS_PAGE='30',
 XY='(-5700,3450)',
 ROT='0',
 VER='2',
 CDS_LIB='passive',
 CDS_PART_NAME='CAPACITOR-G107-0F106-EM,10UF,2A',
 TOLERANCE='20%',
 CLS_PN='G107-0F106-EM',
 VOLTAGE='25V',
 VALUE='10UF',
 PRIM_FILE='./archive_libs/passive/capacitor/chips/chips.prt';

PART_NAME
 C196 'CAPACITOR-G105-0B104-EK,0.1UF,A':;

SECTION_NUMBER 1
 '@TIMECARD_LIB.TIMECARD(SCH_1):PAGE68_I61@PASSIVE.CAPACITOR(CHIPS)':
 C_PATH='@timecard_lib.timecard(sch_1):page68_i61@passive.capacitor(chips)',
 P_PATH='@timecard_lib.timecard(sch_1):page30_i61@passive.capacitor(chips)',
 PATH='I61',
 DRAWING='@TIMECARD_LIB.TIMECARD(SCH_1):PAGE68',
 PACKAGE='0402',
 PHYS_PAGE='30',
 XY='(-5150,8350)',
 ROT='0',
 VER='2',
 CDS_LIB='passive',
 CDS_PART_NAME='CAPACITOR-G105-0B104-EK,0.1UF,A',
 TOLERANCE='10%',
 CLS_PN='G105-0B104-EK',
 VOLTAGE='25V',
 VALUE='0.1UF',
 PRIM_FILE='./archive_libs/passive/capacitor/chips/chips.prt';

PART_NAME
 C197 'CAPACITOR-G105-0B104-EK,0.1UF,A':;

SECTION_NUMBER 1
 '@TIMECARD_LIB.TIMECARD(SCH_1):PAGE68_I83@PASSIVE.CAPACITOR(CHIPS)':
 C_PATH='@timecard_lib.timecard(sch_1):page68_i83@passive.capacitor(chips)',
 P_PATH='@timecard_lib.timecard(sch_1):page30_i83@passive.capacitor(chips)',
 PATH='I83',
 DRAWING='@TIMECARD_LIB.TIMECARD(SCH_1):PAGE68',
 PACKAGE='0402',
 PHYS_PAGE='30',
 XY='(-5100,3450)',
 ROT='0',
 VER='2',
 CDS_LIB='passive',
 CDS_PART_NAME='CAPACITOR-G105-0B104-EK,0.1UF,A',
 TOLERANCE='10%',
 CLS_PN='G105-0B104-EK',
 VOLTAGE='25V',
 VALUE='0.1UF',
 PRIM_FILE='./archive_libs/passive/capacitor/chips/chips.prt';

PART_NAME
 C198 'CAPACITOR-G105-0F475-BM,4.7UF,A':;

SECTION_NUMBER 1
 '@TIMECARD_LIB.TIMECARD(SCH_1):PAGE127_I473@PASSIVE.CAPACITOR(CHIPS)':
 C_PATH='@timecard_lib.timecard(sch_1):page127_i473@passive.capacitor(chips)',
 P_PATH='@timecard_lib.timecard(sch_1):page10_i473@passive.capacitor(chips)',
 PATH='I473',
 DRAWING='@TIMECARD_LIB.TIMECARD(SCH_1):PAGE127',
 PACKAGE='0402',
 PHYS_PAGE='10',
 XY='(-7600,900)',
 ROT='0',
 VER='2',
 CDS_LIB='passive',
 CDS_PART_NAME='CAPACITOR-G105-0F475-BM,4.7UF,A',
 TOLERANCE='20%',
 CLS_PN='G105-0F475-BM',
 VOLTAGE='6.3V',
 VALUE='4.7UF',
 PRIM_FILE='./archive_libs/passive/capacitor/chips/chips.prt';

PART_NAME
 C199 'CAPACITOR-G105-0B104-CK,0.1UF,A':;

SECTION_NUMBER 1
 '@TIMECARD_LIB.TIMECARD(SCH_1):PAGE127_I472@PASSIVE.CAPACITOR(CHIPS)':
 C_PATH='@timecard_lib.timecard(sch_1):page127_i472@passive.capacitor(chips)',
 P_PATH='@timecard_lib.timecard(sch_1):page10_i472@passive.capacitor(chips)',
 PATH='I472',
 DRAWING='@TIMECARD_LIB.TIMECARD(SCH_1):PAGE127',
 PACKAGE='0402',
 PHYS_PAGE='10',
 XY='(-7000,900)',
 ROT='0',
 VER='2',
 CDS_LIB='passive',
 CDS_PART_NAME='CAPACITOR-G105-0B104-CK,0.1UF,A',
 TOLERANCE='10%',
 CLS_PN='G105-0B104-CK',
 VOLTAGE='10V',
 VALUE='0.1UF',
 PRIM_FILE='./archive_libs/passive/capacitor/chips/chips.prt';

PART_NAME
 C200 'CAPACITOR-G105-0B104-CK,0.1UF,A':;

SECTION_NUMBER 1
 '@TIMECARD_LIB.TIMECARD(SCH_1):PAGE164_I199@PASSIVE.CAPACITOR(CHIPS)':
 C_PATH='@timecard_lib.timecard(sch_1):page164_i199@passive.capacitor(chips)',
 P_PATH='@timecard_lib.timecard(sch_1):page14_i199@passive.capacitor(chips)',
 PATH='I199',
 DRAWING='@TIMECARD_LIB.TIMECARD(SCH_1):PAGE164',
 PACKAGE='0402',
 PHYS_PAGE='14',
 XY='(-10950,7150)',
 ROT='0',
 VER='2',
 CDS_LIB='passive',
 CDS_PART_NAME='CAPACITOR-G105-0B104-CK,0.1UF,A',
 TOLERANCE='10%',
 CLS_PN='G105-0B104-CK',
 VOLTAGE='10V',
 VALUE='0.1UF',
 PRIM_FILE='./archive_libs/passive/capacitor/chips/chips.prt';

PART_NAME
 C201 'CAPACITOR-G105-0B104-CK,0.1UF,A':;

SECTION_NUMBER 1
 '@TIMECARD_LIB.TIMECARD(SCH_1):PAGE164_I182@PASSIVE.CAPACITOR(CHIPS)':
 C_PATH='@timecard_lib.timecard(sch_1):page164_i182@passive.capacitor(chips)',
 P_PATH='@timecard_lib.timecard(sch_1):page14_i182@passive.capacitor(chips)',
 PATH='I182',
 DRAWING='@TIMECARD_LIB.TIMECARD(SCH_1):PAGE164',
 PACKAGE='0402',
 PHYS_PAGE='14',
 XY='(-10950,5700)',
 ROT='0',
 VER='2',
 CDS_LIB='passive',
 CDS_PART_NAME='CAPACITOR-G105-0B104-CK,0.1UF,A',
 TOLERANCE='10%',
 CLS_PN='G105-0B104-CK',
 VOLTAGE='10V',
 VALUE='0.1UF',
 PRIM_FILE='./archive_libs/passive/capacitor/chips/chips.prt';

PART_NAME
 C202 'CAPACITOR-G105-0B104-CK,0.1UF,A':;

SECTION_NUMBER 1
 '@TIMECARD_LIB.TIMECARD(SCH_1):PAGE164_I205@PASSIVE.CAPACITOR(CHIPS)':
 C_PATH='@timecard_lib.timecard(sch_1):page164_i205@passive.capacitor(chips)',
 P_PATH='@timecard_lib.timecard(sch_1):page14_i205@passive.capacitor(chips)',
 PATH='I205',
 DRAWING='@TIMECARD_LIB.TIMECARD(SCH_1):PAGE164',
 PACKAGE='0402',
 PHYS_PAGE='14',
 XY='(-10950,4300)',
 ROT='0',
 VER='2',
 CDS_LIB='passive',
 CDS_PART_NAME='CAPACITOR-G105-0B104-CK,0.1UF,A',
 TOLERANCE='10%',
 CLS_PN='G105-0B104-CK',
 VOLTAGE='10V',
 VALUE='0.1UF',
 PRIM_FILE='./archive_libs/passive/capacitor/chips/chips.prt';

PART_NAME
 C203 'CAPACITOR-G105-0B104-CK,0.1UF,A':;

SECTION_NUMBER 1
 '@TIMECARD_LIB.TIMECARD(SCH_1):PAGE164_I216@PASSIVE.CAPACITOR(CHIPS)':
 C_PATH='@timecard_lib.timecard(sch_1):page164_i216@passive.capacitor(chips)',
 P_PATH='@timecard_lib.timecard(sch_1):page14_i216@passive.capacitor(chips)',
 PATH='I216',
 DRAWING='@TIMECARD_LIB.TIMECARD(SCH_1):PAGE164',
 PACKAGE='0402',
 PHYS_PAGE='14',
 XY='(-10950,3450)',
 ROT='0',
 VER='2',
 CDS_LIB='passive',
 CDS_PART_NAME='CAPACITOR-G105-0B104-CK,0.1UF,A',
 TOLERANCE='10%',
 CLS_PN='G105-0B104-CK',
 VOLTAGE='10V',
 VALUE='0.1UF',
 PRIM_FILE='./archive_libs/passive/capacitor/chips/chips.prt';

PART_NAME
 C204 'CAPACITOR-G105-0B104-CK,0.1UF,A':;

SECTION_NUMBER 1
 '@TIMECARD_LIB.TIMECARD(SCH_1):PAGE164_I231@PASSIVE.CAPACITOR(CHIPS)':
 C_PATH='@timecard_lib.timecard(sch_1):page164_i231@passive.capacitor(chips)',
 P_PATH='@timecard_lib.timecard(sch_1):page14_i231@passive.capacitor(chips)',
 PATH='I231',
 DRAWING='@TIMECARD_LIB.TIMECARD(SCH_1):PAGE164',
 PACKAGE='0402',
 PHYS_PAGE='14',
 XY='(-10950,2050)',
 ROT='0',
 VER='2',
 CDS_LIB='passive',
 CDS_PART_NAME='CAPACITOR-G105-0B104-CK,0.1UF,A',
 TOLERANCE='10%',
 CLS_PN='G105-0B104-CK',
 VOLTAGE='10V',
 VALUE='0.1UF',
 PRIM_FILE='./archive_libs/passive/capacitor/chips/chips.prt';

PART_NAME
 C205 'CAPACITOR-G105-0B104-CK,0.1UF,A':;

SECTION_NUMBER 1
 '@TIMECARD_LIB.TIMECARD(SCH_1):PAGE164_I260@PASSIVE.CAPACITOR(CHIPS)':
 C_PATH='@timecard_lib.timecard(sch_1):page164_i260@passive.capacitor(chips)',
 P_PATH='@timecard_lib.timecard(sch_1):page14_i260@passive.capacitor(chips)',
 PATH='I260',
 DRAWING='@TIMECARD_LIB.TIMECARD(SCH_1):PAGE164',
 PACKAGE='0402',
 PHYS_PAGE='14',
 XY='(-10950,-650)',
 ROT='0',
 VER='2',
 CDS_LIB='passive',
 CDS_PART_NAME='CAPACITOR-G105-0B104-CK,0.1UF,A',
 TOLERANCE='10%',
 CLS_PN='G105-0B104-CK',
 VOLTAGE='10V',
 VALUE='0.1UF',
 PRIM_FILE='./archive_libs/passive/capacitor/chips/chips.prt';

PART_NAME
 C206 'CAPACITOR-G105-0B104-CK,0.1UF,A':;

SECTION_NUMBER 1
 '@TIMECARD_LIB.TIMECARD(SCH_1):PAGE164_I200@PASSIVE.CAPACITOR(CHIPS)':
 C_PATH='@timecard_lib.timecard(sch_1):page164_i200@passive.capacitor(chips)',
 P_PATH='@timecard_lib.timecard(sch_1):page14_i200@passive.capacitor(chips)',
 PATH='I200',
 DRAWING='@TIMECARD_LIB.TIMECARD(SCH_1):PAGE164',
 PACKAGE='0402',
 PHYS_PAGE='14',
 XY='(-10600,7150)',
 ROT='0',
 VER='2',
 CDS_LIB='passive',
 CDS_PART_NAME='CAPACITOR-G105-0B104-CK,0.1UF,A',
 TOLERANCE='10%',
 CLS_PN='G105-0B104-CK',
 VOLTAGE='10V',
 VALUE='0.1UF',
 PRIM_FILE='./archive_libs/passive/capacitor/chips/chips.prt';

PART_NAME
 C207 'CAPACITOR-G105-0B104-CK,0.1UF,A':;

SECTION_NUMBER 1
 '@TIMECARD_LIB.TIMECARD(SCH_1):PAGE164_I183@PASSIVE.CAPACITOR(CHIPS)':
 C_PATH='@timecard_lib.timecard(sch_1):page164_i183@passive.capacitor(chips)',
 P_PATH='@timecard_lib.timecard(sch_1):page14_i183@passive.capacitor(chips)',
 PATH='I183',
 DRAWING='@TIMECARD_LIB.TIMECARD(SCH_1):PAGE164',
 PACKAGE='0402',
 PHYS_PAGE='14',
 XY='(-10600,5700)',
 ROT='0',
 VER='2',
 CDS_LIB='passive',
 CDS_PART_NAME='CAPACITOR-G105-0B104-CK,0.1UF,A',
 TOLERANCE='10%',
 CLS_PN='G105-0B104-CK',
 VOLTAGE='10V',
 VALUE='0.1UF',
 PRIM_FILE='./archive_libs/passive/capacitor/chips/chips.prt';

PART_NAME
 C208 'CAPACITOR-G105-0B104-CK,0.1UF,A':;

SECTION_NUMBER 1
 '@TIMECARD_LIB.TIMECARD(SCH_1):PAGE164_I232@PASSIVE.CAPACITOR(CHIPS)':
 C_PATH='@timecard_lib.timecard(sch_1):page164_i232@passive.capacitor(chips)',
 P_PATH='@timecard_lib.timecard(sch_1):page14_i232@passive.capacitor(chips)',
 PATH='I232',
 DRAWING='@TIMECARD_LIB.TIMECARD(SCH_1):PAGE164',
 PACKAGE='0402',
 PHYS_PAGE='14',
 XY='(-10600,2050)',
 ROT='0',
 VER='2',
 CDS_LIB='passive',
 CDS_PART_NAME='CAPACITOR-G105-0B104-CK,0.1UF,A',
 TOLERANCE='10%',
 CLS_PN='G105-0B104-CK',
 VOLTAGE='10V',
 VALUE='0.1UF',
 PRIM_FILE='./archive_libs/passive/capacitor/chips/chips.prt';

PART_NAME
 C209 'CAPACITOR-G105-0B104-CK,0.1UF,A':;

SECTION_NUMBER 1
 '@TIMECARD_LIB.TIMECARD(SCH_1):PAGE164_I259@PASSIVE.CAPACITOR(CHIPS)':
 C_PATH='@timecard_lib.timecard(sch_1):page164_i259@passive.capacitor(chips)',
 P_PATH='@timecard_lib.timecard(sch_1):page14_i259@passive.capacitor(chips)',
 PATH='I259',
 DRAWING='@TIMECARD_LIB.TIMECARD(SCH_1):PAGE164',
 PACKAGE='0402',
 PHYS_PAGE='14',
 XY='(-10600,-650)',
 ROT='0',
 VER='2',
 CDS_LIB='passive',
 CDS_PART_NAME='CAPACITOR-G105-0B104-CK,0.1UF,A',
 TOLERANCE='10%',
 CLS_PN='G105-0B104-CK',
 VOLTAGE='10V',
 VALUE='0.1UF',
 PRIM_FILE='./archive_libs/passive/capacitor/chips/chips.prt';

PART_NAME
 C210 'CAPACITOR-G105-0B104-CK,0.1UF,A':;

SECTION_NUMBER 1
 '@TIMECARD_LIB.TIMECARD(SCH_1):PAGE164_I206@PASSIVE.CAPACITOR(CHIPS)':
 C_PATH='@timecard_lib.timecard(sch_1):page164_i206@passive.capacitor(chips)',
 P_PATH='@timecard_lib.timecard(sch_1):page14_i206@passive.capacitor(chips)',
 PATH='I206',
 DRAWING='@TIMECARD_LIB.TIMECARD(SCH_1):PAGE164',
 PACKAGE='0402',
 PHYS_PAGE='14',
 XY='(-10550,4300)',
 ROT='0',
 VER='2',
 CDS_LIB='passive',
 CDS_PART_NAME='CAPACITOR-G105-0B104-CK,0.1UF,A',
 TOLERANCE='10%',
 CLS_PN='G105-0B104-CK',
 VOLTAGE='10V',
 VALUE='0.1UF',
 PRIM_FILE='./archive_libs/passive/capacitor/chips/chips.prt';

PART_NAME
 C211 'CAPACITOR-G105-0B104-CK,0.1UF,A':;

SECTION_NUMBER 1
 '@TIMECARD_LIB.TIMECARD(SCH_1):PAGE164_I217@PASSIVE.CAPACITOR(CHIPS)':
 C_PATH='@timecard_lib.timecard(sch_1):page164_i217@passive.capacitor(chips)',
 P_PATH='@timecard_lib.timecard(sch_1):page14_i217@passive.capacitor(chips)',
 PATH='I217',
 DRAWING='@TIMECARD_LIB.TIMECARD(SCH_1):PAGE164',
 PACKAGE='0402',
 PHYS_PAGE='14',
 XY='(-10550,3450)',
 ROT='0',
 VER='2',
 CDS_LIB='passive',
 CDS_PART_NAME='CAPACITOR-G105-0B104-CK,0.1UF,A',
 TOLERANCE='10%',
 CLS_PN='G105-0B104-CK',
 VOLTAGE='10V',
 VALUE='0.1UF',
 PRIM_FILE='./archive_libs/passive/capacitor/chips/chips.prt';

PART_NAME
 C212 'CAPACITOR-G105-0B104-CK,0.1UF,A':;

SECTION_NUMBER 1
 '@TIMECARD_LIB.TIMECARD(SCH_1):PAGE164_I201@PASSIVE.CAPACITOR(CHIPS)':
 C_PATH='@timecard_lib.timecard(sch_1):page164_i201@passive.capacitor(chips)',
 P_PATH='@timecard_lib.timecard(sch_1):page14_i201@passive.capacitor(chips)',
 PATH='I201',
 DRAWING='@TIMECARD_LIB.TIMECARD(SCH_1):PAGE164',
 PACKAGE='0402',
 PHYS_PAGE='14',
 XY='(-10250,7150)',
 ROT='0',
 VER='2',
 CDS_LIB='passive',
 CDS_PART_NAME='CAPACITOR-G105-0B104-CK,0.1UF,A',
 TOLERANCE='10%',
 CLS_PN='G105-0B104-CK',
 VOLTAGE='10V',
 VALUE='0.1UF',
 PRIM_FILE='./archive_libs/passive/capacitor/chips/chips.prt';

PART_NAME
 C213 'CAPACITOR-G105-0B104-CK,0.1UF,A':;

SECTION_NUMBER 1
 '@TIMECARD_LIB.TIMECARD(SCH_1):PAGE164_I233@PASSIVE.CAPACITOR(CHIPS)':
 C_PATH='@timecard_lib.timecard(sch_1):page164_i233@passive.capacitor(chips)',
 P_PATH='@timecard_lib.timecard(sch_1):page14_i233@passive.capacitor(chips)',
 PATH='I233',
 DRAWING='@TIMECARD_LIB.TIMECARD(SCH_1):PAGE164',
 PACKAGE='0402',
 PHYS_PAGE='14',
 XY='(-10250,2050)',
 ROT='0',
 VER='2',
 CDS_LIB='passive',
 CDS_PART_NAME='CAPACITOR-G105-0B104-CK,0.1UF,A',
 TOLERANCE='10%',
 CLS_PN='G105-0B104-CK',
 VOLTAGE='10V',
 VALUE='0.1UF',
 PRIM_FILE='./archive_libs/passive/capacitor/chips/chips.prt';

PART_NAME
 C214 'CAPACITOR-G105-0B104-CK,0.1UF,A':;

SECTION_NUMBER 1
 '@TIMECARD_LIB.TIMECARD(SCH_1):PAGE164_I184@PASSIVE.CAPACITOR(CHIPS)':
 C_PATH='@timecard_lib.timecard(sch_1):page164_i184@passive.capacitor(chips)',
 P_PATH='@timecard_lib.timecard(sch_1):page14_i184@passive.capacitor(chips)',
 PATH='I184',
 DRAWING='@TIMECARD_LIB.TIMECARD(SCH_1):PAGE164',
 PACKAGE='0402',
 PHYS_PAGE='14',
 XY='(-10200,5700)',
 ROT='0',
 VER='2',
 CDS_LIB='passive',
 CDS_PART_NAME='CAPACITOR-G105-0B104-CK,0.1UF,A',
 TOLERANCE='10%',
 CLS_PN='G105-0B104-CK',
 VOLTAGE='10V',
 VALUE='0.1UF',
 PRIM_FILE='./archive_libs/passive/capacitor/chips/chips.prt';

PART_NAME
 C215 'CAPACITOR-G105-0B104-CK,0.1UF,A':;

SECTION_NUMBER 1
 '@TIMECARD_LIB.TIMECARD(SCH_1):PAGE164_I207@PASSIVE.CAPACITOR(CHIPS)':
 C_PATH='@timecard_lib.timecard(sch_1):page164_i207@passive.capacitor(chips)',
 P_PATH='@timecard_lib.timecard(sch_1):page14_i207@passive.capacitor(chips)',
 PATH='I207',
 DRAWING='@TIMECARD_LIB.TIMECARD(SCH_1):PAGE164',
 PACKAGE='0402',
 PHYS_PAGE='14',
 XY='(-10200,4300)',
 ROT='0',
 VER='2',
 CDS_LIB='passive',
 CDS_PART_NAME='CAPACITOR-G105-0B104-CK,0.1UF,A',
 TOLERANCE='10%',
 CLS_PN='G105-0B104-CK',
 VOLTAGE='10V',
 VALUE='0.1UF',
 PRIM_FILE='./archive_libs/passive/capacitor/chips/chips.prt';

PART_NAME
 C216 'CAPACITOR-G105-0B104-CK,0.1UF,A':;

SECTION_NUMBER 1
 '@TIMECARD_LIB.TIMECARD(SCH_1):PAGE164_I218@PASSIVE.CAPACITOR(CHIPS)':
 C_PATH='@timecard_lib.timecard(sch_1):page164_i218@passive.capacitor(chips)',
 P_PATH='@timecard_lib.timecard(sch_1):page14_i218@passive.capacitor(chips)',
 PATH='I218',
 DRAWING='@TIMECARD_LIB.TIMECARD(SCH_1):PAGE164',
 PACKAGE='0402',
 PHYS_PAGE='14',
 XY='(-10200,3450)',
 ROT='0',
 VER='2',
 CDS_LIB='passive',
 CDS_PART_NAME='CAPACITOR-G105-0B104-CK,0.1UF,A',
 TOLERANCE='10%',
 CLS_PN='G105-0B104-CK',
 VOLTAGE='10V',
 VALUE='0.1UF',
 PRIM_FILE='./archive_libs/passive/capacitor/chips/chips.prt';

PART_NAME
 C217 'CAPACITOR-G105-0B104-CK,0.1UF,A':;

SECTION_NUMBER 1
 '@TIMECARD_LIB.TIMECARD(SCH_1):PAGE164_I258@PASSIVE.CAPACITOR(CHIPS)':
 C_PATH='@timecard_lib.timecard(sch_1):page164_i258@passive.capacitor(chips)',
 P_PATH='@timecard_lib.timecard(sch_1):page14_i258@passive.capacitor(chips)',
 PATH='I258',
 DRAWING='@TIMECARD_LIB.TIMECARD(SCH_1):PAGE164',
 PACKAGE='0402',
 PHYS_PAGE='14',
 XY='(-10200,-650)',
 ROT='0',
 VER='2',
 CDS_LIB='passive',
 CDS_PART_NAME='CAPACITOR-G105-0B104-CK,0.1UF,A',
 TOLERANCE='10%',
 CLS_PN='G105-0B104-CK',
 VOLTAGE='10V',
 VALUE='0.1UF',
 PRIM_FILE='./archive_libs/passive/capacitor/chips/chips.prt';

PART_NAME
 C218 'CAPACITOR-G105-0B104-CK,0.1UF,A':;

SECTION_NUMBER 1
 '@TIMECARD_LIB.TIMECARD(SCH_1):PAGE164_I251@PASSIVE.CAPACITOR(CHIPS)':
 C_PATH='@timecard_lib.timecard(sch_1):page164_i251@passive.capacitor(chips)',
 P_PATH='@timecard_lib.timecard(sch_1):page14_i251@passive.capacitor(chips)',
 PATH='I251',
 DRAWING='@TIMECARD_LIB.TIMECARD(SCH_1):PAGE164',
 PACKAGE='0402',
 PHYS_PAGE='14',
 XY='(-10150,450)',
 ROT='0',
 VER='2',
 CDS_LIB='passive',
 CDS_PART_NAME='CAPACITOR-G105-0B104-CK,0.1UF,A',
 TOLERANCE='10%',
 CLS_PN='G105-0B104-CK',
 VOLTAGE='10V',
 VALUE='0.1UF',
 PRIM_FILE='./archive_libs/passive/capacitor/chips/chips.prt';

PART_NAME
 C219 'CAPACITOR-G105-0B104-CK,0.1UF,A':;

SECTION_NUMBER 1
 '@TIMECARD_LIB.TIMECARD(SCH_1):PAGE164_I202@PASSIVE.CAPACITOR(CHIPS)':
 C_PATH='@timecard_lib.timecard(sch_1):page164_i202@passive.capacitor(chips)',
 P_PATH='@timecard_lib.timecard(sch_1):page14_i202@passive.capacitor(chips)',
 PATH='I202',
 DRAWING='@TIMECARD_LIB.TIMECARD(SCH_1):PAGE164',
 PACKAGE='0402',
 PHYS_PAGE='14',
 XY='(-9900,7150)',
 ROT='0',
 VER='2',
 CDS_LIB='passive',
 CDS_PART_NAME='CAPACITOR-G105-0B104-CK,0.1UF,A',
 TOLERANCE='10%',
 CLS_PN='G105-0B104-CK',
 VOLTAGE='10V',
 VALUE='0.1UF',
 PRIM_FILE='./archive_libs/passive/capacitor/chips/chips.prt';

PART_NAME
 C220 'CAPACITOR-G105-0B104-CK,0.1UF,A':;

SECTION_NUMBER 1
 '@TIMECARD_LIB.TIMECARD(SCH_1):PAGE164_I234@PASSIVE.CAPACITOR(CHIPS)':
 C_PATH='@timecard_lib.timecard(sch_1):page164_i234@passive.capacitor(chips)',
 P_PATH='@timecard_lib.timecard(sch_1):page14_i234@passive.capacitor(chips)',
 PATH='I234',
 DRAWING='@TIMECARD_LIB.TIMECARD(SCH_1):PAGE164',
 PACKAGE='0402',
 PHYS_PAGE='14',
 XY='(-9900,2050)',
 ROT='0',
 VER='2',
 CDS_LIB='passive',
 CDS_PART_NAME='CAPACITOR-G105-0B104-CK,0.1UF,A',
 TOLERANCE='10%',
 CLS_PN='G105-0B104-CK',
 VOLTAGE='10V',
 VALUE='0.1UF',
 PRIM_FILE='./archive_libs/passive/capacitor/chips/chips.prt';

PART_NAME
 C221 'CAPACITOR-G105-0B104-CK,0.1UF,A':;

SECTION_NUMBER 1
 '@TIMECARD_LIB.TIMECARD(SCH_1):PAGE164_I219@PASSIVE.CAPACITOR(CHIPS)':
 C_PATH='@timecard_lib.timecard(sch_1):page164_i219@passive.capacitor(chips)',
 P_PATH='@timecard_lib.timecard(sch_1):page14_i219@passive.capacitor(chips)',
 PATH='I219',
 DRAWING='@TIMECARD_LIB.TIMECARD(SCH_1):PAGE164',
 PACKAGE='0402',
 PHYS_PAGE='14',
 XY='(-9850,3450)',
 ROT='0',
 VER='2',
 CDS_LIB='passive',
 CDS_PART_NAME='CAPACITOR-G105-0B104-CK,0.1UF,A',
 TOLERANCE='10%',
 CLS_PN='G105-0B104-CK',
 VOLTAGE='10V',
 VALUE='0.1UF',
 PRIM_FILE='./archive_libs/passive/capacitor/chips/chips.prt';

PART_NAME
 C222 'CAPACITOR-G105-0B104-CK,0.1UF,A':;

SECTION_NUMBER 1
 '@TIMECARD_LIB.TIMECARD(SCH_1):PAGE164_I185@PASSIVE.CAPACITOR(CHIPS)':
 C_PATH='@timecard_lib.timecard(sch_1):page164_i185@passive.capacitor(chips)',
 P_PATH='@timecard_lib.timecard(sch_1):page14_i185@passive.capacitor(chips)',
 PATH='I185',
 DRAWING='@TIMECARD_LIB.TIMECARD(SCH_1):PAGE164',
 PACKAGE='0402',
 PHYS_PAGE='14',
 XY='(-9800,5700)',
 ROT='0',
 VER='2',
 CDS_LIB='passive',
 CDS_PART_NAME='CAPACITOR-G105-0B104-CK,0.1UF,A',
 TOLERANCE='10%',
 CLS_PN='G105-0B104-CK',
 VOLTAGE='10V',
 VALUE='0.1UF',
 PRIM_FILE='./archive_libs/passive/capacitor/chips/chips.prt';

PART_NAME
 C223 'CAPACITOR-G105-0B104-CK,0.1UF,A':;

SECTION_NUMBER 1
 '@TIMECARD_LIB.TIMECARD(SCH_1):PAGE164_I222@PASSIVE.CAPACITOR(CHIPS)':
 C_PATH='@timecard_lib.timecard(sch_1):page164_i222@passive.capacitor(chips)',
 P_PATH='@timecard_lib.timecard(sch_1):page14_i222@passive.capacitor(chips)',
 PATH='I222',
 DRAWING='@TIMECARD_LIB.TIMECARD(SCH_1):PAGE164',
 PACKAGE='0402',
 PHYS_PAGE='14',
 XY='(-8700,3450)',
 ROT='0',
 VER='2',
 CDS_LIB='passive',
 CDS_PART_NAME='CAPACITOR-G105-0B104-CK,0.1UF,A',
 TOLERANCE='10%',
 CLS_PN='G105-0B104-CK',
 VOLTAGE='10V',
 VALUE='0.1UF',
 PRIM_FILE='./archive_libs/passive/capacitor/chips/chips.prt';

PART_NAME
 C224 'CAPACITOR-G107-0F226-CM,22UF,2A':;

SECTION_NUMBER 1
 '@TIMECARD_LIB.TIMECARD(SCH_1):PAGE515_I154@PASSIVE.CAPACITOR(CHIPS)':
 C_PATH='@timecard_lib.timecard(sch_1):page515_i154@passive.capacitor(chips)',
 P_PATH='@timecard_lib.timecard(sch_1):page31_i154@passive.capacitor(chips)',
 PATH='I154',
 DRAWING='@TIMECARD_LIB.TIMECARD(SCH_1):PAGE515',
 PACKAGE='0805',
 PHYS_PAGE='31',
 XY='(-11200,1850)',
 ROT='0',
 VER='2',
 CDS_LIB='passive',
 CDS_PART_NAME='CAPACITOR-G107-0F226-CM,22UF,2A',
 TOLERANCE='20%',
 CLS_PN='G107-0F226-CM',
 VOLTAGE='10V',
 VALUE='22UF',
 PRIM_FILE='./archive_libs/passive/capacitor/chips/chips.prt';

PART_NAME
 C225 'CAPACITOR-G105-0B104-EK,0.1UF,A':;

SECTION_NUMBER 1
 '@TIMECARD_LIB.TIMECARD(SCH_1):PAGE5_I92@PASSIVE.CAPACITOR(CHIPS)':
 C_PATH='@timecard_lib.timecard(sch_1):page5_i92@passive.capacitor(chips)',
 P_PATH='@timecard_lib.timecard(sch_1):page16_i92@passive.capacitor(chips)',
 PATH='I92',
 DRAWING='@TIMECARD_LIB.TIMECARD(SCH_1):PAGE5',
 PACKAGE='0402',
 PHYS_PAGE='16',
 XY='(-4850,6100)',
 ROT='0',
 VER='2',
 CDS_LIB='passive',
 CDS_PART_NAME='CAPACITOR-G105-0B104-EK,0.1UF,A',
 TOLERANCE='10%',
 CLS_PN='G105-0B104-EK',
 VOLTAGE='25V',
 VALUE='0.1UF',
 PRIM_FILE='./archive_libs/passive/capacitor/chips/chips.prt';

PART_NAME
 C226 'CAPACITOR-G105-0B104-EK,0.1UF,A':;

SECTION_NUMBER 1
 '@TIMECARD_LIB.TIMECARD(SCH_1):PAGE515_I155@PASSIVE.CAPACITOR(CHIPS)':
 C_PATH='@timecard_lib.timecard(sch_1):page515_i155@passive.capacitor(chips)',
 P_PATH='@timecard_lib.timecard(sch_1):page31_i155@passive.capacitor(chips)',
 PATH='I155',
 DRAWING='@TIMECARD_LIB.TIMECARD(SCH_1):PAGE515',
 MATERIAL='X7R',
 PACKAGE='0402',
 PHYS_PAGE='31',
 XY='(-10750,1850)',
 ROT='0',
 VER='2',
 CDS_LIB='passive',
 CDS_PART_NAME='CAPACITOR-G105-0B104-EK,0.1UF,A',
 TOLERANCE='10%',
 CLS_PN='G105-0B104-EK',
 VOLTAGE='25V',
 VALUE='0.1UF',
 PRIM_FILE='./archive_libs/passive/capacitor/chips/chips.prt';

PART_NAME
 C227 'CAPACITOR-G105-0B104-EK,0.1UF,A':;

SECTION_NUMBER 1
 '@TIMECARD_LIB.TIMECARD(SCH_1):PAGE515_I128@PASSIVE.CAPACITOR(CHIPS)':
 C_PATH='@timecard_lib.timecard(sch_1):page515_i128@passive.capacitor(chips)',
 P_PATH='@timecard_lib.timecard(sch_1):page31_i128@passive.capacitor(chips)',
 PATH='I128',
 DRAWING='@TIMECARD_LIB.TIMECARD(SCH_1):PAGE515',
 PACKAGE='0402',
 PHYS_PAGE='31',
 XY='(-9250,800)',
 ROT='0',
 VER='2',
 CDS_LIB='passive',
 CDS_PART_NAME='CAPACITOR-G105-0B104-EK,0.1UF,A',
 TOLERANCE='10%',
 CLS_PN='G105-0B104-EK',
 VOLTAGE='25V',
 VALUE='0.1UF',
 PRIM_FILE='./archive_libs/passive/capacitor/chips/chips.prt';

PART_NAME
 C228 'CAPACITOR-G107-0F106-EM,10UF,2A':;

SECTION_NUMBER 1
 '@TIMECARD_LIB.TIMECARD(SCH_1):PAGE515_I130@PASSIVE.CAPACITOR(CHIPS)':
 C_PATH='@timecard_lib.timecard(sch_1):page515_i130@passive.capacitor(chips)',
 P_PATH='@timecard_lib.timecard(sch_1):page31_i130@passive.capacitor(chips)',
 PATH='I130',
 DRAWING='@TIMECARD_LIB.TIMECARD(SCH_1):PAGE515',
 PACKAGE='0805',
 PHYS_PAGE='31',
 XY='(-9300,1850)',
 ROT='0',
 VER='2',
 CDS_LIB='passive',
 CDS_PART_NAME='CAPACITOR-G107-0F106-EM,10UF,2A',
 TOLERANCE='20%',
 CLS_PN='G107-0F106-EM',
 VOLTAGE='25V',
 VALUE='10UF',
 PRIM_FILE='./archive_libs/passive/capacitor/chips/chips.prt';

PART_NAME
 C229 'CAPACITOR-G105-0B104-CK,0.1UF,A':;

SECTION_NUMBER 1
 '@TIMECARD_LIB.TIMECARD(SCH_1):PAGE515_I87@PASSIVE.CAPACITOR(CHIPS)':
 C_PATH='@timecard_lib.timecard(sch_1):page515_i87@passive.capacitor(chips)',
 P_PATH='@timecard_lib.timecard(sch_1):page31_i87@passive.capacitor(chips)',
 PATH='I87',
 DRAWING='@TIMECARD_LIB.TIMECARD(SCH_1):PAGE515',
 PACKAGE='0402',
 PHYS_PAGE='31',
 XY='(-9200,6250)',
 ROT='0',
 VER='2',
 CDS_LIB='passive',
 CDS_PART_NAME='CAPACITOR-G105-0B104-CK,0.1UF,A',
 TOLERANCE='10%',
 CLS_PN='G105-0B104-CK',
 VOLTAGE='10V',
 VALUE='0.1UF',
 PRIM_FILE='./archive_libs/passive/capacitor/chips/chips.prt';

PART_NAME
 C230 'CAPACITOR-G105-0B104-EK,0.1UF,A':;

SECTION_NUMBER 1
 '@TIMECARD_LIB.TIMECARD(SCH_1):PAGE515_I134@PASSIVE.CAPACITOR(CHIPS)':
 C_PATH='@timecard_lib.timecard(sch_1):page515_i134@passive.capacitor(chips)',
 P_PATH='@timecard_lib.timecard(sch_1):page31_i134@passive.capacitor(chips)',
 PATH='I134',
 DRAWING='@TIMECARD_LIB.TIMECARD(SCH_1):PAGE515',
 PACKAGE='0402',
 PHYS_PAGE='31',
 XY='(-8850,1850)',
 ROT='0',
 VER='2',
 CDS_LIB='passive',
 CDS_PART_NAME='CAPACITOR-G105-0B104-EK,0.1UF,A',
 TOLERANCE='10%',
 CLS_PN='G105-0B104-EK',
 VOLTAGE='25V',
 VALUE='0.1UF',
 PRIM_FILE='./archive_libs/passive/capacitor/chips/chips.prt';

PART_NAME
 C231 'CAPACITOR-G104-0B103-EK,0.01UFA':;

SECTION_NUMBER 1
 '@TIMECARD_LIB.TIMECARD(SCH_1):PAGE515_I132@PASSIVE.CAPACITOR(CHIPS)':
 C_PATH='@timecard_lib.timecard(sch_1):page515_i132@passive.capacitor(chips)',
 P_PATH='@timecard_lib.timecard(sch_1):page31_i132@passive.capacitor(chips)',
 PATH='I132',
 DRAWING='@TIMECARD_LIB.TIMECARD(SCH_1):PAGE515',
 PACKAGE='0201',
 PHYS_PAGE='31',
 XY='(-8750,650)',
 ROT='0',
 VER='2',
 CDS_LIB='passive',
 CDS_PART_NAME='CAPACITOR-G104-0B103-EK,0.01UFA',
 TOLERANCE='10%',
 CLS_PN='G104-0B103-EK',
 VOLTAGE='25V',
 VALUE='0.01UF',
 PRIM_FILE='./archive_libs/passive/capacitor/chips/chips.prt';

PART_NAME
 C232 'CAPACITOR-G107-0F226-CM,22UF,2A':;

SECTION_NUMBER 1
 '@TIMECARD_LIB.TIMECARD(SCH_1):PAGE515_I61@PASSIVE.CAPACITOR(CHIPS)':
 C_PATH='@timecard_lib.timecard(sch_1):page515_i61@passive.capacitor(chips)',
 P_PATH='@timecard_lib.timecard(sch_1):page31_i61@passive.capacitor(chips)',
 PATH='I61',
 DRAWING='@TIMECARD_LIB.TIMECARD(SCH_1):PAGE515',
 PACKAGE='0805',
 PHYS_PAGE='31',
 XY='(-7800,5400)',
 ROT='0',
 VER='2',
 CDS_LIB='passive',
 CDS_PART_NAME='CAPACITOR-G107-0F226-CM,22UF,2A',
 TOLERANCE='20%',
 CLS_PN='G107-0F226-CM',
 VOLTAGE='10V',
 VALUE='22UF',
 PRIM_FILE='./archive_libs/passive/capacitor/chips/chips.prt';

PART_NAME
 C233 'CAPACITOR-G105-0B104-CK,0.1UF,A':;

SECTION_NUMBER 1
 '@TIMECARD_LIB.TIMECARD(SCH_1):PAGE515_I63@PASSIVE.CAPACITOR(CHIPS)':
 C_PATH='@timecard_lib.timecard(sch_1):page515_i63@passive.capacitor(chips)',
 P_PATH='@timecard_lib.timecard(sch_1):page31_i63@passive.capacitor(chips)',
 PATH='I63',
 DRAWING='@TIMECARD_LIB.TIMECARD(SCH_1):PAGE515',
 PACKAGE='0402',
 PHYS_PAGE='31',
 XY='(-7250,5450)',
 ROT='0',
 VER='2',
 CDS_LIB='passive',
 CDS_PART_NAME='CAPACITOR-G105-0B104-CK,0.1UF,A',
 TOLERANCE='10%',
 CLS_PN='G105-0B104-CK',
 VOLTAGE='10V',
 VALUE='0.1UF',
 PRIM_FILE='./archive_libs/passive/capacitor/chips/chips.prt';

PART_NAME
 C234 'CAPACITOR-G104-0B103-EK,0.01UFA':;

SECTION_NUMBER 1
 '@TIMECARD_LIB.TIMECARD(SCH_1):PAGE515_I138@PASSIVE.CAPACITOR(CHIPS)':
 C_PATH='@timecard_lib.timecard(sch_1):page515_i138@passive.capacitor(chips)',
 P_PATH='@timecard_lib.timecard(sch_1):page31_i138@passive.capacitor(chips)',
 PATH='I138',
 DRAWING='@TIMECARD_LIB.TIMECARD(SCH_1):PAGE515',
 PACKAGE='0201',
 PHYS_PAGE='31',
 XY='(-5800,50)',
 ROT='0',
 VER='2',
 CDS_LIB='passive',
 CDS_PART_NAME='CAPACITOR-G104-0B103-EK,0.01UFA',
 TOLERANCE='10%',
 CLS_PN='G104-0B103-EK',
 VOLTAGE='25V',
 VALUE='0.01UF',
 PRIM_FILE='./archive_libs/passive/capacitor/chips/chips.prt';

PART_NAME
 C235 'CAPACITOR-G105-0B104-CK,0.1UF,A':;

SECTION_NUMBER 1
 '@TIMECARD_LIB.TIMECARD(SCH_1):PAGE515_I80@PASSIVE.CAPACITOR(CHIPS)':
 C_PATH='@timecard_lib.timecard(sch_1):page515_i80@passive.capacitor(chips)',
 P_PATH='@timecard_lib.timecard(sch_1):page31_i80@passive.capacitor(chips)',
 PATH='I80',
 DRAWING='@TIMECARD_LIB.TIMECARD(SCH_1):PAGE515',
 PACKAGE='0402',
 PHYS_PAGE='31',
 XY='(-5000,4850)',
 ROT='0',
 VER='2',
 CDS_LIB='passive',
 CDS_PART_NAME='CAPACITOR-G105-0B104-CK,0.1UF,A',
 TOLERANCE='10%',
 CLS_PN='G105-0B104-CK',
 VOLTAGE='10V',
 VALUE='0.1UF',
 PRIM_FILE='./archive_libs/passive/capacitor/chips/chips.prt';

PART_NAME
 C236 'CAPACITOR-G105-0B104-EK,0.1UF,A':;

SECTION_NUMBER 1
 '@TIMECARD_LIB.TIMECARD(SCH_1):PAGE515_I66@PASSIVE.CAPACITOR(CHIPS)':
 C_PATH='@timecard_lib.timecard(sch_1):page515_i66@passive.capacitor(chips)',
 P_PATH='@timecard_lib.timecard(sch_1):page31_i66@passive.capacitor(chips)',
 PATH='I66',
 DRAWING='@TIMECARD_LIB.TIMECARD(SCH_1):PAGE515',
 PACKAGE='0402',
 PHYS_PAGE='31',
 XY='(-4400,6400)',
 ROT='0',
 VER='2',
 CDS_LIB='passive',
 CDS_PART_NAME='CAPACITOR-G105-0B104-EK,0.1UF,A',
 TOLERANCE='10%',
 CLS_PN='G105-0B104-EK',
 VOLTAGE='25V',
 VALUE='0.1UF',
 PRIM_FILE='./archive_libs/passive/capacitor/chips/chips.prt';

PART_NAME
 C237 'CAPACITOR-G105-0B104-CK,0.1UF,A':;

SECTION_NUMBER 1
 '@TIMECARD_LIB.TIMECARD(SCH_1):PAGE515_I64@PASSIVE.CAPACITOR(CHIPS)':
 C_PATH='@timecard_lib.timecard(sch_1):page515_i64@passive.capacitor(chips)',
 P_PATH='@timecard_lib.timecard(sch_1):page31_i64@passive.capacitor(chips)',
 PATH='I64',
 DRAWING='@TIMECARD_LIB.TIMECARD(SCH_1):PAGE515',
 PACKAGE='0402',
 PHYS_PAGE='31',
 XY='(-4150,5400)',
 ROT='0',
 VER='2',
 CDS_LIB='passive',
 CDS_PART_NAME='CAPACITOR-G105-0B104-CK,0.1UF,A',
 TOLERANCE='10%',
 CLS_PN='G105-0B104-CK',
 VOLTAGE='10V',
 VALUE='0.1UF',
 PRIM_FILE='./archive_libs/passive/capacitor/chips/chips.prt';

PART_NAME
 C238 'CAPACITOR-G107-0F226-CM,22UF,2A':;

SECTION_NUMBER 1
 '@TIMECARD_LIB.TIMECARD(SCH_1):PAGE515_I81@PASSIVE.CAPACITOR(CHIPS)':
 C_PATH='@timecard_lib.timecard(sch_1):page515_i81@passive.capacitor(chips)',
 P_PATH='@timecard_lib.timecard(sch_1):page31_i81@passive.capacitor(chips)',
 PATH='I81',
 DRAWING='@TIMECARD_LIB.TIMECARD(SCH_1):PAGE515',
 PACKAGE='0805',
 PHYS_PAGE='31',
 XY='(-3650,5400)',
 ROT='0',
 VER='2',
 CDS_LIB='passive',
 CDS_PART_NAME='CAPACITOR-G107-0F226-CM,22UF,2A',
 NO_ASSY='TRUE',
 TOLERANCE='20%',
 CLS_PN='G107-0F226-CM',
 VOLTAGE='10V',
 VALUE='22UF',
 PRIM_FILE='./archive_libs/passive/capacitor/chips/chips.prt';

PART_NAME
 C239 'CAPACITOR-G107-0F106-EM,10UF,2A':;

SECTION_NUMBER 1
 '@TIMECARD_LIB.TIMECARD(SCH_1):PAGE515_I147@PASSIVE.CAPACITOR(CHIPS)':
 C_PATH='@timecard_lib.timecard(sch_1):page515_i147@passive.capacitor(chips)',
 P_PATH='@timecard_lib.timecard(sch_1):page31_i147@passive.capacitor(chips)',
 PATH='I147',
 DRAWING='@TIMECARD_LIB.TIMECARD(SCH_1):PAGE515',
 PACKAGE='0805',
 PHYS_PAGE='31',
 XY='(-3800,1750)',
 ROT='0',
 VER='2',
 CDS_LIB='passive',
 CDS_PART_NAME='CAPACITOR-G107-0F106-EM,10UF,2A',
 TOLERANCE='20%',
 CLS_PN='G107-0F106-EM',
 VOLTAGE='25V',
 VALUE='10UF',
 PRIM_FILE='./archive_libs/passive/capacitor/chips/chips.prt';

PART_NAME
 C240 'CAPACITOR-G107-0F226-CM,22UF,2A':;

SECTION_NUMBER 1
 '@TIMECARD_LIB.TIMECARD(SCH_1):PAGE515_I71@PASSIVE.CAPACITOR(CHIPS)':
 C_PATH='@timecard_lib.timecard(sch_1):page515_i71@passive.capacitor(chips)',
 P_PATH='@timecard_lib.timecard(sch_1):page31_i71@passive.capacitor(chips)',
 PATH='I71',
 DRAWING='@TIMECARD_LIB.TIMECARD(SCH_1):PAGE515',
 PACKAGE='0805',
 PHYS_PAGE='31',
 XY='(-3100,5400)',
 ROT='0',
 VER='2',
 CDS_LIB='passive',
 CDS_PART_NAME='CAPACITOR-G107-0F226-CM,22UF,2A',
 NO_ASSY='TRUE',
 TOLERANCE='20%',
 CLS_PN='G107-0F226-CM',
 VOLTAGE='10V',
 VALUE='22UF',
 PRIM_FILE='./archive_libs/passive/capacitor/chips/chips.prt';

PART_NAME
 C241 'CAPACITOR-G107-0F226-CM,22UF,2A':;

SECTION_NUMBER 1
 '@TIMECARD_LIB.TIMECARD(SCH_1):PAGE515_I72@PASSIVE.CAPACITOR(CHIPS)':
 C_PATH='@timecard_lib.timecard(sch_1):page515_i72@passive.capacitor(chips)',
 P_PATH='@timecard_lib.timecard(sch_1):page31_i72@passive.capacitor(chips)',
 PATH='I72',
 DRAWING='@TIMECARD_LIB.TIMECARD(SCH_1):PAGE515',
 PACKAGE='0805',
 PHYS_PAGE='31',
 XY='(-2650,5400)',
 ROT='0',
 VER='2',
 CDS_LIB='passive',
 CDS_PART_NAME='CAPACITOR-G107-0F226-CM,22UF,2A',
 TOLERANCE='20%',
 CLS_PN='G107-0F226-CM',
 VOLTAGE='10V',
 VALUE='22UF',
 PRIM_FILE='./archive_libs/passive/capacitor/chips/chips.prt';

PART_NAME
 C242 'CAPACITOR-G105-0B104-EK,0.1UF,A':;

SECTION_NUMBER 1
 '@TIMECARD_LIB.TIMECARD(SCH_1):PAGE515_I149@PASSIVE.CAPACITOR(CHIPS)':
 C_PATH='@timecard_lib.timecard(sch_1):page515_i149@passive.capacitor(chips)',
 P_PATH='@timecard_lib.timecard(sch_1):page31_i149@passive.capacitor(chips)',
 PATH='I149',
 DRAWING='@TIMECARD_LIB.TIMECARD(SCH_1):PAGE515',
 PACKAGE='0805',
 PHYS_PAGE='31',
 XY='(-3200,1750)',
 ROT='0',
 VER='2',
 CDS_LIB='passive',
 CDS_PART_NAME='CAPACITOR-G105-0B104-EK,0.1UF,A',
 TOLERANCE='10%',
 CLS_PN='G105-0B104-EK',
 VOLTAGE='25V',
 VALUE='0.1UF',
 PRIM_FILE='./archive_libs/passive/capacitor/chips/chips.prt';

PART_NAME
 C243 'CAPACITOR-G107-0F226-CM,22UF,2A':;

SECTION_NUMBER 1
 '@TIMECARD_LIB.TIMECARD(SCH_1):PAGE515_I74@PASSIVE.CAPACITOR(CHIPS)':
 C_PATH='@timecard_lib.timecard(sch_1):page515_i74@passive.capacitor(chips)',
 P_PATH='@timecard_lib.timecard(sch_1):page31_i74@passive.capacitor(chips)',
 PATH='I74',
 DRAWING='@TIMECARD_LIB.TIMECARD(SCH_1):PAGE515',
 PACKAGE='0805',
 PHYS_PAGE='31',
 XY='(-2200,5400)',
 ROT='0',
 VER='2',
 CDS_LIB='passive',
 CDS_PART_NAME='CAPACITOR-G107-0F226-CM,22UF,2A',
 TOLERANCE='20%',
 CLS_PN='G107-0F226-CM',
 VOLTAGE='10V',
 VALUE='22UF',
 PRIM_FILE='./archive_libs/passive/capacitor/chips/chips.prt';

PART_NAME
 C244 'CAPACITOR-G105-0B104-EK,0.1UF,A':;

SECTION_NUMBER 1
 '@TIMECARD_LIB.TIMECARD(SCH_1):PAGE522_I152@PASSIVE.CAPACITOR(CHIPS)':
 C_PATH='@timecard_lib.timecard(sch_1):page522_i152@passive.capacitor(chips)',
 P_PATH='@timecard_lib.timecard(sch_1):page15_i152@passive.capacitor(chips)',
 PATH='I152',
 DRAWING='@TIMECARD_LIB.TIMECARD(SCH_1):PAGE522',
 PACKAGE='0402',
 PHYS_PAGE='15',
 XY='(-11650,6350)',
 ROT='2',
 VER='2',
 CDS_LIB='passive',
 CDS_PART_NAME='CAPACITOR-G105-0B104-EK,0.1UF,A',
 TOLERANCE='10%',
 CLS_PN='G105-0B104-EK',
 VOLTAGE='25V',
 VALUE='0.1UF',
 PRIM_FILE='./archive_libs/passive/capacitor/chips/chips.prt';

PART_NAME
 C245 'CAPACITOR-G105-0B104-EK,0.1UF,A':;

SECTION_NUMBER 1
 '@TIMECARD_LIB.TIMECARD(SCH_1):PAGE522_I153@PASSIVE.CAPACITOR(CHIPS)':
 C_PATH='@timecard_lib.timecard(sch_1):page522_i153@passive.capacitor(chips)',
 P_PATH='@timecard_lib.timecard(sch_1):page15_i153@passive.capacitor(chips)',
 PATH='I153',
 DRAWING='@TIMECARD_LIB.TIMECARD(SCH_1):PAGE522',
 PACKAGE='0402',
 PHYS_PAGE='15',
 XY='(-11650,2800)',
 ROT='2',
 VER='2',
 CDS_LIB='passive',
 CDS_PART_NAME='CAPACITOR-G105-0B104-EK,0.1UF,A',
 TOLERANCE='10%',
 CLS_PN='G105-0B104-EK',
 VOLTAGE='25V',
 VALUE='0.1UF',
 PRIM_FILE='./archive_libs/passive/capacitor/chips/chips.prt';

PART_NAME
 C246 'CAPACITOR-G105-0C106-BM,10UF,2A':;

SECTION_NUMBER 1
 '@TIMECARD_LIB.TIMECARD(SCH_1):PAGE522_I151@PASSIVE.CAPACITOR(CHIPS)':
 C_PATH='@timecard_lib.timecard(sch_1):page522_i151@passive.capacitor(chips)',
 P_PATH='@timecard_lib.timecard(sch_1):page15_i151@passive.capacitor(chips)',
 PATH='I151',
 DRAWING='@TIMECARD_LIB.TIMECARD(SCH_1):PAGE522',
 PACKAGE='0402',
 PHYS_PAGE='15',
 XY='(-10650,6350)',
 ROT='2',
 VER='2',
 CDS_LIB='passive',
 CDS_PART_NAME='CAPACITOR-G105-0C106-BM,10UF,2A',
 TOLERANCE='20%',
 CLS_PN='G105-0C106-BM',
 VOLTAGE='6.3V',
 VALUE='10UF',
 PRIM_FILE='./archive_libs/passive/capacitor/chips/chips.prt';

PART_NAME
 C247 'CAPACITOR-G105-0C106-BM,10UF,2A':;

SECTION_NUMBER 1
 '@TIMECARD_LIB.TIMECARD(SCH_1):PAGE522_I154@PASSIVE.CAPACITOR(CHIPS)':
 C_PATH='@timecard_lib.timecard(sch_1):page522_i154@passive.capacitor(chips)',
 P_PATH='@timecard_lib.timecard(sch_1):page15_i154@passive.capacitor(chips)',
 PATH='I154',
 DRAWING='@TIMECARD_LIB.TIMECARD(SCH_1):PAGE522',
 PACKAGE='0402',
 PHYS_PAGE='15',
 XY='(-10650,2800)',
 ROT='2',
 VER='2',
 CDS_LIB='passive',
 CDS_PART_NAME='CAPACITOR-G105-0C106-BM,10UF,2A',
 TOLERANCE='20%',
 CLS_PN='G105-0C106-BM',
 VOLTAGE='6.3V',
 VALUE='10UF',
 PRIM_FILE='./archive_libs/passive/capacitor/chips/chips.prt';

PART_NAME
 C248 'CAPACITOR-G105-0B104-EK,0.1UF,A':;

SECTION_NUMBER 1
 '@TIMECARD_LIB.TIMECARD(SCH_1):PAGE522_I147@PASSIVE.CAPACITOR(CHIPS)':
 C_PATH='@timecard_lib.timecard(sch_1):page522_i147@passive.capacitor(chips)',
 P_PATH='@timecard_lib.timecard(sch_1):page15_i147@passive.capacitor(chips)',
 PATH='I147',
 DRAWING='@TIMECARD_LIB.TIMECARD(SCH_1):PAGE522',
 PACKAGE='0402',
 PHYS_PAGE='15',
 XY='(-10200,6350)',
 ROT='2',
 VER='2',
 CDS_LIB='passive',
 CDS_PART_NAME='CAPACITOR-G105-0B104-EK,0.1UF,A',
 TOLERANCE='10%',
 CLS_PN='G105-0B104-EK',
 VOLTAGE='25V',
 VALUE='0.1UF',
 PRIM_FILE='./archive_libs/passive/capacitor/chips/chips.prt';

PART_NAME
 C249 'CAPACITOR-G105-0B104-EK,0.1UF,A':;

SECTION_NUMBER 1
 '@TIMECARD_LIB.TIMECARD(SCH_1):PAGE522_I158@PASSIVE.CAPACITOR(CHIPS)':
 C_PATH='@timecard_lib.timecard(sch_1):page522_i158@passive.capacitor(chips)',
 P_PATH='@timecard_lib.timecard(sch_1):page15_i158@passive.capacitor(chips)',
 PATH='I158',
 DRAWING='@TIMECARD_LIB.TIMECARD(SCH_1):PAGE522',
 PACKAGE='0402',
 PHYS_PAGE='15',
 XY='(-10200,2820)',
 ROT='2',
 VER='2',
 CDS_LIB='passive',
 CDS_PART_NAME='CAPACITOR-G105-0B104-EK,0.1UF,A',
 TOLERANCE='10%',
 CLS_PN='G105-0B104-EK',
 VOLTAGE='25V',
 VALUE='0.1UF',
 PRIM_FILE='./archive_libs/passive/capacitor/chips/chips.prt';

PART_NAME
 C250 'CAPACITOR-G105-0B104-EK,0.1UF,A':;

SECTION_NUMBER 1
 '@TIMECARD_LIB.TIMECARD(SCH_1):PAGE3_I152@PASSIVE.CAPACITOR(CHIPS)':
 C_PATH='@timecard_lib.timecard(sch_1):page3_i152@passive.capacitor(chips)',
 P_PATH='@timecard_lib.timecard(sch_1):page9_i152@passive.capacitor(chips)',
 PATH='I152',
 DRAWING='@TIMECARD_LIB.TIMECARD(SCH_1):PAGE3',
 PACKAGE='0402',
 PHYS_PAGE='9',
 XY='(650,3350)',
 ROT='2',
 VER='2',
 CDS_LIB='passive',
 CDS_PART_NAME='CAPACITOR-G105-0B104-EK,0.1UF,A',
 TOLERANCE='10%',
 CLS_PN='G105-0B104-EK',
 VOLTAGE='25V',
 VALUE='0.1UF',
 PRIM_FILE='./archive_libs/passive/capacitor/chips/chips.prt';

PART_NAME
 C251 'CAPACITOR-G105-0B104-CK,0.1UF,A':;

SECTION_NUMBER 1
 '@TIMECARD_LIB.TIMECARD(SCH_1):PAGE522_I161@PASSIVE.CAPACITOR(CHIPS)':
 C_PATH='@timecard_lib.timecard(sch_1):page522_i161@passive.capacitor(chips)',
 P_PATH='@timecard_lib.timecard(sch_1):page15_i161@passive.capacitor(chips)',
 PATH='I161',
 DRAWING='@TIMECARD_LIB.TIMECARD(SCH_1):PAGE522',
 PACKAGE='0402',
 PHYS_PAGE='15',
 XY='(-6150,6650)',
 ROT='0',
 VER='1',
 CDS_LIB='passive',
 CDS_PART_NAME='CAPACITOR-G105-0B104-CK,0.1UF,A',
 TOLERANCE='10%',
 CLS_PN='G105-0B104-CK',
 VOLTAGE='10V',
 VALUE='0.1UF',
 PRIM_FILE='./archive_libs/passive/capacitor/chips/chips.prt';

PART_NAME
 C252 'CAPACITOR-G105-0B104-CK,0.1UF,A':;

SECTION_NUMBER 1
 '@TIMECARD_LIB.TIMECARD(SCH_1):PAGE522_I160@PASSIVE.CAPACITOR(CHIPS)':
 C_PATH='@timecard_lib.timecard(sch_1):page522_i160@passive.capacitor(chips)',
 P_PATH='@timecard_lib.timecard(sch_1):page15_i160@passive.capacitor(chips)',
 PATH='I160',
 DRAWING='@TIMECARD_LIB.TIMECARD(SCH_1):PAGE522',
 PACKAGE='0402',
 PHYS_PAGE='15',
 XY='(-6150,6550)',
 ROT='0',
 VER='1',
 CDS_LIB='passive',
 CDS_PART_NAME='CAPACITOR-G105-0B104-CK,0.1UF,A',
 TOLERANCE='10%',
 CLS_PN='G105-0B104-CK',
 VOLTAGE='10V',
 VALUE='0.1UF',
 PRIM_FILE='./archive_libs/passive/capacitor/chips/chips.prt';

PART_NAME
 C253 'CAPACITOR-G105-0B104-CK,0.1UF,A':;

SECTION_NUMBER 1
 '@TIMECARD_LIB.TIMECARD(SCH_1):PAGE522_I143@PASSIVE.CAPACITOR(CHIPS)':
 C_PATH='@timecard_lib.timecard(sch_1):page522_i143@passive.capacitor(chips)',
 P_PATH='@timecard_lib.timecard(sch_1):page15_i143@passive.capacitor(chips)',
 PATH='I143',
 DRAWING='@TIMECARD_LIB.TIMECARD(SCH_1):PAGE522',
 PACKAGE='0402',
 PHYS_PAGE='15',
 XY='(-6200,3100)',
 ROT='0',
 VER='1',
 CDS_LIB='passive',
 CDS_PART_NAME='CAPACITOR-G105-0B104-CK,0.1UF,A',
 TOLERANCE='10%',
 CLS_PN='G105-0B104-CK',
 VOLTAGE='10V',
 VALUE='0.1UF',
 PRIM_FILE='./archive_libs/passive/capacitor/chips/chips.prt';

PART_NAME
 C254 'CAPACITOR-G105-0B104-CK,0.1UF,A':;

SECTION_NUMBER 1
 '@TIMECARD_LIB.TIMECARD(SCH_1):PAGE522_I142@PASSIVE.CAPACITOR(CHIPS)':
 C_PATH='@timecard_lib.timecard(sch_1):page522_i142@passive.capacitor(chips)',
 P_PATH='@timecard_lib.timecard(sch_1):page15_i142@passive.capacitor(chips)',
 PATH='I142',
 DRAWING='@TIMECARD_LIB.TIMECARD(SCH_1):PAGE522',
 PACKAGE='0402',
 PHYS_PAGE='15',
 XY='(-6200,3000)',
 ROT='0',
 VER='1',
 CDS_LIB='passive',
 CDS_PART_NAME='CAPACITOR-G105-0B104-CK,0.1UF,A',
 TOLERANCE='10%',
 CLS_PN='G105-0B104-CK',
 VOLTAGE='10V',
 VALUE='0.1UF',
 PRIM_FILE='./archive_libs/passive/capacitor/chips/chips.prt';

PART_NAME
 C255 'CAPACITOR-G105-0B104-EK,0.1UF,A':;

SECTION_NUMBER 1
 '@TIMECARD_LIB.TIMECARD(SCH_1):PAGE523_I46@PASSIVE.CAPACITOR(CHIPS)':
 C_PATH='@timecard_lib.timecard(sch_1):page523_i46@passive.capacitor(chips)',
 P_PATH='@timecard_lib.timecard(sch_1):page29_i46@passive.capacitor(chips)',
 PATH='I46',
 DRAWING='@TIMECARD_LIB.TIMECARD(SCH_1):PAGE523',
 PACKAGE='0402',
 PHYS_PAGE='29',
 XY='(-13050,5250)',
 ROT='0',
 VER='2',
 CDS_LIB='passive',
 CDS_PART_NAME='CAPACITOR-G105-0B104-EK,0.1UF,A',
 TOLERANCE='10%',
 CLS_PN='G105-0B104-EK',
 VOLTAGE='25V',
 VALUE='0.1UF',
 PRIM_FILE='./archive_libs/passive/capacitor/chips/chips.prt';

PART_NAME
 C256 'CAPACITOR-G105-0B104-CK,0.1UF,A':;

SECTION_NUMBER 1
 '@TIMECARD_LIB.TIMECARD(SCH_1):PAGE523_I7@PASSIVE.CAPACITOR(CHIPS)':
 C_PATH='@timecard_lib.timecard(sch_1):page523_i7@passive.capacitor(chips)',
 P_PATH='@timecard_lib.timecard(sch_1):page29_i7@passive.capacitor(chips)',
 PATH='I7',
 DRAWING='@TIMECARD_LIB.TIMECARD(SCH_1):PAGE523',
 PACKAGE='0402',
 PHYS_PAGE='29',
 XY='(-11800,3850)',
 ROT='0',
 VER='2',
 CDS_LIB='passive',
 CDS_PART_NAME='CAPACITOR-G105-0B104-CK,0.1UF,A',
 TOLERANCE='10%',
 CLS_PN='G105-0B104-CK',
 VOLTAGE='10V',
 VALUE='0.1UF',
 PRIM_FILE='./archive_libs/passive/capacitor/chips/chips.prt';

PART_NAME
 C257 'CAPACITOR-G107-0F106-EM,10UF,2A':;

SECTION_NUMBER 1
 '@TIMECARD_LIB.TIMECARD(SCH_1):PAGE523_I13@PASSIVE.CAPACITOR(CHIPS)':
 C_PATH='@timecard_lib.timecard(sch_1):page523_i13@passive.capacitor(chips)',
 P_PATH='@timecard_lib.timecard(sch_1):page29_i13@passive.capacitor(chips)',
 PATH='I13',
 DRAWING='@TIMECARD_LIB.TIMECARD(SCH_1):PAGE523',
 PACKAGE='0805',
 PHYS_PAGE='29',
 XY='(-11450,5200)',
 ROT='0',
 VER='2',
 CDS_LIB='passive',
 CDS_PART_NAME='CAPACITOR-G107-0F106-EM,10UF,2A',
 TOLERANCE='20%',
 CLS_PN='G107-0F106-EM',
 VOLTAGE='25V',
 VALUE='10UF',
 PRIM_FILE='./archive_libs/passive/capacitor/chips/chips.prt';

PART_NAME
 C258 'CAPACITOR-G104-0B103-EK,0.01UFA':;

SECTION_NUMBER 1
 '@TIMECARD_LIB.TIMECARD(SCH_1):PAGE523_I50@PASSIVE.CAPACITOR(CHIPS)':
 C_PATH='@timecard_lib.timecard(sch_1):page523_i50@passive.capacitor(chips)',
 P_PATH='@timecard_lib.timecard(sch_1):page29_i50@passive.capacitor(chips)',
 PATH='I50',
 DRAWING='@TIMECARD_LIB.TIMECARD(SCH_1):PAGE523',
 PACKAGE='0402',
 PHYS_PAGE='29',
 XY='(-11550,2600)',
 ROT='1',
 VER='1',
 CDS_LIB='passive',
 CDS_PART_NAME='CAPACITOR-G104-0B103-EK,0.01UFA',
 TOLERANCE='10%',
 CLS_PN='G104-0B103-EK',
 VOLTAGE='25V',
 VALUE='0.01UF',
 PRIM_FILE='./archive_libs/passive/capacitor/chips/chips.prt';

PART_NAME
 C259 'CAPACITOR-G105-0B223-EK,0.022UA':;

SECTION_NUMBER 1
 '@TIMECARD_LIB.TIMECARD(SCH_1):PAGE523_I12@PASSIVE.CAPACITOR(CHIPS)':
 C_PATH='@timecard_lib.timecard(sch_1):page523_i12@passive.capacitor(chips)',
 P_PATH='@timecard_lib.timecard(sch_1):page29_i12@passive.capacitor(chips)',
 PATH='I12',
 DRAWING='@TIMECARD_LIB.TIMECARD(SCH_1):PAGE523',
 PACKAGE='0402',
 PHYS_PAGE='29',
 XY='(-11050,3350)',
 ROT='0',
 VER='2',
 CDS_LIB='passive',
 CDS_PART_NAME='CAPACITOR-G105-0B223-EK,0.022UA',
 TOLERANCE='10%',
 CLS_PN='G105-0B223-EK',
 VOLTAGE='25V',
 VALUE='0.022UF',
 PRIM_FILE='./archive_libs/passive/capacitor/chips/chips.prt';

PART_NAME
 C260 'CAPACITOR-G107-0F106-EM,10UF,2A':;

SECTION_NUMBER 1
 '@TIMECARD_LIB.TIMECARD(SCH_1):PAGE523_I14@PASSIVE.CAPACITOR(CHIPS)':
 C_PATH='@timecard_lib.timecard(sch_1):page523_i14@passive.capacitor(chips)',
 P_PATH='@timecard_lib.timecard(sch_1):page29_i14@passive.capacitor(chips)',
 PATH='I14',
 DRAWING='@TIMECARD_LIB.TIMECARD(SCH_1):PAGE523',
 PACKAGE='0805',
 PHYS_PAGE='29',
 XY='(-11000,5200)',
 ROT='0',
 VER='2',
 CDS_LIB='passive',
 CDS_PART_NAME='CAPACITOR-G107-0F106-EM,10UF,2A',
 TOLERANCE='20%',
 CLS_PN='G107-0F106-EM',
 VOLTAGE='25V',
 VALUE='10UF',
 PRIM_FILE='./archive_libs/passive/capacitor/chips/chips.prt';

PART_NAME
 C261 'CAPACITOR-G105-0B104-EK,0.1UF,A':;

SECTION_NUMBER 1
 '@TIMECARD_LIB.TIMECARD(SCH_1):PAGE523_I17@PASSIVE.CAPACITOR(CHIPS)':
 C_PATH='@timecard_lib.timecard(sch_1):page523_i17@passive.capacitor(chips)',
 P_PATH='@timecard_lib.timecard(sch_1):page29_i17@passive.capacitor(chips)',
 PATH='I17',
 DRAWING='@TIMECARD_LIB.TIMECARD(SCH_1):PAGE523',
 PACKAGE='0402',
 PHYS_PAGE='29',
 XY='(-10550,5200)',
 ROT='0',
 VER='2',
 CDS_LIB='passive',
 CDS_PART_NAME='CAPACITOR-G105-0B104-EK,0.1UF,A',
 TOLERANCE='10%',
 CLS_PN='G105-0B104-EK',
 VOLTAGE='25V',
 VALUE='0.1UF',
 PRIM_FILE='./archive_libs/passive/capacitor/chips/chips.prt';

PART_NAME
 C262 'CAPACITOR-G105-0B104-EK,0.1UF,A':;

SECTION_NUMBER 1
 '@TIMECARD_LIB.TIMECARD(SCH_1):PAGE523_I19@PASSIVE.CAPACITOR(CHIPS)':
 C_PATH='@timecard_lib.timecard(sch_1):page523_i19@passive.capacitor(chips)',
 P_PATH='@timecard_lib.timecard(sch_1):page29_i19@passive.capacitor(chips)',
 PATH='I19',
 DRAWING='@TIMECARD_LIB.TIMECARD(SCH_1):PAGE523',
 PACKAGE='0402',
 PHYS_PAGE='29',
 XY='(-10000,5200)',
 ROT='0',
 VER='2',
 CDS_LIB='passive',
 CDS_PART_NAME='CAPACITOR-G105-0B104-EK,0.1UF,A',
 TOLERANCE='10%',
 CLS_PN='G105-0B104-EK',
 VOLTAGE='25V',
 VALUE='0.1UF',
 PRIM_FILE='./archive_libs/passive/capacitor/chips/chips.prt';

PART_NAME
 C263 'CAPACITOR-G104-0B472-EK,4700PFA':;

SECTION_NUMBER 1
 '@TIMECARD_LIB.TIMECARD(SCH_1):PAGE523_I9@PASSIVE.CAPACITOR(CHIPS)':
 C_PATH='@timecard_lib.timecard(sch_1):page523_i9@passive.capacitor(chips)',
 P_PATH='@timecard_lib.timecard(sch_1):page29_i9@passive.capacitor(chips)',
 PATH='I9',
 DRAWING='@TIMECARD_LIB.TIMECARD(SCH_1):PAGE523',
 PACKAGE='0402',
 PHYS_PAGE='29',
 XY='(-9850,2950)',
 ROT='0',
 VER='2',
 CDS_LIB='passive',
 CDS_PART_NAME='CAPACITOR-G104-0B472-EK,4700PFA',
 TOLERANCE='10%',
 CLS_PN='G104-0B472-EK',
 VOLTAGE='25V',
 VALUE='4700PF',
 PRIM_FILE='./archive_libs/passive/capacitor/chips/chips.prt';

PART_NAME
 C264 'CAPACITOR-G104-0A180-FJ,18PF,5%':;

SECTION_NUMBER 1
 '@TIMECARD_LIB.TIMECARD(SCH_1):PAGE523_I10@PASSIVE.CAPACITOR(CHIPS)':
 C_PATH='@timecard_lib.timecard(sch_1):page523_i10@passive.capacitor(chips)',
 P_PATH='@timecard_lib.timecard(sch_1):page29_i10@passive.capacitor(chips)',
 PATH='I10',
 DRAWING='@TIMECARD_LIB.TIMECARD(SCH_1):PAGE523',
 PACKAGE='0201',
 PHYS_PAGE='29',
 XY='(-9250,3100)',
 ROT='0',
 VER='2',
 CDS_LIB='passive',
 CDS_PART_NAME='CAPACITOR-G104-0A180-FJ,18PF,5%',
 TOLERANCE='5%',
 CLS_PN='G104-0A180-FJ',
 VOLTAGE='25V',
 VALUE='18PF',
 PRIM_FILE='./archive_libs/passive/capacitor/chips/chips.prt';

PART_NAME
 C265 'CAPACITOR-G105-0B104-EK,0.1UF,A':;

SECTION_NUMBER 1
 '@TIMECARD_LIB.TIMECARD(SCH_1):PAGE523_I24@PASSIVE.CAPACITOR(CHIPS)':
 C_PATH='@timecard_lib.timecard(sch_1):page523_i24@passive.capacitor(chips)',
 P_PATH='@timecard_lib.timecard(sch_1):page29_i24@passive.capacitor(chips)',
 PATH='I24',
 DRAWING='@TIMECARD_LIB.TIMECARD(SCH_1):PAGE523',
 PACKAGE='0402',
 PHYS_PAGE='29',
 XY='(-5400,4550)',
 ROT='0',
 VER='1',
 CDS_LIB='passive',
 CDS_PART_NAME='CAPACITOR-G105-0B104-EK,0.1UF,A',
 TOLERANCE='10%',
 CLS_PN='G105-0B104-EK',
 VOLTAGE='25V',
 VALUE='0.1UF',
 PRIM_FILE='./archive_libs/passive/capacitor/chips/chips.prt';

PART_NAME
 C266 'CAPACITOR-G105-0A102-FJ,1000PFA':;

SECTION_NUMBER 1
 '@TIMECARD_LIB.TIMECARD(SCH_1):PAGE523_I31@PASSIVE.CAPACITOR(CHIPS)':
 C_PATH='@timecard_lib.timecard(sch_1):page523_i31@passive.capacitor(chips)',
 P_PATH='@timecard_lib.timecard(sch_1):page29_i31@passive.capacitor(chips)',
 PATH='I31',
 DRAWING='@TIMECARD_LIB.TIMECARD(SCH_1):PAGE523',
 PACKAGE='0402',
 PHYS_PAGE='29',
 XY='(-4150,4700)',
 ROT='0',
 VER='1',
 CDS_LIB='passive',
 CDS_PART_NAME='CAPACITOR-G105-0A102-FJ,1000PFA',
 NO_ASSY='TRUE',
 TOLERANCE='5%',
 CLS_PN='G105-0A102-FJ',
 VOLTAGE='50V',
 VALUE='1000PF',
 PRIM_FILE='./archive_libs/passive/capacitor/chips/chips.prt';

PART_NAME
 C267 'CAPACITOR-G104-0B101-FK,100PF,A':;

SECTION_NUMBER 1
 '@TIMECARD_LIB.TIMECARD(SCH_1):PAGE523_I28@PASSIVE.CAPACITOR(CHIPS)':
 C_PATH='@timecard_lib.timecard(sch_1):page523_i28@passive.capacitor(chips)',
 P_PATH='@timecard_lib.timecard(sch_1):page29_i28@passive.capacitor(chips)',
 PATH='I28',
 DRAWING='@TIMECARD_LIB.TIMECARD(SCH_1):PAGE523',
 PACKAGE='0201',
 PHYS_PAGE='29',
 XY='(-3150,3550)',
 ROT='0',
 VER='2',
 CDS_LIB='passive',
 CDS_PART_NAME='CAPACITOR-G104-0B101-FK,100PF,A',
 TOLERANCE='10%',
 CLS_PN='G104-0B101-FK',
 VALUE='100PF',
 PRIM_FILE='./archive_libs/passive/capacitor/chips/chips.prt';

PART_NAME
 C268 'CAPACITOR-G105-0B104-CK,0.1UF,A':;

SECTION_NUMBER 1
 '@TIMECARD_LIB.TIMECARD(SCH_1):PAGE523_I33@PASSIVE.CAPACITOR(CHIPS)':
 C_PATH='@timecard_lib.timecard(sch_1):page523_i33@passive.capacitor(chips)',
 P_PATH='@timecard_lib.timecard(sch_1):page29_i33@passive.capacitor(chips)',
 PATH='I33',
 DRAWING='@TIMECARD_LIB.TIMECARD(SCH_1):PAGE523',
 PACKAGE='0402',
 PHYS_PAGE='29',
 XY='(-1850,4000)',
 ROT='0',
 VER='2',
 CDS_LIB='passive',
 CDS_PART_NAME='CAPACITOR-G105-0B104-CK,0.1UF,A',
 TOLERANCE='10%',
 CLS_PN='G105-0B104-CK',
 VOLTAGE='10V',
 VALUE='0.1UF',
 PRIM_FILE='./archive_libs/passive/capacitor/chips/chips.prt';

PART_NAME
 C269 'CAPACITOR-G107-0F476-AM,47UF,2A':;

SECTION_NUMBER 1
 '@TIMECARD_LIB.TIMECARD(SCH_1):PAGE523_I34@PASSIVE.CAPACITOR(CHIPS)':
 C_PATH='@timecard_lib.timecard(sch_1):page523_i34@passive.capacitor(chips)',
 P_PATH='@timecard_lib.timecard(sch_1):page29_i34@passive.capacitor(chips)',
 PATH='I34',
 DRAWING='@TIMECARD_LIB.TIMECARD(SCH_1):PAGE523',
 PACKAGE='0805',
 PHYS_PAGE='29',
 XY='(-1350,4000)',
 ROT='0',
 VER='2',
 CDS_LIB='passive',
 CDS_PART_NAME='CAPACITOR-G107-0F476-AM,47UF,2A',
 TOLERANCE='20%',
 CLS_PN='G107-0F476-AM',
 VOLTAGE='4V',
 VALUE='47UF',
 PRIM_FILE='./archive_libs/passive/capacitor/chips/chips.prt';

PART_NAME
 C270 'CAPACITOR-G107-0F476-AM,47UF,2A':;

SECTION_NUMBER 1
 '@TIMECARD_LIB.TIMECARD(SCH_1):PAGE523_I35@PASSIVE.CAPACITOR(CHIPS)':
 C_PATH='@timecard_lib.timecard(sch_1):page523_i35@passive.capacitor(chips)',
 P_PATH='@timecard_lib.timecard(sch_1):page29_i35@passive.capacitor(chips)',
 PATH='I35',
 DRAWING='@TIMECARD_LIB.TIMECARD(SCH_1):PAGE523',
 PACKAGE='0805',
 PHYS_PAGE='29',
 XY='(-850,4000)',
 ROT='0',
 VER='2',
 CDS_LIB='passive',
 CDS_PART_NAME='CAPACITOR-G107-0F476-AM,47UF,2A',
 TOLERANCE='20%',
 CLS_PN='G107-0F476-AM',
 VOLTAGE='4V',
 VALUE='47UF',
 PRIM_FILE='./archive_libs/passive/capacitor/chips/chips.prt';

PART_NAME
 C271 'CAPACITOR-G107-0F476-AM,47UF,2A':;

SECTION_NUMBER 1
 '@TIMECARD_LIB.TIMECARD(SCH_1):PAGE523_I37@PASSIVE.CAPACITOR(CHIPS)':
 C_PATH='@timecard_lib.timecard(sch_1):page523_i37@passive.capacitor(chips)',
 P_PATH='@timecard_lib.timecard(sch_1):page29_i37@passive.capacitor(chips)',
 PATH='I37',
 DRAWING='@TIMECARD_LIB.TIMECARD(SCH_1):PAGE523',
 PACKAGE='0805',
 PHYS_PAGE='29',
 XY='(-400,4000)',
 ROT='0',
 VER='2',
 CDS_LIB='passive',
 CDS_PART_NAME='CAPACITOR-G107-0F476-AM,47UF,2A',
 TOLERANCE='20%',
 CLS_PN='G107-0F476-AM',
 VOLTAGE='4V',
 VALUE='47UF',
 PRIM_FILE='./archive_libs/passive/capacitor/chips/chips.prt';

PART_NAME
 C272 'CAPACITOR-G105-0B104-EK,0.1UF,A':;

SECTION_NUMBER 1
 '@TIMECARD_LIB.TIMECARD(SCH_1):PAGE11_I44@PASSIVE.CAPACITOR(CHIPS)':
 C_PATH='@timecard_lib.timecard(sch_1):page11_i44@passive.capacitor(chips)',
 P_PATH='@timecard_lib.timecard(sch_1):page22_i44@passive.capacitor(chips)',
 PATH='I44',
 DRAWING='@TIMECARD_LIB.TIMECARD(SCH_1):PAGE11',
 PACKAGE='0402',
 PHYS_PAGE='22',
 XY='(-6850,6950)',
 ROT='3',
 VER='1',
 CDS_LIB='passive',
 CDS_PART_NAME='CAPACITOR-G105-0B104-EK,0.1UF,A',
 TOLERANCE='10%',
 CLS_PN='G105-0B104-EK',
 VOLTAGE='25V',
 VALUE='0.1UF',
 PRIM_FILE='./archive_libs/passive/capacitor/chips/chips.prt';

PART_NAME
 C273 'CAPACITOR-G105-0B104-CK,0.1UF,A':;

SECTION_NUMBER 1
 '@TIMECARD_LIB.TIMECARD(SCH_1):PAGE11_I45@PASSIVE.CAPACITOR(CHIPS)':
 C_PATH='@timecard_lib.timecard(sch_1):page11_i45@passive.capacitor(chips)',
 P_PATH='@timecard_lib.timecard(sch_1):page22_i45@passive.capacitor(chips)',
 PATH='I45',
 DRAWING='@TIMECARD_LIB.TIMECARD(SCH_1):PAGE11',
 PACKAGE='0402',
 PHYS_PAGE='22',
 XY='(-2600,6850)',
 ROT='3',
 VER='1',
 CDS_LIB='passive',
 CDS_PART_NAME='CAPACITOR-G105-0B104-CK,0.1UF,A',
 TOLERANCE='10%',
 CLS_PN='G105-0B104-CK',
 VOLTAGE='10V',
 VALUE='0.1UF',
 PRIM_FILE='./archive_libs/passive/capacitor/chips/chips.prt';

PART_NAME
 C274 'CAPACITOR-G105-0C106-BM,10UF,2A':;

SECTION_NUMBER 1
 '@TIMECARD_LIB.TIMECARD(SCH_1):PAGE7_I23@PASSIVE.CAPACITOR(CHIPS)':
 C_PATH='@timecard_lib.timecard(sch_1):page7_i23@passive.capacitor(chips)',
 P_PATH='@timecard_lib.timecard(sch_1):page18_i23@passive.capacitor(chips)',
 PATH='I23',
 DRAWING='@TIMECARD_LIB.TIMECARD(SCH_1):PAGE7',
 PACKAGE='0402',
 PHYS_PAGE='18',
 XY='(-5200,8750)',
 ROT='2',
 VER='2',
 CDS_LIB='passive',
 CDS_PART_NAME='CAPACITOR-G105-0C106-BM,10UF,2A',
 TOLERANCE='20%',
 CLS_PN='G105-0C106-BM',
 VOLTAGE='6.3V',
 VALUE='10UF',
 PRIM_FILE='./archive_libs/passive/capacitor/chips/chips.prt';

PART_NAME
 C275 'CAPACITOR-G105-0B104-EK,0.1UF,A':;

SECTION_NUMBER 1
 '@TIMECARD_LIB.TIMECARD(SCH_1):PAGE7_I19@PASSIVE.CAPACITOR(CHIPS)':
 C_PATH='@timecard_lib.timecard(sch_1):page7_i19@passive.capacitor(chips)',
 P_PATH='@timecard_lib.timecard(sch_1):page18_i19@passive.capacitor(chips)',
 PATH='I19',
 DRAWING='@TIMECARD_LIB.TIMECARD(SCH_1):PAGE7',
 PACKAGE='0402',
 PHYS_PAGE='18',
 XY='(-5650,8750)',
 ROT='2',
 VER='2',
 CDS_LIB='passive',
 CDS_PART_NAME='CAPACITOR-G105-0B104-EK,0.1UF,A',
 TOLERANCE='10%',
 CLS_PN='G105-0B104-EK',
 VOLTAGE='25V',
 VALUE='0.1UF',
 PRIM_FILE='./archive_libs/passive/capacitor/chips/chips.prt';

PART_NAME
 C276 'CAPACITOR-G105-0B104-EK,0.1UF,A':;

SECTION_NUMBER 1
 '@TIMECARD_LIB.TIMECARD(SCH_1):PAGE8_I16@PASSIVE.CAPACITOR(CHIPS)':
 C_PATH='@timecard_lib.timecard(sch_1):page8_i16@passive.capacitor(chips)',
 P_PATH='@timecard_lib.timecard(sch_1):page19_i16@passive.capacitor(chips)',
 PATH='I16',
 DRAWING='@TIMECARD_LIB.TIMECARD(SCH_1):PAGE8',
 PACKAGE='0402',
 PHYS_PAGE='19',
 XY='(-2950,8500)',
 ROT='2',
 VER='2',
 CDS_LIB='passive',
 CDS_PART_NAME='CAPACITOR-G105-0B104-EK,0.1UF,A',
 TOLERANCE='10%',
 CLS_PN='G105-0B104-EK',
 VOLTAGE='25V',
 VALUE='0.1UF',
 PRIM_FILE='./archive_libs/passive/capacitor/chips/chips.prt';

PART_NAME
 C277 'CAPACITOR-G105-0C106-BM,10UF,2A':;

SECTION_NUMBER 1
 '@TIMECARD_LIB.TIMECARD(SCH_1):PAGE8_I21@PASSIVE.CAPACITOR(CHIPS)':
 C_PATH='@timecard_lib.timecard(sch_1):page8_i21@passive.capacitor(chips)',
 P_PATH='@timecard_lib.timecard(sch_1):page19_i21@passive.capacitor(chips)',
 PATH='I21',
 DRAWING='@TIMECARD_LIB.TIMECARD(SCH_1):PAGE8',
 PACKAGE='0402',
 PHYS_PAGE='19',
 XY='(-4350,8500)',
 ROT='2',
 VER='2',
 CDS_LIB='passive',
 CDS_PART_NAME='CAPACITOR-G105-0C106-BM,10UF,2A',
 TOLERANCE='20%',
 CLS_PN='G105-0C106-BM',
 VOLTAGE='6.3V',
 VALUE='10UF',
 PRIM_FILE='./archive_libs/passive/capacitor/chips/chips.prt';

PART_NAME
 C278 'CAPACITOR-G105-0B104-EK,0.1UF,A':;

SECTION_NUMBER 1
 '@TIMECARD_LIB.TIMECARD(SCH_1):PAGE8_I19@PASSIVE.CAPACITOR(CHIPS)':
 C_PATH='@timecard_lib.timecard(sch_1):page8_i19@passive.capacitor(chips)',
 P_PATH='@timecard_lib.timecard(sch_1):page19_i19@passive.capacitor(chips)',
 PATH='I19',
 DRAWING='@TIMECARD_LIB.TIMECARD(SCH_1):PAGE8',
 PACKAGE='0402',
 PHYS_PAGE='19',
 XY='(-3950,8500)',
 ROT='2',
 VER='2',
 CDS_LIB='passive',
 CDS_PART_NAME='CAPACITOR-G105-0B104-EK,0.1UF,A',
 TOLERANCE='10%',
 CLS_PN='G105-0B104-EK',
 VOLTAGE='25V',
 VALUE='0.1UF',
 PRIM_FILE='./archive_libs/passive/capacitor/chips/chips.prt';

PART_NAME
 C279 'CAPACITOR-G105-0B104-EK,0.1UF,A':;

SECTION_NUMBER 1
 '@TIMECARD_LIB.TIMECARD(SCH_1):PAGE9_I21@PASSIVE.CAPACITOR(CHIPS)':
 C_PATH='@timecard_lib.timecard(sch_1):page9_i21@passive.capacitor(chips)',
 P_PATH='@timecard_lib.timecard(sch_1):page20_i21@passive.capacitor(chips)',
 PATH='I21',
 DRAWING='@TIMECARD_LIB.TIMECARD(SCH_1):PAGE9',
 PACKAGE='0402',
 PHYS_PAGE='20',
 XY='(-10250,11700)',
 ROT='2',
 VER='2',
 CDS_LIB='passive',
 CDS_PART_NAME='CAPACITOR-G105-0B104-EK,0.1UF,A',
 TOLERANCE='10%',
 CLS_PN='G105-0B104-EK',
 VOLTAGE='25V',
 VALUE='0.1UF',
 PRIM_FILE='./archive_libs/passive/capacitor/chips/chips.prt';

PART_NAME
 C280 'CAPACITOR-G105-0C106-BM,10UF,2A':;

SECTION_NUMBER 1
 '@TIMECARD_LIB.TIMECARD(SCH_1):PAGE9_I23@PASSIVE.CAPACITOR(CHIPS)':
 C_PATH='@timecard_lib.timecard(sch_1):page9_i23@passive.capacitor(chips)',
 P_PATH='@timecard_lib.timecard(sch_1):page20_i23@passive.capacitor(chips)',
 PATH='I23',
 DRAWING='@TIMECARD_LIB.TIMECARD(SCH_1):PAGE9',
 PACKAGE='0402',
 PHYS_PAGE='20',
 XY='(-9200,11700)',
 ROT='2',
 VER='2',
 CDS_LIB='passive',
 CDS_PART_NAME='CAPACITOR-G105-0C106-BM,10UF,2A',
 TOLERANCE='20%',
 CLS_PN='G105-0C106-BM',
 VOLTAGE='6.3V',
 VALUE='10UF',
 PRIM_FILE='./archive_libs/passive/capacitor/chips/chips.prt';

PART_NAME
 C281 'CAPACITOR-G105-0B104-EK,0.1UF,A':;

SECTION_NUMBER 1
 '@TIMECARD_LIB.TIMECARD(SCH_1):PAGE9_I24@PASSIVE.CAPACITOR(CHIPS)':
 C_PATH='@timecard_lib.timecard(sch_1):page9_i24@passive.capacitor(chips)',
 P_PATH='@timecard_lib.timecard(sch_1):page20_i24@passive.capacitor(chips)',
 PATH='I24',
 DRAWING='@TIMECARD_LIB.TIMECARD(SCH_1):PAGE9',
 PACKAGE='0402',
 PHYS_PAGE='20',
 XY='(-8750,11700)',
 ROT='2',
 VER='2',
 CDS_LIB='passive',
 CDS_PART_NAME='CAPACITOR-G105-0B104-EK,0.1UF,A',
 TOLERANCE='10%',
 CLS_PN='G105-0B104-EK',
 VOLTAGE='25V',
 VALUE='0.1UF',
 PRIM_FILE='./archive_libs/passive/capacitor/chips/chips.prt';

PART_NAME
 C282 'CAPACITOR-G107-0F106-EM,10UF,2A':;

SECTION_NUMBER 1
 '@TIMECARD_LIB.TIMECARD(SCH_1):PAGE527_I208@PASSIVE.CAPACITOR(CHIPS)':
 C_PATH='@timecard_lib.timecard(sch_1):page527_i208@passive.capacitor(chips)',
 P_PATH='@timecard_lib.timecard(sch_1):page21_i208@passive.capacitor(chips)',
 PATH='I208',
 DRAWING='@TIMECARD_LIB.TIMECARD(SCH_1):PAGE527',
 PACKAGE='0805',
 PHYS_PAGE='21',
 XY='(-8800,4550)',
 ROT='0',
 VER='2',
 CDS_LIB='passive',
 CDS_PART_NAME='CAPACITOR-G107-0F106-EM,10UF,2A',
 TOLERANCE='20%',
 CLS_PN='G107-0F106-EM',
 VOLTAGE='25V',
 VALUE='10UF',
 PRIM_FILE='./archive_libs/passive/capacitor/chips/chips.prt';

PART_NAME
 C283 'CAPACITOR-G107-0F106-EM,10UF,2A':;

SECTION_NUMBER 1
 '@TIMECARD_LIB.TIMECARD(SCH_1):PAGE527_I209@PASSIVE.CAPACITOR(CHIPS)':
 C_PATH='@timecard_lib.timecard(sch_1):page527_i209@passive.capacitor(chips)',
 P_PATH='@timecard_lib.timecard(sch_1):page21_i209@passive.capacitor(chips)',
 PATH='I209',
 DRAWING='@TIMECARD_LIB.TIMECARD(SCH_1):PAGE527',
 PACKAGE='0805',
 PHYS_PAGE='21',
 XY='(-8350,4550)',
 ROT='0',
 VER='2',
 CDS_LIB='passive',
 CDS_PART_NAME='CAPACITOR-G107-0F106-EM,10UF,2A',
 TOLERANCE='20%',
 CLS_PN='G107-0F106-EM',
 VOLTAGE='25V',
 VALUE='10UF',
 PRIM_FILE='./archive_libs/passive/capacitor/chips/chips.prt';

PART_NAME
 C284 'CAPACITOR-G107-0F226-CM,22UF,2A':;

SECTION_NUMBER 1
 '@TIMECARD_LIB.TIMECARD(SCH_1):PAGE525_I7@PASSIVE.CAPACITOR(CHIPS)':
 C_PATH='@timecard_lib.timecard(sch_1):page525_i7@passive.capacitor(chips)',
 P_PATH='@timecard_lib.timecard(sch_1):page33_i7@passive.capacitor(chips)',
 PATH='I7',
 DRAWING='@TIMECARD_LIB.TIMECARD(SCH_1):PAGE525',
 PACKAGE='0805',
 PHYS_PAGE='33',
 XY='(-1100,3050)',
 ROT='0',
 VER='2',
 CDS_LIB='passive',
 CDS_PART_NAME='CAPACITOR-G107-0F226-CM,22UF,2A',
 TOLERANCE='20%',
 CLS_PN='G107-0F226-CM',
 VOLTAGE='10V',
 VALUE='22UF',
 PRIM_FILE='./archive_libs/passive/capacitor/chips/chips.prt';

PART_NAME
 C285 'CAPACITOR-G105-0B104-CK,0.1UF,A':;

SECTION_NUMBER 1
 '@TIMECARD_LIB.TIMECARD(SCH_1):PAGE9_I53@PASSIVE.CAPACITOR(CHIPS)':
 C_PATH='@timecard_lib.timecard(sch_1):page9_i53@passive.capacitor(chips)',
 P_PATH='@timecard_lib.timecard(sch_1):page20_i53@passive.capacitor(chips)',
 PATH='I53',
 DRAWING='@TIMECARD_LIB.TIMECARD(SCH_1):PAGE9',
 PACKAGE='0402',
 PHYS_PAGE='20',
 XY='(-4800,10700)',
 ROT='1',
 VER='2',
 CDS_LIB='passive',
 CDS_PART_NAME='CAPACITOR-G105-0B104-CK,0.1UF,A',
 TOLERANCE='10%',
 CLS_PN='G105-0B104-CK',
 VOLTAGE='10V',
 VALUE='0.1UF',
 PRIM_FILE='./archive_libs/passive/capacitor/chips/chips.prt';

PART_NAME
 C286 'CAPACITOR-G105-0B224-DK,0.22UFA':;

SECTION_NUMBER 1
 '@TIMECARD_LIB.TIMECARD(SCH_1):PAGE517_I51@PASSIVE.CAPACITOR(CHIPS)':
 C_PATH='@timecard_lib.timecard(sch_1):page517_i51@passive.capacitor(chips)',
 P_PATH='@timecard_lib.timecard(sch_1):page28_i51@passive.capacitor(chips)',
 PATH='I51',
 DRAWING='@TIMECARD_LIB.TIMECARD(SCH_1):PAGE517',
 PACKAGE='0402',
 PHYS_PAGE='28',
 XY='(-12850,5800)',
 ROT='0',
 VER='2',
 CDS_LIB='passive',
 CDS_PART_NAME='CAPACITOR-G105-0B224-DK,0.22UFA',
 TOLERANCE='10%',
 CLS_PN='G105-0B224-DK',
 VOLTAGE='25V',
 VALUE='0.22UF',
 PRIM_FILE='./archive_libs/passive/capacitor/chips/chips.prt';

PART_NAME
 C287 'CAPACITOR-G105-0C106-BM,10UF,2A':;

SECTION_NUMBER 1
 '@TIMECARD_LIB.TIMECARD(SCH_1):PAGE3_I129@PASSIVE.CAPACITOR(CHIPS)':
 C_PATH='@timecard_lib.timecard(sch_1):page3_i129@passive.capacitor(chips)',
 P_PATH='@timecard_lib.timecard(sch_1):page9_i129@passive.capacitor(chips)',
 PATH='I129',
 DRAWING='@TIMECARD_LIB.TIMECARD(SCH_1):PAGE3',
 PACKAGE='0402',
 PHYS_PAGE='9',
 XY='(-7050,3900)',
 ROT='2',
 VER='2',
 CDS_LIB='passive',
 CDS_PART_NAME='CAPACITOR-G105-0C106-BM,10UF,2A',
 TOLERANCE='20%',
 CLS_PN='G105-0C106-BM',
 VOLTAGE='6.3V',
 VALUE='10UF',
 PRIM_FILE='./archive_libs/passive/capacitor/chips/chips.prt';

PART_NAME
 C288 'CAPACITOR-G105-0B104-EK,0.1UF,A':;

SECTION_NUMBER 1
 '@TIMECARD_LIB.TIMECARD(SCH_1):PAGE3_I127@PASSIVE.CAPACITOR(CHIPS)':
 C_PATH='@timecard_lib.timecard(sch_1):page3_i127@passive.capacitor(chips)',
 P_PATH='@timecard_lib.timecard(sch_1):page9_i127@passive.capacitor(chips)',
 PATH='I127',
 DRAWING='@TIMECARD_LIB.TIMECARD(SCH_1):PAGE3',
 PACKAGE='0402',
 PHYS_PAGE='9',
 XY='(-6650,3900)',
 ROT='2',
 VER='2',
 CDS_LIB='passive',
 CDS_PART_NAME='CAPACITOR-G105-0B104-EK,0.1UF,A',
 TOLERANCE='10%',
 CLS_PN='G105-0B104-EK',
 VOLTAGE='25V',
 VALUE='0.1UF',
 PRIM_FILE='./archive_libs/passive/capacitor/chips/chips.prt';

PART_NAME
 C289 'CAPACITOR-G105-0C106-BM,10UF,2A':;

SECTION_NUMBER 1
 '@TIMECARD_LIB.TIMECARD(SCH_1):PAGE3_I124@PASSIVE.CAPACITOR(CHIPS)':
 C_PATH='@timecard_lib.timecard(sch_1):page3_i124@passive.capacitor(chips)',
 P_PATH='@timecard_lib.timecard(sch_1):page9_i124@passive.capacitor(chips)',
 PATH='I124',
 DRAWING='@TIMECARD_LIB.TIMECARD(SCH_1):PAGE3',
 PACKAGE='0402',
 PHYS_PAGE='9',
 XY='(-5900,3900)',
 ROT='2',
 VER='2',
 CDS_LIB='passive',
 CDS_PART_NAME='CAPACITOR-G105-0C106-BM,10UF,2A',
 TOLERANCE='20%',
 CLS_PN='G105-0C106-BM',
 VOLTAGE='6.3V',
 VALUE='10UF',
 PRIM_FILE='./archive_libs/passive/capacitor/chips/chips.prt';

PART_NAME
 C290 'CAPACITOR-G105-0B104-EK,0.1UF,A':;

SECTION_NUMBER 1
 '@TIMECARD_LIB.TIMECARD(SCH_1):PAGE3_I126@PASSIVE.CAPACITOR(CHIPS)':
 C_PATH='@timecard_lib.timecard(sch_1):page3_i126@passive.capacitor(chips)',
 P_PATH='@timecard_lib.timecard(sch_1):page9_i126@passive.capacitor(chips)',
 PATH='I126',
 DRAWING='@TIMECARD_LIB.TIMECARD(SCH_1):PAGE3',
 PACKAGE='0402',
 PHYS_PAGE='9',
 XY='(-5500,3900)',
 ROT='2',
 VER='2',
 CDS_LIB='passive',
 CDS_PART_NAME='CAPACITOR-G105-0B104-EK,0.1UF,A',
 TOLERANCE='10%',
 CLS_PN='G105-0B104-EK',
 VOLTAGE='25V',
 VALUE='0.1UF',
 PRIM_FILE='./archive_libs/passive/capacitor/chips/chips.prt';

PART_NAME
 C291 'CAPACITOR-G107-0F226-CM,22UF,2A':;

SECTION_NUMBER 1
 '@TIMECARD_LIB.TIMECARD(SCH_1):PAGE164_I290@PASSIVE.CAPACITOR(CHIPS)':
 C_PATH='@timecard_lib.timecard(sch_1):page164_i290@passive.capacitor(chips)',
 P_PATH='@timecard_lib.timecard(sch_1):page14_i290@passive.capacitor(chips)',
 PATH='I290',
 DRAWING='@TIMECARD_LIB.TIMECARD(SCH_1):PAGE164',
 PACKAGE='0805',
 PHYS_PAGE='14',
 XY='(-4950,2050)',
 ROT='0',
 VER='2',
 CDS_LIB='passive',
 CDS_PART_NAME='CAPACITOR-G107-0F226-CM,22UF,2A',
 TOLERANCE='20%',
 CLS_PN='G107-0F226-CM',
 VOLTAGE='10V',
 VALUE='22UF',
 PRIM_FILE='./archive_libs/passive/capacitor/chips/chips.prt';

PART_NAME
 C292 'CAPACITOR-G107-0F226-CM,22UF,2A':;

SECTION_NUMBER 1
 '@TIMECARD_LIB.TIMECARD(SCH_1):PAGE164_I291@PASSIVE.CAPACITOR(CHIPS)':
 C_PATH='@timecard_lib.timecard(sch_1):page164_i291@passive.capacitor(chips)',
 P_PATH='@timecard_lib.timecard(sch_1):page14_i291@passive.capacitor(chips)',
 PATH='I291',
 DRAWING='@TIMECARD_LIB.TIMECARD(SCH_1):PAGE164',
 PACKAGE='0805',
 PHYS_PAGE='14',
 XY='(-4600,2050)',
 ROT='0',
 VER='2',
 CDS_LIB='passive',
 CDS_PART_NAME='CAPACITOR-G107-0F226-CM,22UF,2A',
 TOLERANCE='20%',
 CLS_PN='G107-0F226-CM',
 VOLTAGE='10V',
 VALUE='22UF',
 PRIM_FILE='./archive_libs/passive/capacitor/chips/chips.prt';

PART_NAME
 C293 'CAPACITOR-G105-0B224-DK,0.22UFA':;

SECTION_NUMBER 1
 '@TIMECARD_LIB.TIMECARD(SCH_1):PAGE515_I168@PASSIVE.CAPACITOR(CHIPS)':
 C_PATH='@timecard_lib.timecard(sch_1):page515_i168@passive.capacitor(chips)',
 P_PATH='@timecard_lib.timecard(sch_1):page31_i168@passive.capacitor(chips)',
 PATH='I168',
 DRAWING='@TIMECARD_LIB.TIMECARD(SCH_1):PAGE515',
 PACKAGE='0402',
 PHYS_PAGE='31',
 XY='(-10150,800)',
 ROT='0',
 VER='2',
 CDS_LIB='passive',
 CDS_PART_NAME='CAPACITOR-G105-0B224-DK,0.22UFA',
 TOLERANCE='10%',
 CLS_PN='G105-0B224-DK',
 VOLTAGE='25V',
 VALUE='0.22UF',
 PRIM_FILE='./archive_libs/passive/capacitor/chips/chips.prt';

PART_NAME
 C294 'CAPACITOR-G105-0B224-DK,0.22UFA':;

SECTION_NUMBER 1
 '@TIMECARD_LIB.TIMECARD(SCH_1):PAGE515_I169@PASSIVE.CAPACITOR(CHIPS)':
 C_PATH='@timecard_lib.timecard(sch_1):page515_i169@passive.capacitor(chips)',
 P_PATH='@timecard_lib.timecard(sch_1):page31_i169@passive.capacitor(chips)',
 PATH='I169',
 DRAWING='@TIMECARD_LIB.TIMECARD(SCH_1):PAGE515',
 PACKAGE='0402',
 PHYS_PAGE='31',
 XY='(-10100,6300)',
 ROT='0',
 VER='2',
 CDS_LIB='passive',
 CDS_PART_NAME='CAPACITOR-G105-0B224-DK,0.22UFA',
 TOLERANCE='10%',
 CLS_PN='G105-0B224-DK',
 VOLTAGE='25V',
 VALUE='0.22UF',
 PRIM_FILE='./archive_libs/passive/capacitor/chips/chips.prt';

PART_NAME
 C297 'CAPACITOR-G107-0F106-EM,10UF,2A':;

SECTION_NUMBER 1
 '@TIMECARD_LIB.TIMECARD(SCH_1):PAGE15_I229@PASSIVE.CAPACITOR(CHIPS)':
 C_PATH='@timecard_lib.timecard(sch_1):page15_i229@passive.capacitor(chips)',
 P_PATH='@timecard_lib.timecard(sch_1):page27_i229@passive.capacitor(chips)',
 PATH='I229',
 DRAWING='@TIMECARD_LIB.TIMECARD(SCH_1):PAGE15',
 PACKAGE='0805',
 PHYS_PAGE='27',
 XY='(-10650,9000)',
 ROT='0',
 VER='2',
 CDS_LIB='passive',
 CDS_PART_NAME='CAPACITOR-G107-0F106-EM,10UF,2A',
 NO_ASSY='TRUE',
 TOLERANCE='20%',
 CLS_PN='G107-0F106-EM',
 VOLTAGE='25V',
 VALUE='10UF',
 PRIM_FILE='./archive_libs/passive/capacitor/chips/chips.prt';

PART_NAME
 C298 'CAPACITOR-G105-0B104-EK,0.1UF,A':;

SECTION_NUMBER 1
 '@TIMECARD_LIB.TIMECARD(SCH_1):PAGE525_I8@PASSIVE.CAPACITOR(CHIPS)':
 C_PATH='@timecard_lib.timecard(sch_1):page525_i8@passive.capacitor(chips)',
 P_PATH='@timecard_lib.timecard(sch_1):page33_i8@passive.capacitor(chips)',
 PATH='I8',
 DRAWING='@TIMECARD_LIB.TIMECARD(SCH_1):PAGE525',
 MATERIAL='X7R',
 PACKAGE='0402',
 PHYS_PAGE='33',
 XY='(-650,3050)',
 ROT='0',
 VER='2',
 CDS_LIB='passive',
 CDS_PART_NAME='CAPACITOR-G105-0B104-EK,0.1UF,A',
 TOLERANCE='10%',
 CLS_PN='G105-0B104-EK',
 VOLTAGE='25V',
 VALUE='0.1UF',
 PRIM_FILE='./archive_libs/passive/capacitor/chips/chips.prt';

PART_NAME
 C299 'CAPACITOR-G107-0F106-EM,10UF,2A':;

SECTION_NUMBER 1
 '@TIMECARD_LIB.TIMECARD(SCH_1):PAGE15_I230@PASSIVE.CAPACITOR(CHIPS)':
 C_PATH='@timecard_lib.timecard(sch_1):page15_i230@passive.capacitor(chips)',
 P_PATH='@timecard_lib.timecard(sch_1):page27_i230@passive.capacitor(chips)',
 PATH='I230',
 DRAWING='@TIMECARD_LIB.TIMECARD(SCH_1):PAGE15',
 PACKAGE='0805',
 PHYS_PAGE='27',
 XY='(-10250,9000)',
 ROT='0',
 VER='2',
 CDS_LIB='passive',
 CDS_PART_NAME='CAPACITOR-G107-0F106-EM,10UF,2A',
 NO_ASSY='TRUE',
 TOLERANCE='20%',
 CLS_PN='G107-0F106-EM',
 VOLTAGE='25V',
 VALUE='10UF',
 PRIM_FILE='./archive_libs/passive/capacitor/chips/chips.prt';

PART_NAME
 C300 'CAPACITOR-G107-0F106-EM,10UF,2A':;

SECTION_NUMBER 1
 '@TIMECARD_LIB.TIMECARD(SCH_1):PAGE525_I16@PASSIVE.CAPACITOR(CHIPS)':
 C_PATH='@timecard_lib.timecard(sch_1):page525_i16@passive.capacitor(chips)',
 P_PATH='@timecard_lib.timecard(sch_1):page33_i16@passive.capacitor(chips)',
 PATH='I16',
 DRAWING='@TIMECARD_LIB.TIMECARD(SCH_1):PAGE525',
 PACKAGE='0805',
 PHYS_PAGE='33',
 XY='(800,3050)',
 ROT='0',
 VER='2',
 CDS_LIB='passive',
 CDS_PART_NAME='CAPACITOR-G107-0F106-EM,10UF,2A',
 TOLERANCE='20%',
 CLS_PN='G107-0F106-EM',
 VOLTAGE='25V',
 VALUE='10UF',
 PRIM_FILE='./archive_libs/passive/capacitor/chips/chips.prt';

PART_NAME
 C301 'CAPACITOR-G107-0F106-EM,10UF,2A':;

SECTION_NUMBER 1
 '@TIMECARD_LIB.TIMECARD(SCH_1):PAGE15_I232@PASSIVE.CAPACITOR(CHIPS)':
 C_PATH='@timecard_lib.timecard(sch_1):page15_i232@passive.capacitor(chips)',
 P_PATH='@timecard_lib.timecard(sch_1):page27_i232@passive.capacitor(chips)',
 PATH='I232',
 DRAWING='@TIMECARD_LIB.TIMECARD(SCH_1):PAGE15',
 PACKAGE='0805',
 PHYS_PAGE='27',
 XY='(-9850,9000)',
 ROT='0',
 VER='2',
 CDS_LIB='passive',
 CDS_PART_NAME='CAPACITOR-G107-0F106-EM,10UF,2A',
 NO_ASSY='TRUE',
 TOLERANCE='20%',
 CLS_PN='G107-0F106-EM',
 VOLTAGE='25V',
 VALUE='10UF',
 PRIM_FILE='./archive_libs/passive/capacitor/chips/chips.prt';

PART_NAME
 C302 'CAPACITOR-G105-0B104-EK,0.1UF,A':;

SECTION_NUMBER 1
 '@TIMECARD_LIB.TIMECARD(SCH_1):PAGE525_I14@PASSIVE.CAPACITOR(CHIPS)':
 C_PATH='@timecard_lib.timecard(sch_1):page525_i14@passive.capacitor(chips)',
 P_PATH='@timecard_lib.timecard(sch_1):page33_i14@passive.capacitor(chips)',
 PATH='I14',
 DRAWING='@TIMECARD_LIB.TIMECARD(SCH_1):PAGE525',
 PACKAGE='0402',
 PHYS_PAGE='33',
 XY='(850,1950)',
 ROT='0',
 VER='2',
 CDS_LIB='passive',
 CDS_PART_NAME='CAPACITOR-G105-0B104-EK,0.1UF,A',
 TOLERANCE='10%',
 CLS_PN='G105-0B104-EK',
 VOLTAGE='25V',
 VALUE='0.1UF',
 PRIM_FILE='./archive_libs/passive/capacitor/chips/chips.prt';

PART_NAME
 C303 'CAPACITOR-G107-0F106-EM,10UF,2A':;

SECTION_NUMBER 1
 '@TIMECARD_LIB.TIMECARD(SCH_1):PAGE15_I231@PASSIVE.CAPACITOR(CHIPS)':
 C_PATH='@timecard_lib.timecard(sch_1):page15_i231@passive.capacitor(chips)',
 P_PATH='@timecard_lib.timecard(sch_1):page27_i231@passive.capacitor(chips)',
 PATH='I231',
 DRAWING='@TIMECARD_LIB.TIMECARD(SCH_1):PAGE15',
 PACKAGE='0805',
 PHYS_PAGE='27',
 XY='(-9450,9000)',
 ROT='0',
 VER='2',
 CDS_LIB='passive',
 CDS_PART_NAME='CAPACITOR-G107-0F106-EM,10UF,2A',
 NO_ASSY='TRUE',
 TOLERANCE='20%',
 CLS_PN='G107-0F106-EM',
 VOLTAGE='25V',
 VALUE='10UF',
 PRIM_FILE='./archive_libs/passive/capacitor/chips/chips.prt';

PART_NAME
 C304 'CAPACITOR-G105-0B104-EK,0.1UF,A':;

SECTION_NUMBER 1
 '@TIMECARD_LIB.TIMECARD(SCH_1):PAGE525_I20@PASSIVE.CAPACITOR(CHIPS)':
 C_PATH='@timecard_lib.timecard(sch_1):page525_i20@passive.capacitor(chips)',
 P_PATH='@timecard_lib.timecard(sch_1):page33_i20@passive.capacitor(chips)',
 PATH='I20',
 DRAWING='@TIMECARD_LIB.TIMECARD(SCH_1):PAGE525',
 PACKAGE='0402',
 PHYS_PAGE='33',
 XY='(1250,3050)',
 ROT='0',
 VER='2',
 CDS_LIB='passive',
 CDS_PART_NAME='CAPACITOR-G105-0B104-EK,0.1UF,A',
 TOLERANCE='10%',
 CLS_PN='G105-0B104-EK',
 VOLTAGE='25V',
 VALUE='0.1UF',
 PRIM_FILE='./archive_libs/passive/capacitor/chips/chips.prt';

PART_NAME
 C305 'CAPACITOR-G105-0B104-EK,0.1UF,A':;

SECTION_NUMBER 1
 '@TIMECARD_LIB.TIMECARD(SCH_1):PAGE6_I67@PASSIVE.CAPACITOR(CHIPS)':
 C_PATH='@timecard_lib.timecard(sch_1):page6_i67@passive.capacitor(chips)',
 P_PATH='@timecard_lib.timecard(sch_1):page17_i67@passive.capacitor(chips)',
 PATH='I67',
 DRAWING='@TIMECARD_LIB.TIMECARD(SCH_1):PAGE6',
 PACKAGE='0402',
 PHYS_PAGE='17',
 XY='(-1450,3250)',
 ROT='0',
 VER='1',
 CDS_LIB='passive',
 CDS_PART_NAME='CAPACITOR-G105-0B104-EK,0.1UF,A',
 TOLERANCE='10%',
 CLS_PN='G105-0B104-EK',
 VOLTAGE='25V',
 VALUE='0.1UF',
 PRIM_FILE='./archive_libs/passive/capacitor/chips/chips.prt';

PART_NAME
 C306 'CAPACITOR-G105-0B104-EK,0.1UF,A':;

SECTION_NUMBER 1
 '@TIMECARD_LIB.TIMECARD(SCH_1):PAGE6_I91@PASSIVE.CAPACITOR(CHIPS)':
 C_PATH='@timecard_lib.timecard(sch_1):page6_i91@passive.capacitor(chips)',
 P_PATH='@timecard_lib.timecard(sch_1):page17_i91@passive.capacitor(chips)',
 PATH='I91',
 DRAWING='@TIMECARD_LIB.TIMECARD(SCH_1):PAGE6',
 PACKAGE='0402',
 PHYS_PAGE='17',
 XY='(-1450,400)',
 ROT='0',
 VER='1',
 CDS_LIB='passive',
 CDS_PART_NAME='CAPACITOR-G105-0B104-EK,0.1UF,A',
 TOLERANCE='10%',
 CLS_PN='G105-0B104-EK',
 VOLTAGE='25V',
 VALUE='0.1UF',
 PRIM_FILE='./archive_libs/passive/capacitor/chips/chips.prt';

PART_NAME
 C307 'CAPACITOR-G104-0B103-EK,0.01UFA':;

SECTION_NUMBER 1
 '@TIMECARD_LIB.TIMECARD(SCH_1):PAGE525_I18@PASSIVE.CAPACITOR(CHIPS)':
 C_PATH='@timecard_lib.timecard(sch_1):page525_i18@passive.capacitor(chips)',
 P_PATH='@timecard_lib.timecard(sch_1):page33_i18@passive.capacitor(chips)',
 PATH='I18',
 DRAWING='@TIMECARD_LIB.TIMECARD(SCH_1):PAGE525',
 PACKAGE='0201',
 PHYS_PAGE='33',
 XY='(1350,1850)',
 ROT='0',
 VER='2',
 CDS_LIB='passive',
 CDS_PART_NAME='CAPACITOR-G104-0B103-EK,0.01UFA',
 TOLERANCE='10%',
 CLS_PN='G104-0B103-EK',
 VOLTAGE='25V',
 VALUE='0.01UF',
 PRIM_FILE='./archive_libs/passive/capacitor/chips/chips.prt';

PART_NAME
 C308 'CAPACITOR-G107-0F106-EM,10UF,2A':;

SECTION_NUMBER 1
 '@TIMECARD_LIB.TIMECARD(SCH_1):PAGE525_I64@PASSIVE.CAPACITOR(CHIPS)':
 C_PATH='@timecard_lib.timecard(sch_1):page525_i64@passive.capacitor(chips)',
 P_PATH='@timecard_lib.timecard(sch_1):page33_i64@passive.capacitor(chips)',
 PATH='I64',
 DRAWING='@TIMECARD_LIB.TIMECARD(SCH_1):PAGE525',
 PACKAGE='0805',
 PHYS_PAGE='33',
 XY='(6150,2950)',
 ROT='0',
 VER='2',
 CDS_LIB='passive',
 CDS_PART_NAME='CAPACITOR-G107-0F106-EM,10UF,2A',
 TOLERANCE='20%',
 CLS_PN='G107-0F106-EM',
 VOLTAGE='25V',
 VALUE='10UF',
 PRIM_FILE='./archive_libs/passive/capacitor/chips/chips.prt';

PART_NAME
 C309 'CAPACITOR-G105-0B104-EK,0.1UF,A':;

SECTION_NUMBER 1
 '@TIMECARD_LIB.TIMECARD(SCH_1):PAGE525_I56@PASSIVE.CAPACITOR(CHIPS)':
 C_PATH='@timecard_lib.timecard(sch_1):page525_i56@passive.capacitor(chips)',
 P_PATH='@timecard_lib.timecard(sch_1):page33_i56@passive.capacitor(chips)',
 PATH='I56',
 DRAWING='@TIMECARD_LIB.TIMECARD(SCH_1):PAGE525',
 PACKAGE='0805',
 PHYS_PAGE='33',
 XY='(6750,2950)',
 ROT='0',
 VER='2',
 CDS_LIB='passive',
 CDS_PART_NAME='CAPACITOR-G105-0B104-EK,0.1UF,A',
 TOLERANCE='10%',
 CLS_PN='G105-0B104-EK',
 VOLTAGE='25V',
 VALUE='0.1UF',
 PRIM_FILE='./archive_libs/passive/capacitor/chips/chips.prt';

PART_NAME
 C310 'CAPACITOR-G104-0A180-FJ,18PF,5%':;

SECTION_NUMBER 1
 '@TIMECARD_LIB.TIMECARD(SCH_1):PAGE12_I318@PASSIVE.CAPACITOR(CHIPS)':
 C_PATH='@timecard_lib.timecard(sch_1):page12_i318@passive.capacitor(chips)',
 P_PATH='@timecard_lib.timecard(sch_1):page23_i318@passive.capacitor(chips)',
 PATH='I318',
 DRAWING='@TIMECARD_LIB.TIMECARD(SCH_1):PAGE12',
 PACKAGE='0201',
 PHYS_PAGE='23',
 XY='(-10000,8250)',
 ROT='1',
 VER='1',
 CDS_LIB='passive',
 CDS_PART_NAME='CAPACITOR-G104-0A180-FJ,18PF,5%',
 TOLERANCE='5%',
 CLS_PN='G104-0A180-FJ',
 VALUE='18PF',
 PRIM_FILE='./archive_libs/passive/capacitor/chips/chips.prt';

PART_NAME
 C311 'CAPACITOR-G104-0A180-FJ,18PF,5%':;

SECTION_NUMBER 1
 '@TIMECARD_LIB.TIMECARD(SCH_1):PAGE12_I321@PASSIVE.CAPACITOR(CHIPS)':
 C_PATH='@timecard_lib.timecard(sch_1):page12_i321@passive.capacitor(chips)',
 P_PATH='@timecard_lib.timecard(sch_1):page23_i321@passive.capacitor(chips)',
 PATH='I321',
 DRAWING='@TIMECARD_LIB.TIMECARD(SCH_1):PAGE12',
 PACKAGE='0201',
 PHYS_PAGE='23',
 XY='(-9950,6100)',
 ROT='1',
 VER='1',
 CDS_LIB='passive',
 CDS_PART_NAME='CAPACITOR-G104-0A180-FJ,18PF,5%',
 TOLERANCE='5%',
 CLS_PN='G104-0A180-FJ',
 VALUE='18PF',
 PRIM_FILE='./archive_libs/passive/capacitor/chips/chips.prt';

PART_NAME
 C312 'CAPACITOR-G105-0B104-CK,0.1UF,A':;

SECTION_NUMBER 1
 '@TIMECARD_LIB.TIMECARD(SCH_1):PAGE8_I39@PASSIVE.CAPACITOR(CHIPS)':
 C_PATH='@timecard_lib.timecard(sch_1):page8_i39@passive.capacitor(chips)',
 P_PATH='@timecard_lib.timecard(sch_1):page19_i39@passive.capacitor(chips)',
 PATH='I39',
 DRAWING='@TIMECARD_LIB.TIMECARD(SCH_1):PAGE8',
 PACKAGE='0402',
 PHYS_PAGE='19',
 XY='(-4550,5700)',
 ROT='0',
 VER='2',
 CDS_LIB='passive',
 CDS_PART_NAME='CAPACITOR-G105-0B104-CK,0.1UF,A',
 TOLERANCE='10%',
 CLS_PN='G105-0B104-CK',
 VOLTAGE='10V',
 VALUE='0.1UF',
 PRIM_FILE='./archive_libs/passive/capacitor/chips/chips.prt';

PART_NAME
 C313 'CAPACITOR-G105-0B104-CK,0.1UF,A':;

SECTION_NUMBER 1
 '@TIMECARD_LIB.TIMECARD(SCH_1):PAGE8_I41@PASSIVE.CAPACITOR(CHIPS)':
 C_PATH='@timecard_lib.timecard(sch_1):page8_i41@passive.capacitor(chips)',
 P_PATH='@timecard_lib.timecard(sch_1):page19_i41@passive.capacitor(chips)',
 PATH='I41',
 DRAWING='@TIMECARD_LIB.TIMECARD(SCH_1):PAGE8',
 PACKAGE='0402',
 PHYS_PAGE='19',
 XY='(-3800,5700)',
 ROT='0',
 VER='2',
 CDS_LIB='passive',
 CDS_PART_NAME='CAPACITOR-G105-0B104-CK,0.1UF,A',
 TOLERANCE='10%',
 CLS_PN='G105-0B104-CK',
 VOLTAGE='10V',
 VALUE='0.1UF',
 PRIM_FILE='./archive_libs/passive/capacitor/chips/chips.prt';

PART_NAME
 C314 'CAPACITOR-G105-0C106-BM,10UF,2A':;

SECTION_NUMBER 1
 '@TIMECARD_LIB.TIMECARD(SCH_1):PAGE14_I238@PASSIVE.CAPACITOR(CHIPS)':
 C_PATH='@timecard_lib.timecard(sch_1):page14_i238@passive.capacitor(chips)',
 P_PATH='@timecard_lib.timecard(sch_1):page26_i238@passive.capacitor(chips)',
 PATH='I238',
 DRAWING='@TIMECARD_LIB.TIMECARD(SCH_1):PAGE14',
 PACKAGE='0402',
 PHYS_PAGE='26',
 XY='(-10550,5900)',
 ROT='2',
 VER='2',
 CDS_LIB='passive',
 CDS_PART_NAME='CAPACITOR-G105-0C106-BM,10UF,2A',
 TOLERANCE='20%',
 CLS_PN='G105-0C106-BM',
 VOLTAGE='6.3V',
 VALUE='10UF',
 PRIM_FILE='./archive_libs/passive/capacitor/chips/chips.prt';

PART_NAME
 C315 'CAPACITOR-G105-0B104-EK,0.1UF,A':;

SECTION_NUMBER 1
 '@TIMECARD_LIB.TIMECARD(SCH_1):PAGE14_I237@PASSIVE.CAPACITOR(CHIPS)':
 C_PATH='@timecard_lib.timecard(sch_1):page14_i237@passive.capacitor(chips)',
 P_PATH='@timecard_lib.timecard(sch_1):page26_i237@passive.capacitor(chips)',
 PATH='I237',
 DRAWING='@TIMECARD_LIB.TIMECARD(SCH_1):PAGE14',
 PACKAGE='0402',
 PHYS_PAGE='26',
 XY='(-10150,5900)',
 ROT='2',
 VER='2',
 CDS_LIB='passive',
 CDS_PART_NAME='CAPACITOR-G105-0B104-EK,0.1UF,A',
 TOLERANCE='10%',
 CLS_PN='G105-0B104-EK',
 VOLTAGE='25V',
 VALUE='0.1UF',
 PRIM_FILE='./archive_libs/passive/capacitor/chips/chips.prt';

PART_NAME
 C316 'CAPACITOR-G105-0B104-EK,0.1UF,A':;

SECTION_NUMBER 1
 '@TIMECARD_LIB.TIMECARD(SCH_1):PAGE14_I250@PASSIVE.CAPACITOR(CHIPS)':
 C_PATH='@timecard_lib.timecard(sch_1):page14_i250@passive.capacitor(chips)',
 P_PATH='@timecard_lib.timecard(sch_1):page26_i250@passive.capacitor(chips)',
 PATH='I250',
 DRAWING='@TIMECARD_LIB.TIMECARD(SCH_1):PAGE14',
 PACKAGE='0402',
 PHYS_PAGE='26',
 XY='(-9750,4600)',
 ROT='2',
 VER='2',
 CDS_LIB='passive',
 CDS_PART_NAME='CAPACITOR-G105-0B104-EK,0.1UF,A',
 TOLERANCE='10%',
 CLS_PN='G105-0B104-EK',
 VOLTAGE='25V',
 VALUE='0.1UF',
 PRIM_FILE='./archive_libs/passive/capacitor/chips/chips.prt';

PART_NAME
 C317 'CAPACITOR-G104-0A180-FJ,18PF,5%':;

SECTION_NUMBER 1
 '@TIMECARD_LIB.TIMECARD(SCH_1):PAGE12_I328@PASSIVE.CAPACITOR(CHIPS)':
 C_PATH='@timecard_lib.timecard(sch_1):page12_i328@passive.capacitor(chips)',
 P_PATH='@timecard_lib.timecard(sch_1):page23_i328@passive.capacitor(chips)',
 PATH='I328',
 DRAWING='@TIMECARD_LIB.TIMECARD(SCH_1):PAGE12',
 PACKAGE='0201',
 PHYS_PAGE='23',
 XY='(-9950,3950)',
 ROT='1',
 VER='1',
 CDS_LIB='passive',
 CDS_PART_NAME='CAPACITOR-G104-0A180-FJ,18PF,5%',
 TOLERANCE='5%',
 CLS_PN='G104-0A180-FJ',
 VALUE='18PF',
 PRIM_FILE='./archive_libs/passive/capacitor/chips/chips.prt';

PART_NAME
 C318 'CAPACITOR-G104-0A180-FJ,18PF,5%':;

SECTION_NUMBER 1
 '@TIMECARD_LIB.TIMECARD(SCH_1):PAGE12_I332@PASSIVE.CAPACITOR(CHIPS)':
 C_PATH='@timecard_lib.timecard(sch_1):page12_i332@passive.capacitor(chips)',
 P_PATH='@timecard_lib.timecard(sch_1):page23_i332@passive.capacitor(chips)',
 PATH='I332',
 DRAWING='@TIMECARD_LIB.TIMECARD(SCH_1):PAGE12',
 PACKAGE='0201',
 PHYS_PAGE='23',
 XY='(-9900,1800)',
 ROT='1',
 VER='1',
 CDS_LIB='passive',
 CDS_PART_NAME='CAPACITOR-G104-0A180-FJ,18PF,5%',
 TOLERANCE='5%',
 CLS_PN='G104-0A180-FJ',
 VALUE='18PF',
 PRIM_FILE='./archive_libs/passive/capacitor/chips/chips.prt';

PART_NAME
 CR1 'DIODE_2F-G122-10186-01':;

SECTION_NUMBER 1
 '@TIMECARD_LIB.TIMECARD(SCH_1):PAGE525_I102@DISCRETE.DIODE_2F(CHIPS)':
 C_PATH='@timecard_lib.timecard(sch_1):page525_i102@discrete.diode_2f(chips)',
 P_PATH='@timecard_lib.timecard(sch_1):page33_i102@discrete.diode_2f(chips)',
 PATH='I102',
 DRAWING='@TIMECARD_LIB.TIMECARD(SCH_1):PAGE525',
 PHYS_PAGE='33',
 XY='(-1600,3350)',
 ROT='0',
 VER='1',
 CDS_LIB='discrete',
 CDS_PART_NAME='DIODE_2F-G122-10186-01',
 CLS_PN='G122-10186-01',
 PRIM_FILE='./archive_libs/discrete/diode_2f/chips/chips.prt';

PART_NAME
 CR2 'DIODE_2F-G122-10186-01':;

SECTION_NUMBER 1
 '@TIMECARD_LIB.TIMECARD(SCH_1):PAGE525_I104@DISCRETE.DIODE_2F(CHIPS)':
 C_PATH='@timecard_lib.timecard(sch_1):page525_i104@discrete.diode_2f(chips)',
 P_PATH='@timecard_lib.timecard(sch_1):page33_i104@discrete.diode_2f(chips)',
 PATH='I104',
 DRAWING='@TIMECARD_LIB.TIMECARD(SCH_1):PAGE525',
 PHYS_PAGE='33',
 XY='(-1600,3200)',
 ROT='0',
 VER='1',
 CDS_LIB='discrete',
 CDS_PART_NAME='DIODE_2F-G122-10186-01',
 NO_ASSY='TRUE',
 CLS_PN='G122-10186-01',
 PRIM_FILE='./archive_libs/discrete/diode_2f/chips/chips.prt';

PART_NAME
 CR3 'DIODE_2-G122-00005-01':;

SECTION_NUMBER 1
 '@TIMECARD_LIB.TIMECARD(SCH_1):PAGE15_I204@DISCRETE.DIODE_2(CHIPS)':
 C_PATH='@timecard_lib.timecard(sch_1):page15_i204@discrete.diode_2(chips)',
 P_PATH='@timecard_lib.timecard(sch_1):page27_i204@discrete.diode_2(chips)',
 PATH='I204',
 DRAWING='@TIMECARD_LIB.TIMECARD(SCH_1):PAGE15',
 PHYS_PAGE='27',
 XY='(-2400,8500)',
 ROT='1',
 VER='1',
 CDS_LIB='discrete',
 CDS_PART_NAME='DIODE_2-G122-00005-01',
 CLS_PN='G122-00005-01',
 PART_NUMBER='MBRS240LT3G',
 PRIM_FILE='./archive_libs/discrete/diode_2/chips/chips.prt';

PART_NAME
 CR4 'DIODE_4_V1-G122-10123-01':;

SECTION_NUMBER 1
 '@TIMECARD_LIB.TIMECARD(SCH_1):PAGE12_I179@DISCRETE.DIODE_4_V1(CHIPS)':
 C_PATH='@timecard_lib.timecard(sch_1):page12_i179@discrete.diode_4_v1(chips)',
 P_PATH='@timecard_lib.timecard(sch_1):page23_i179@discrete.diode_4_v1(chips)',
 PATH='I179',
 DRAWING='@TIMECARD_LIB.TIMECARD(SCH_1):PAGE12',
 PHYS_PAGE='23',
 XY='(-3750,3350)',
 ROT='1',
 VER='1',
 LOCATION='CR4',
 CDS_LIB='discrete',
 CDS_PART_NAME='DIODE_4_V1-G122-10123-01',
 CLS_PN='G122-10123-01',
 PART_NUMBER='SR3.3.TCT',
 PRIM_FILE='./archive_libs/discrete/diode_4_v1/chips/chips.prt';

PART_NAME
 CR5 'DIODE_4_V1-G122-10123-01':;

SECTION_NUMBER 1
 '@TIMECARD_LIB.TIMECARD(SCH_1):PAGE12_I42@DISCRETE.DIODE_4_V1(CHIPS)':
 C_PATH='@timecard_lib.timecard(sch_1):page12_i42@discrete.diode_4_v1(chips)',
 P_PATH='@timecard_lib.timecard(sch_1):page23_i42@discrete.diode_4_v1(chips)',
 PATH='I42',
 DRAWING='@TIMECARD_LIB.TIMECARD(SCH_1):PAGE12',
 PHYS_PAGE='23',
 XY='(-3800,7700)',
 ROT='1',
 VER='1',
 CDS_LIB='discrete',
 CDS_PART_NAME='DIODE_4_V1-G122-10123-01',
 CLS_PN='G122-10123-01',
 PART_NUMBER='SR3.3.TCT',
 PRIM_FILE='./archive_libs/discrete/diode_4_v1/chips/chips.prt';

PART_NAME
 CR6 'DIODE_4_V1-G122-10123-01':;

SECTION_NUMBER 1
 '@TIMECARD_LIB.TIMECARD(SCH_1):PAGE127_I443@DISCRETE.DIODE_4_V1(CHIPS)':
 C_PATH='@timecard_lib.timecard(sch_1):page127_i443@discrete.diode_4_v1(chips)',
 P_PATH='@timecard_lib.timecard(sch_1):page10_i443@discrete.diode_4_v1(chips)',
 PATH='I443',
 DRAWING='@TIMECARD_LIB.TIMECARD(SCH_1):PAGE127',
 PHYS_PAGE='10',
 XY='(-12250,-200)',
 ROT='1',
 VER='1',
 LOCATION='CR6',
 CDS_LIB='discrete',
 CDS_PART_NAME='DIODE_4_V1-G122-10123-01',
 CLS_PN='G122-10123-01',
 PART_NUMBER='SR3.3.TCT',
 PRIM_FILE='./archive_libs/discrete/diode_4_v1/chips/chips.prt';

PART_NAME
 CR7 'DIODE_4_V1-G122-10123-01':;

SECTION_NUMBER 1
 '@TIMECARD_LIB.TIMECARD(SCH_1):PAGE127_I442@DISCRETE.DIODE_4_V1(CHIPS)':
 C_PATH='@timecard_lib.timecard(sch_1):page127_i442@discrete.diode_4_v1(chips)',
 P_PATH='@timecard_lib.timecard(sch_1):page10_i442@discrete.diode_4_v1(chips)',
 PATH='I442',
 DRAWING='@TIMECARD_LIB.TIMECARD(SCH_1):PAGE127',
 PHYS_PAGE='10',
 XY='(-11450,-200)',
 ROT='1',
 VER='1',
 LOCATION='CR7',
 CDS_LIB='discrete',
 CDS_PART_NAME='DIODE_4_V1-G122-10123-01',
 CLS_PN='G122-10123-01',
 PART_NUMBER='SR3.3.TCT',
 PRIM_FILE='./archive_libs/discrete/diode_4_v1/chips/chips.prt';

PART_NAME
 CR10 'DIODE_2E-G122-10190-01':;

SECTION_NUMBER 1
 '@TIMECARD_LIB.TIMECARD(SCH_1):PAGE15_I159@DISCRETE.DIODE_2E(CHIPS)':
 C_PATH='@timecard_lib.timecard(sch_1):page15_i159@discrete.diode_2e(chips)',
 P_PATH='@timecard_lib.timecard(sch_1):page27_i159@discrete.diode_2e(chips)',
 PATH='I159',
 DRAWING='@TIMECARD_LIB.TIMECARD(SCH_1):PAGE15',
 PHYS_PAGE='27',
 XY='(-11150,8950)',
 ROT='1',
 VER='1',
 CDS_LIB='discrete',
 CDS_PART_NAME='DIODE_2E-G122-10190-01',
 CLS_PN='G122-10190-01',
 PART_NUMBER='SMDJ12A',
 PRIM_FILE='./archive_libs/discrete/diode_2e/chips/chips.prt';

PART_NAME
 CR12 'DIODE_3F-G122-10080-01':;

SECTION_NUMBER 1
 '@TIMECARD_LIB.TIMECARD(SCH_1):PAGE15_I239@DISCRETE.DIODE_3F(CHIPS)':
 C_PATH='@timecard_lib.timecard(sch_1):page15_i239@discrete.diode_3f(chips)',
 P_PATH='@timecard_lib.timecard(sch_1):page27_i239@discrete.diode_3f(chips)',
 PATH='I239',
 DRAWING='@TIMECARD_LIB.TIMECARD(SCH_1):PAGE15',
 PHYS_PAGE='27',
 XY='(-11950,9500)',
 ROT='0',
 VER='1',
 LOCATION='CR12',
 CDS_LIB='discrete',
 CDS_PART_NAME='DIODE_3F-G122-10080-01',
 CLS_PN='G122-10080-01',
 PART_NUMBER='V20PW60C-M3/I',
 PRIM_FILE='./archive_libs/discrete/diode_3f/chips/chips.prt';

PART_NAME
 DS1 'OPTICAL-G170-10143-01':;

SECTION_NUMBER 1
 '@TIMECARD_LIB.TIMECARD(SCH_1):PAGE14_I12@DISCRETE.OPTICAL(CHIPS)':
 C_PATH='@timecard_lib.timecard(sch_1):page14_i12@discrete.optical(chips)',
 P_PATH='@timecard_lib.timecard(sch_1):page26_i12@discrete.optical(chips)',
 PATH='I12',
 DRAWING='@TIMECARD_LIB.TIMECARD(SCH_1):PAGE14',
 PHYS_PAGE='26',
 XY='(-10500,12400)',
 ROT='2',
 VER='1',
 CDS_LIB='discrete',
 CDS_PART_NAME='OPTICAL-G170-10143-01',
 CLS_PN='G170-10143-01',
 PART_NUMBER='LTST-C190KGKT',
 PRIM_FILE='./archive_libs/discrete/optical/chips/chips.prt';

PART_NAME
 DS2 'OPTICAL-G170-10143-01':;

SECTION_NUMBER 1
 '@TIMECARD_LIB.TIMECARD(SCH_1):PAGE14_I11@DISCRETE.OPTICAL(CHIPS)':
 C_PATH='@timecard_lib.timecard(sch_1):page14_i11@discrete.optical(chips)',
 P_PATH='@timecard_lib.timecard(sch_1):page26_i11@discrete.optical(chips)',
 PATH='I11',
 DRAWING='@TIMECARD_LIB.TIMECARD(SCH_1):PAGE14',
 PHYS_PAGE='26',
 XY='(-10500,12050)',
 ROT='2',
 VER='1',
 CDS_LIB='discrete',
 CDS_PART_NAME='OPTICAL-G170-10143-01',
 CLS_PN='G170-10143-01',
 PART_NUMBER='LTST-C190KGKT',
 PRIM_FILE='./archive_libs/discrete/optical/chips/chips.prt';

PART_NAME
 DS3 'OPTICAL-G170-10143-01':;

SECTION_NUMBER 1
 '@TIMECARD_LIB.TIMECARD(SCH_1):PAGE14_I136@DISCRETE.OPTICAL(CHIPS)':
 C_PATH='@timecard_lib.timecard(sch_1):page14_i136@discrete.optical(chips)',
 P_PATH='@timecard_lib.timecard(sch_1):page26_i136@discrete.optical(chips)',
 PATH='I136',
 DRAWING='@TIMECARD_LIB.TIMECARD(SCH_1):PAGE14',
 PHYS_PAGE='26',
 XY='(-10500,11700)',
 ROT='2',
 VER='1',
 LOCATION='DS3',
 CDS_LIB='discrete',
 CDS_PART_NAME='OPTICAL-G170-10143-01',
 CLS_PN='G170-10143-01',
 PART_NUMBER='LTST-C190KGKT',
 PRIM_FILE='./archive_libs/discrete/optical/chips/chips.prt';

PART_NAME
 DS4 'OPTICAL-G170-10143-01':;

SECTION_NUMBER 1
 '@TIMECARD_LIB.TIMECARD(SCH_1):PAGE14_I137@DISCRETE.OPTICAL(CHIPS)':
 C_PATH='@timecard_lib.timecard(sch_1):page14_i137@discrete.optical(chips)',
 P_PATH='@timecard_lib.timecard(sch_1):page26_i137@discrete.optical(chips)',
 PATH='I137',
 DRAWING='@TIMECARD_LIB.TIMECARD(SCH_1):PAGE14',
 PHYS_PAGE='26',
 XY='(-10500,11350)',
 ROT='2',
 VER='1',
 LOCATION='DS4',
 CDS_LIB='discrete',
 CDS_PART_NAME='OPTICAL-G170-10143-01',
 CLS_PN='G170-10143-01',
 PART_NUMBER='LTST-C190KGKT',
 PRIM_FILE='./archive_libs/discrete/optical/chips/chips.prt';

PART_NAME
 DS5 'OPTICAL-G170-10143-01':;

SECTION_NUMBER 1
 '@TIMECARD_LIB.TIMECARD(SCH_1):PAGE14_I143@DISCRETE.OPTICAL(CHIPS)':
 C_PATH='@timecard_lib.timecard(sch_1):page14_i143@discrete.optical(chips)',
 P_PATH='@timecard_lib.timecard(sch_1):page26_i143@discrete.optical(chips)',
 PATH='I143',
 DRAWING='@TIMECARD_LIB.TIMECARD(SCH_1):PAGE14',
 PHYS_PAGE='26',
 XY='(-10600,8100)',
 ROT='2',
 VER='1',
 LOCATION='DS5',
 CDS_LIB='discrete',
 CDS_PART_NAME='OPTICAL-G170-10143-01',
 CLS_PN='G170-10143-01',
 PART_NUMBER='LTST-C190KGKT',
 PRIM_FILE='./archive_libs/discrete/optical/chips/chips.prt';

PART_NAME
 DS6 'OPTICAL-G170-10143-01':;

SECTION_NUMBER 1
 '@TIMECARD_LIB.TIMECARD(SCH_1):PAGE14_I140@DISCRETE.OPTICAL(CHIPS)':
 C_PATH='@timecard_lib.timecard(sch_1):page14_i140@discrete.optical(chips)',
 P_PATH='@timecard_lib.timecard(sch_1):page26_i140@discrete.optical(chips)',
 PATH='I140',
 DRAWING='@TIMECARD_LIB.TIMECARD(SCH_1):PAGE14',
 PHYS_PAGE='26',
 XY='(-10600,9200)',
 ROT='2',
 VER='1',
 LOCATION='DS6',
 CDS_LIB='discrete',
 CDS_PART_NAME='OPTICAL-G170-10143-01',
 CLS_PN='G170-10143-01',
 PART_NUMBER='LTST-C190KGKT',
 PRIM_FILE='./archive_libs/discrete/optical/chips/chips.prt';

PART_NAME
 DS7 'OPTICAL-G170-10143-01':;

SECTION_NUMBER 1
 '@TIMECARD_LIB.TIMECARD(SCH_1):PAGE14_I141@DISCRETE.OPTICAL(CHIPS)':
 C_PATH='@timecard_lib.timecard(sch_1):page14_i141@discrete.optical(chips)',
 P_PATH='@timecard_lib.timecard(sch_1):page26_i141@discrete.optical(chips)',
 PATH='I141',
 DRAWING='@TIMECARD_LIB.TIMECARD(SCH_1):PAGE14',
 PHYS_PAGE='26',
 XY='(-10600,8850)',
 ROT='2',
 VER='1',
 LOCATION='DS7',
 CDS_LIB='discrete',
 CDS_PART_NAME='OPTICAL-G170-10143-01',
 CLS_PN='G170-10143-01',
 PART_NUMBER='LTST-C190KGKT',
 PRIM_FILE='./archive_libs/discrete/optical/chips/chips.prt';

PART_NAME
 DS8 'OPTICAL-G170-10143-01':;

SECTION_NUMBER 1
 '@TIMECARD_LIB.TIMECARD(SCH_1):PAGE14_I142@DISCRETE.OPTICAL(CHIPS)':
 C_PATH='@timecard_lib.timecard(sch_1):page14_i142@discrete.optical(chips)',
 P_PATH='@timecard_lib.timecard(sch_1):page26_i142@discrete.optical(chips)',
 PATH='I142',
 DRAWING='@TIMECARD_LIB.TIMECARD(SCH_1):PAGE14',
 PHYS_PAGE='26',
 XY='(-10600,8500)',
 ROT='2',
 VER='1',
 LOCATION='DS8',
 CDS_LIB='discrete',
 CDS_PART_NAME='OPTICAL-G170-10143-01',
 CLS_PN='G170-10143-01',
 PART_NUMBER='LTST-C190KGKT',
 PRIM_FILE='./archive_libs/discrete/optical/chips/chips.prt';

PART_NAME
 DS9 'OPTICAL-G170-10143-01':;

SECTION_NUMBER 1
 '@TIMECARD_LIB.TIMECARD(SCH_1):PAGE14_I292@DISCRETE.OPTICAL(CHIPS)':
 C_PATH='@timecard_lib.timecard(sch_1):page14_i292@discrete.optical(chips)',
 P_PATH='@timecard_lib.timecard(sch_1):page26_i292@discrete.optical(chips)',
 PATH='I292',
 DRAWING='@TIMECARD_LIB.TIMECARD(SCH_1):PAGE14',
 PHYS_PAGE='26',
 XY='(-11250,10200)',
 ROT='2',
 VER='1',
 LOCATION='DS9',
 CDS_LIB='discrete',
 CDS_PART_NAME='OPTICAL-G170-10143-01',
 CLS_PN='G170-10143-01',
 PART_NUMBER='LTST-C190KGKT',
 PRIM_FILE='./archive_libs/discrete/optical/chips/chips.prt';

PART_NAME
 DS10 'OPTICAL-G170-10143-01':;

SECTION_NUMBER 1
 '@TIMECARD_LIB.TIMECARD(SCH_1):PAGE14_I138@DISCRETE.OPTICAL(CHIPS)':
 C_PATH='@timecard_lib.timecard(sch_1):page14_i138@discrete.optical(chips)',
 P_PATH='@timecard_lib.timecard(sch_1):page26_i138@discrete.optical(chips)',
 PATH='I138',
 DRAWING='@TIMECARD_LIB.TIMECARD(SCH_1):PAGE14',
 PHYS_PAGE='26',
 XY='(-10500,10950)',
 ROT='2',
 VER='1',
 LOCATION='DS10',
 CDS_LIB='discrete',
 CDS_PART_NAME='OPTICAL-G170-10143-01',
 CLS_PN='G170-10143-01',
 PART_NUMBER='LTST-C190KGKT',
 PRIM_FILE='./archive_libs/discrete/optical/chips/chips.prt';

PART_NAME
 DS11 'OPTICAL-G170-10143-01':;

SECTION_NUMBER 1
 '@TIMECARD_LIB.TIMECARD(SCH_1):PAGE14_I139@DISCRETE.OPTICAL(CHIPS)':
 C_PATH='@timecard_lib.timecard(sch_1):page14_i139@discrete.optical(chips)',
 P_PATH='@timecard_lib.timecard(sch_1):page26_i139@discrete.optical(chips)',
 PATH='I139',
 DRAWING='@TIMECARD_LIB.TIMECARD(SCH_1):PAGE14',
 PHYS_PAGE='26',
 XY='(-10500,10650)',
 ROT='2',
 VER='1',
 LOCATION='DS11',
 CDS_LIB='discrete',
 CDS_PART_NAME='OPTICAL-G170-10143-01',
 CLS_PN='G170-10143-01',
 PART_NUMBER='LTST-C190KGKT',
 PRIM_FILE='./archive_libs/discrete/optical/chips/chips.prt';

PART_NAME
 DS12 'OPTICAL-G170-10143-01':;

SECTION_NUMBER 1
 '@TIMECARD_LIB.TIMECARD(SCH_1):PAGE14_I289@DISCRETE.OPTICAL(CHIPS)':
 C_PATH='@timecard_lib.timecard(sch_1):page14_i289@discrete.optical(chips)',
 P_PATH='@timecard_lib.timecard(sch_1):page26_i289@discrete.optical(chips)',
 PATH='I289',
 DRAWING='@TIMECARD_LIB.TIMECARD(SCH_1):PAGE14',
 PHYS_PAGE='26',
 XY='(-10600,7050)',
 ROT='2',
 VER='1',
 CDS_LIB='discrete',
 CDS_PART_NAME='OPTICAL-G170-10143-01',
 CLS_PN='G170-10143-01',
 PART_NUMBER='LTST-C190KGKT',
 PRIM_FILE='./archive_libs/discrete/optical/chips/chips.prt';

PART_NAME
 DS14 'LED_4P_V14-G170-10189-01':;

SECTION_NUMBER 1
 '@TIMECARD_LIB.TIMECARD(SCH_1):PAGE14_I265@DISCRETE.LED_4P_V14(CHIPS)':
 C_PATH='@timecard_lib.timecard(sch_1):page14_i265@discrete.led_4p_v14(chips)',
 P_PATH='@timecard_lib.timecard(sch_1):page26_i265@discrete.led_4p_v14(chips)',
 PATH='I265',
 DRAWING='@TIMECARD_LIB.TIMECARD(SCH_1):PAGE14',
 PHYS_PAGE='26',
 XY='(-1200,11650)',
 ROT='2',
 VER='1',
 LOCATION='DS14',
 CDS_LIB='discrete',
 CDS_PART_NAME='LED_4P_V14-G170-10189-01',
 CLS_PN='G170-10189-01',
 PART_NUMBER='APFA2507QBDSEEZGKC',
 PRIM_FILE='./archive_libs/discrete/led_4p_v14/chips/chips.prt';

PART_NAME
 DS15 'LED_4P_V14-G170-10189-01':;

SECTION_NUMBER 1
 '@TIMECARD_LIB.TIMECARD(SCH_1):PAGE14_I266@DISCRETE.LED_4P_V14(CHIPS)':
 C_PATH='@timecard_lib.timecard(sch_1):page14_i266@discrete.led_4p_v14(chips)',
 P_PATH='@timecard_lib.timecard(sch_1):page26_i266@discrete.led_4p_v14(chips)',
 PATH='I266',
 DRAWING='@TIMECARD_LIB.TIMECARD(SCH_1):PAGE14',
 PHYS_PAGE='26',
 XY='(-1200,10150)',
 ROT='2',
 VER='1',
 LOCATION='DS15',
 CDS_LIB='discrete',
 CDS_PART_NAME='LED_4P_V14-G170-10189-01',
 CLS_PN='G170-10189-01',
 PART_NUMBER='APFA2507QBDSEEZGKC',
 PRIM_FILE='./archive_libs/discrete/led_4p_v14/chips/chips.prt';

PART_NAME
 DS16 'LED_4P_V14-G170-10189-01':;

SECTION_NUMBER 1
 '@TIMECARD_LIB.TIMECARD(SCH_1):PAGE14_I267@DISCRETE.LED_4P_V14(CHIPS)':
 C_PATH='@timecard_lib.timecard(sch_1):page14_i267@discrete.led_4p_v14(chips)',
 P_PATH='@timecard_lib.timecard(sch_1):page26_i267@discrete.led_4p_v14(chips)',
 PATH='I267',
 DRAWING='@TIMECARD_LIB.TIMECARD(SCH_1):PAGE14',
 PHYS_PAGE='26',
 XY='(-1200,8600)',
 ROT='2',
 VER='1',
 LOCATION='DS16',
 CDS_LIB='discrete',
 CDS_PART_NAME='LED_4P_V14-G170-10189-01',
 CLS_PN='G170-10189-01',
 PART_NUMBER='APFA2507QBDSEEZGKC',
 PRIM_FILE='./archive_libs/discrete/led_4p_v14/chips/chips.prt';

PART_NAME
 DS17 'LED_4P_V14-G170-10189-01':;

SECTION_NUMBER 1
 '@TIMECARD_LIB.TIMECARD(SCH_1):PAGE14_I268@DISCRETE.LED_4P_V14(CHIPS)':
 C_PATH='@timecard_lib.timecard(sch_1):page14_i268@discrete.led_4p_v14(chips)',
 P_PATH='@timecard_lib.timecard(sch_1):page26_i268@discrete.led_4p_v14(chips)',
 PATH='I268',
 DRAWING='@TIMECARD_LIB.TIMECARD(SCH_1):PAGE14',
 PHYS_PAGE='26',
 XY='(-1200,7050)',
 ROT='2',
 VER='1',
 LOCATION='DS17',
 CDS_LIB='discrete',
 CDS_PART_NAME='LED_4P_V14-G170-10189-01',
 CLS_PN='G170-10189-01',
 PART_NUMBER='APFA2507QBDSEEZGKC',
 PRIM_FILE='./archive_libs/discrete/led_4p_v14/chips/chips.prt';

PART_NAME
 DS18 'LED_4P_V14-G170-10189-01':;

SECTION_NUMBER 1
 '@TIMECARD_LIB.TIMECARD(SCH_1):PAGE14_I269@DISCRETE.LED_4P_V14(CHIPS)':
 C_PATH='@timecard_lib.timecard(sch_1):page14_i269@discrete.led_4p_v14(chips)',
 P_PATH='@timecard_lib.timecard(sch_1):page26_i269@discrete.led_4p_v14(chips)',
 PATH='I269',
 DRAWING='@TIMECARD_LIB.TIMECARD(SCH_1):PAGE14',
 PHYS_PAGE='26',
 XY='(-1200,5500)',
 ROT='2',
 VER='1',
 LOCATION='DS18',
 CDS_LIB='discrete',
 CDS_PART_NAME='LED_4P_V14-G170-10189-01',
 CLS_PN='G170-10189-01',
 PART_NUMBER='APFA2507QBDSEEZGKC',
 PRIM_FILE='./archive_libs/discrete/led_4p_v14/chips/chips.prt';

PART_NAME
 DS19 'OPTICAL-G170-10143-01':;

SECTION_NUMBER 1
 '@TIMECARD_LIB.TIMECARD(SCH_1):PAGE14_I191@DISCRETE.OPTICAL(CHIPS)':
 C_PATH='@timecard_lib.timecard(sch_1):page14_i191@discrete.optical(chips)',
 P_PATH='@timecard_lib.timecard(sch_1):page26_i191@discrete.optical(chips)',
 PATH='I191',
 DRAWING='@TIMECARD_LIB.TIMECARD(SCH_1):PAGE14',
 PHYS_PAGE='26',
 XY='(-10600,7750)',
 ROT='2',
 VER='1',
 CDS_LIB='discrete',
 CDS_PART_NAME='OPTICAL-G170-10143-01',
 CLS_PN='G170-10143-01',
 PART_NUMBER='LTST-C190KGKT',
 PRIM_FILE='./archive_libs/discrete/optical/chips/chips.prt';

PART_NAME
 DS20 'OPTICAL-G170-10143-01':;

SECTION_NUMBER 1
 '@TIMECARD_LIB.TIMECARD(SCH_1):PAGE14_I194@DISCRETE.OPTICAL(CHIPS)':
 C_PATH='@timecard_lib.timecard(sch_1):page14_i194@discrete.optical(chips)',
 P_PATH='@timecard_lib.timecard(sch_1):page26_i194@discrete.optical(chips)',
 PATH='I194',
 DRAWING='@TIMECARD_LIB.TIMECARD(SCH_1):PAGE14',
 PHYS_PAGE='26',
 XY='(-10600,7400)',
 ROT='2',
 VER='1',
 CDS_LIB='discrete',
 CDS_PART_NAME='OPTICAL-G170-10143-01',
 CLS_PN='G170-10143-01',
 PART_NUMBER='LTST-C190KGKT',
 PRIM_FILE='./archive_libs/discrete/optical/chips/chips.prt';

PART_NAME
 FU1 'FUSE-G280-10012-01,2.5A':;

SECTION_NUMBER 1
 '@TIMECARD_LIB.TIMECARD(SCH_1):PAGE15_I223@PASSIVE.FUSE(CHIPS)':
 C_PATH='@timecard_lib.timecard(sch_1):page15_i223@passive.fuse(chips)',
 P_PATH='@timecard_lib.timecard(sch_1):page27_i223@passive.fuse(chips)',
 PATH='I223',
 DRAWING='@TIMECARD_LIB.TIMECARD(SCH_1):PAGE15',
 PACKAGE='0603',
 PHYS_PAGE='27',
 XY='(-3500,9400)',
 ROT='0',
 VER='1',
 CDS_LIB='passive',
 CDS_PART_NAME='FUSE-G280-10012-01,2.5A',
 NO_ASSY='TRUE',
 CLS_PN='G280-10012-01',
 VALUE='2.5A',
 PRIM_FILE='./archive_libs/passive/fuse/chips/chips.prt';

PART_NAME
 FU3 'FUSE-G280-10049-01,1A':;

SECTION_NUMBER 1
 '@TIMECARD_LIB.TIMECARD(SCH_1):PAGE527_I244@PASSIVE.FUSE(CHIPS)':
 C_PATH='@timecard_lib.timecard(sch_1):page527_i244@passive.fuse(chips)',
 P_PATH='@timecard_lib.timecard(sch_1):page21_i244@passive.fuse(chips)',
 PATH='I244',
 DRAWING='@TIMECARD_LIB.TIMECARD(SCH_1):PAGE527',
 PHYS_PAGE='21',
 XY='(1650,1850)',
 ROT='0',
 VER='1',
 CDS_LIB='passive',
 CDS_PART_NAME='FUSE-G280-10049-01,1A',
 NO_ASSY='TRUE',
 CLS_PN='G280-10049-01',
 PART_NUMBER='0438001.WR',
 VALUE='1A',
 PRIM_FILE='./archive_libs/passive/fuse/chips/chips.prt';

PART_NAME
 GF1 'CONN_64P_GF-S_M_EF64_PCIE_P039A':;

SECTION_NUMBER 1
 '@TIMECARD_LIB.TIMECARD(SCH_1):PAGE3_I61@CONNECTOR.CONN_64P_GF(CHIPS)':
 C_PATH='@timecard_lib.timecard(sch_1):page3_i61@connector.conn_64p_gf(chips)',
 P_PATH='@timecard_lib.timecard(sch_1):page9_i61@connector.conn_64p_gf(chips)',
 PATH='I61',
 DRAWING='@TIMECARD_LIB.TIMECARD(SCH_1):PAGE3',
 PHYS_PAGE='9',
 XY='(-7050,8350)',
 ROT='0',
 VER='1',
 CDS_LIB='connector',
 CDS_PART_NAME='CONN_64P_GF-S_M_EF64_PCIE_P039A',
 NO_ASSY='TRUE',
 CLS_PN='S_M_EF64_PCIE_P0394_V1',
 PRIM_FILE='./archive_libs/connector/conn_64p_gf/chips/chips.prt';

PART_NAME
 J1 'CONN_JACK_1P_GH4_S_TH-G200-130A':;

SECTION_NUMBER 1
 '@TIMECARD_LIB.TIMECARD(SCH_1):PAGE12_I290@CONNECTOR.CONN_JACK_1P_GH4_S_TH(CHIPS)':
 C_PATH='@timecard_lib.timecard(sch_1):page12_i290@connector.conn_jack_1p_gh4_s_~
th(chips)',
 P_PATH='@timecard_lib.timecard(sch_1):page23_i290@connector.conn_jack_1p_gh4_s_~
th(chips)',
 PATH='I290',
 DRAWING='@TIMECARD_LIB.TIMECARD(SCH_1):PAGE12',
 PHYS_PAGE='23',
 XY='(-2650,9150)',
 ROT='0',
 VER='1',
 LOCATION='J1',
 CDS_LIB='connector',
 CDS_PART_NAME='CONN_JACK_1P_GH4_S_TH-G200-130A',
 CLS_PN='G200-13091-01',
 VALUE='2081680-1',
 PRIM_FILE='./archive_libs/connector/conn_jack_1p_gh4_s_th/chips/chips.prt';

PART_NAME
 J2 'CONN_JACK_1P_GH4_S_TH-G200-130A':;

SECTION_NUMBER 1
 '@TIMECARD_LIB.TIMECARD(SCH_1):PAGE12_I294@CONNECTOR.CONN_JACK_1P_GH4_S_TH(CHIPS)':
 C_PATH='@timecard_lib.timecard(sch_1):page12_i294@connector.conn_jack_1p_gh4_s_~
th(chips)',
 P_PATH='@timecard_lib.timecard(sch_1):page23_i294@connector.conn_jack_1p_gh4_s_~
th(chips)',
 PATH='I294',
 DRAWING='@TIMECARD_LIB.TIMECARD(SCH_1):PAGE12',
 PHYS_PAGE='23',
 XY='(-2600,7000)',
 ROT='0',
 VER='1',
 LOCATION='J2',
 CDS_LIB='connector',
 CDS_PART_NAME='CONN_JACK_1P_GH4_S_TH-G200-130A',
 CLS_PN='G200-13091-01',
 VALUE='2081680-1',
 PRIM_FILE='./archive_libs/connector/conn_jack_1p_gh4_s_th/chips/chips.prt';

PART_NAME
 J3 'CONN_JACK_1P_GH4_S_TH-G200-130A':;

SECTION_NUMBER 1
 '@TIMECARD_LIB.TIMECARD(SCH_1):PAGE12_I297@CONNECTOR.CONN_JACK_1P_GH4_S_TH(CHIPS)':
 C_PATH='@timecard_lib.timecard(sch_1):page12_i297@connector.conn_jack_1p_gh4_s_~
th(chips)',
 P_PATH='@timecard_lib.timecard(sch_1):page23_i297@connector.conn_jack_1p_gh4_s_~
th(chips)',
 PATH='I297',
 DRAWING='@TIMECARD_LIB.TIMECARD(SCH_1):PAGE12',
 PHYS_PAGE='23',
 XY='(-2600,4850)',
 ROT='0',
 VER='1',
 LOCATION='J3',
 CDS_LIB='connector',
 CDS_PART_NAME='CONN_JACK_1P_GH4_S_TH-G200-130A',
 CLS_PN='G200-13091-01',
 VALUE='2081680-1',
 PRIM_FILE='./archive_libs/connector/conn_jack_1p_gh4_s_th/chips/chips.prt';

PART_NAME
 J4 'CONN_JACK_1P_GH4_S_TH-G200-130A':;

SECTION_NUMBER 1
 '@TIMECARD_LIB.TIMECARD(SCH_1):PAGE12_I300@CONNECTOR.CONN_JACK_1P_GH4_S_TH(CHIPS)':
 C_PATH='@timecard_lib.timecard(sch_1):page12_i300@connector.conn_jack_1p_gh4_s_~
th(chips)',
 P_PATH='@timecard_lib.timecard(sch_1):page23_i300@connector.conn_jack_1p_gh4_s_~
th(chips)',
 PATH='I300',
 DRAWING='@TIMECARD_LIB.TIMECARD(SCH_1):PAGE12',
 PHYS_PAGE='23',
 XY='(-2550,2700)',
 ROT='0',
 VER='1',
 LOCATION='J4',
 CDS_LIB='connector',
 CDS_PART_NAME='CONN_JACK_1P_GH4_S_TH-G200-130A',
 CLS_PN='G200-13091-01',
 VALUE='2081680-1',
 PRIM_FILE='./archive_libs/connector/conn_jack_1p_gh4_s_th/chips/chips.prt';

PART_NAME
 J5 'CONN_HDR_2X6_F_S_SMT-G200-1313A':;

SECTION_NUMBER 1
 '@TIMECARD_LIB.TIMECARD(SCH_1):PAGE16_I1614@CONNECTOR.CONN_HDR_2X6_F_S_SMT(CHIPS)':
 C_PATH='@timecard_lib.timecard(sch_1):page16_i1614@connector.conn_hdr_2x6_f_s_s~
mt(chips)',
 P_PATH='@timecard_lib.timecard(sch_1):page25_i1614@connector.conn_hdr_2x6_f_s_s~
mt(chips)',
 PATH='I1614',
 DRAWING='@TIMECARD_LIB.TIMECARD(SCH_1):PAGE16',
 PHYS_PAGE='25',
 XY='(-5900,2850)',
 ROT='4',
 VER='1',
 LOCATION='J5',
 CDS_LIB='connector',
 CDS_PART_NAME='CONN_HDR_2X6_F_S_SMT-G200-1313A',
 CLS_PN='G200-13133-01',
 VALUE='SMH-106-02-L-D-TR',
 PRIM_FILE='./archive_libs/connector/conn_hdr_2x6_f_s_smt/chips/chips.prt';

PART_NAME
 J9 'CONN_HDR_2X2_M_S_SMT-G200-1068A':;

SECTION_NUMBER 1
 '@TIMECARD_LIB.TIMECARD(SCH_1):PAGE5_I126@CONNECTOR.CONN_HDR_2X2_M_S_SMT(CHIPS)':
 C_PATH='@timecard_lib.timecard(sch_1):page5_i126@connector.conn_hdr_2x2_m_s_smt~
(chips)',
 P_PATH='@timecard_lib.timecard(sch_1):page16_i126@connector.conn_hdr_2x2_m_s_sm~
t(chips)',
 PATH='I126',
 DRAWING='@TIMECARD_LIB.TIMECARD(SCH_1):PAGE5',
 PHYS_PAGE='16',
 XY='(-10150,9450)',
 ROT='2',
 VER='1',
 LOCATION='J9',
 CDS_LIB='connector',
 CDS_PART_NAME='CONN_HDR_2X2_M_S_SMT-G200-1068A',
 CLS_PN='G200-10686-01',
 PART_NUMBER='95278-101A04LF',
 PRIM_FILE='./archive_libs/connector/conn_hdr_2x2_m_s_smt/chips/chips.prt';

PART_NAME
 J10 'G200_10283_01-G200-10283-01':;

SECTION_NUMBER 1
 '@TIMECARD_LIB.TIMECARD(SCH_1):PAGE524_I173@CONNECTOR.G200_10283_01(CHIPS)':
 C_PATH='@timecard_lib.timecard(sch_1):page524_i173@connector.g200_10283_01(chip~
s)',
 P_PATH='@timecard_lib.timecard(sch_1):page24_i173@connector.g200_10283_01(chips~
)',
 PATH='I173',
 DRAWING='@TIMECARD_LIB.TIMECARD(SCH_1):PAGE524',
 PHYS_PAGE='24',
 XY='(-2650,8850)',
 ROT='0',
 VER='1',
 CDS_LIB='connector',
 CDS_PART_NAME='G200_10283_01-G200-10283-01',
 CLS_PN='G200-10283-01',
 PART_NUMBER='95278-101A10LF',
 PRIM_FILE='./archive_libs/connector/g200_10283_01/chips/chips.prt';

PART_NAME
 J11 'CONN_USB_1X5_G2_GH4_F_RA_SMT-GA':;

SECTION_NUMBER 1
 '@TIMECARD_LIB.TIMECARD(SCH_1):PAGE527_I2@CONNECTOR.CONN_USB_1X5_G2_GH4_F_RA_SMT(CHIPS)':
 C_PATH='@timecard_lib.timecard(sch_1):page527_i2@connector.conn_usb_1x5_g2_gh4_~
f_ra_smt(chips)',
 P_PATH='@timecard_lib.timecard(sch_1):page21_i2@connector.conn_usb_1x5_g2_gh4_f~
_ra_smt(chips)',
 PATH='I2',
 DRAWING='@TIMECARD_LIB.TIMECARD(SCH_1):PAGE527',
 PHYS_PAGE='21',
 XY='(-11200,800)',
 ROT='2',
 VER='1',
 CDS_LIB='connector',
 CDS_PART_NAME='CONN_USB_1X5_G2_GH4_F_RA_SMT-GA',
 NO_ASSY='TRUE',
 CLS_PN='G200-12192-01',
 VALUE='1050171001',
 PRIM_FILE='./archive_libs/connector/conn_usb_1x5_g2_gh4_f_ra_smt/chips/chips.pr~
t';

PART_NAME
 J13 'CONN_USB_14P_GH4_F_RA_TH-G200-A':;

SECTION_NUMBER 1
 '@TIMECARD_LIB.TIMECARD(SCH_1):PAGE524_I495@CONNECTOR.CONN_USB_14P_GH4_F_RA_TH(CHIPS)':
 C_PATH='@timecard_lib.timecard(sch_1):page524_i495@connector.conn_usb_14p_gh4_f~
_ra_th(chips)',
 P_PATH='@timecard_lib.timecard(sch_1):page24_i495@connector.conn_usb_14p_gh4_f_~
ra_th(chips)',
 PATH='I495',
 DRAWING='@TIMECARD_LIB.TIMECARD(SCH_1):PAGE524',
 PHYS_PAGE='24',
 XY='(-13750,10450)',
 ROT='0',
 VER='1',
 LOCATION='J13',
 CDS_LIB='connector',
 CDS_PART_NAME='CONN_USB_14P_GH4_F_RA_TH-G200-A',
 CLS_PN='G200-13135-01',
 VALUE='2169890002',
 PRIM_FILE='./archive_libs/connector/conn_usb_14p_gh4_f_ra_th/chips/chips.prt';

PART_NAME
 J14 'G200_10283_01-G200-10283-01':;

SECTION_NUMBER 1
 '@TIMECARD_LIB.TIMECARD(SCH_1):PAGE127_I427@CONNECTOR.G200_10283_01(CHIPS)':
 C_PATH='@timecard_lib.timecard(sch_1):page127_i427@connector.g200_10283_01(chip~
s)',
 P_PATH='@timecard_lib.timecard(sch_1):page10_i427@connector.g200_10283_01(chips~
)',
 PATH='I427',
 DRAWING='@TIMECARD_LIB.TIMECARD(SCH_1):PAGE127',
 PHYS_PAGE='10',
 XY='(-13250,650)',
 ROT='2',
 VER='1',
 CDS_LIB='connector',
 CDS_PART_NAME='G200_10283_01-G200-10283-01',
 CLS_PN='G200-10283-01',
 PART_NUMBER='95278-101A10LF',
 PRIM_FILE='./archive_libs/connector/g200_10283_01/chips/chips.prt';

PART_NAME
 J17 'CONN_HDR_2X2_M_S_SMT-G200-1068A':;

SECTION_NUMBER 1
 '@TIMECARD_LIB.TIMECARD(SCH_1):PAGE5_I127@CONNECTOR.CONN_HDR_2X2_M_S_SMT(CHIPS)':
 C_PATH='@timecard_lib.timecard(sch_1):page5_i127@connector.conn_hdr_2x2_m_s_smt~
(chips)',
 P_PATH='@timecard_lib.timecard(sch_1):page16_i127@connector.conn_hdr_2x2_m_s_sm~
t(chips)',
 PATH='I127',
 DRAWING='@TIMECARD_LIB.TIMECARD(SCH_1):PAGE5',
 PHYS_PAGE='16',
 XY='(-2450,5650)',
 ROT='0',
 VER='1',
 LOCATION='J17',
 CDS_LIB='connector',
 CDS_PART_NAME='CONN_HDR_2X2_M_S_SMT-G200-1068A',
 CLS_PN='G200-10686-01',
 PART_NUMBER='95278-101A04LF',
 PRIM_FILE='./archive_libs/connector/conn_hdr_2x2_m_s_smt/chips/chips.prt';

PART_NAME
 J18 'CONN_HDR_1X3_M_S_SMT-G205-1002A':;

SECTION_NUMBER 1
 '@TIMECARD_LIB.TIMECARD(SCH_1):PAGE527_I198@CONNECTOR.CONN_HDR_1X3_M_S_SMT(CHIPS)':
 C_PATH='@timecard_lib.timecard(sch_1):page527_i198@connector.conn_hdr_1x3_m_s_s~
mt(chips)',
 P_PATH='@timecard_lib.timecard(sch_1):page21_i198@connector.conn_hdr_1x3_m_s_sm~
t(chips)',
 PATH='I198',
 DRAWING='@TIMECARD_LIB.TIMECARD(SCH_1):PAGE527',
 PHYS_PAGE='21',
 XY='(-5600,4000)',
 ROT='0',
 VER='1',
 CDS_LIB='connector',
 CDS_PART_NAME='CONN_HDR_1X3_M_S_SMT-G205-1002A',
 NO_ASSY='TRUE',
 CLS_PN='G205-10020-01',
 PRIM_FILE='./archive_libs/connector/conn_hdr_1x3_m_s_smt/chips/chips.prt';

PART_NAME
 L1 'INDUCTOR_2-G190-10424-01,4.7UHA':;

SECTION_NUMBER 1
 '@TIMECARD_LIB.TIMECARD(SCH_1):PAGE516_I36@PASSIVE.INDUCTOR_2(CHIPS)':
 C_PATH='@timecard_lib.timecard(sch_1):page516_i36@passive.inductor_2(chips)',
 P_PATH='@timecard_lib.timecard(sch_1):page32_i36@passive.inductor_2(chips)',
 PATH='I36',
 DRAWING='@TIMECARD_LIB.TIMECARD(SCH_1):PAGE516',
 PHYS_PAGE='32',
 XY='(-4850,7100)',
 ROT='0',
 VER='1',
 CDS_LIB='passive',
 CDS_PART_NAME='INDUCTOR_2-G190-10424-01,4.7UHA',
 TOLERANCE='20%',
 CLS_PN='G190-10424-01',
 VALUE='4.7UH',
 PRIM_FILE='./archive_libs/passive/inductor_2/chips/chips.prt';

PART_NAME
 L2 'INDUCTOR_2-G190-10424-01,4.7UHA':;

SECTION_NUMBER 1
 '@TIMECARD_LIB.TIMECARD(SCH_1):PAGE517_I28@PASSIVE.INDUCTOR_2(CHIPS)':
 C_PATH='@timecard_lib.timecard(sch_1):page517_i28@passive.inductor_2(chips)',
 P_PATH='@timecard_lib.timecard(sch_1):page28_i28@passive.inductor_2(chips)',
 PATH='I28',
 DRAWING='@TIMECARD_LIB.TIMECARD(SCH_1):PAGE517',
 PHYS_PAGE='28',
 XY='(-4600,6300)',
 ROT='0',
 VER='1',
 CDS_LIB='passive',
 CDS_PART_NAME='INDUCTOR_2-G190-10424-01,4.7UHA',
 TOLERANCE='20%',
 CLS_PN='G190-10424-01',
 VALUE='4.7UH',
 PRIM_FILE='./archive_libs/passive/inductor_2/chips/chips.prt';

PART_NAME
 L3 'FERRITEBEAD-G191-10101-01,26OHA':;

SECTION_NUMBER 1
 '@TIMECARD_LIB.TIMECARD(SCH_1):PAGE527_I91@PASSIVE.FERRITEBEAD(CHIPS)':
 C_PATH='@timecard_lib.timecard(sch_1):page527_i91@passive.ferritebead(chips)',
 P_PATH='@timecard_lib.timecard(sch_1):page21_i91@passive.ferritebead(chips)',
 PATH='I91',
 DRAWING='@TIMECARD_LIB.TIMECARD(SCH_1):PAGE527',
 PACKAGE='0805',
 PHYS_PAGE='21',
 XY='(-8050,4800)',
 ROT='0',
 VER='1',
 CDS_LIB='passive',
 CDS_PART_NAME='FERRITEBEAD-G191-10101-01,26OHA',
 TOLERANCE='25%',
 CLS_PN='G191-10101-01',
 VALUE='26OHM',
 PRIM_FILE='./archive_libs/passive/ferritebead/chips/chips.prt';

PART_NAME
 L4 'FERRITEBEAD-G191-10097-01,600OA':;

SECTION_NUMBER 1
 '@TIMECARD_LIB.TIMECARD(SCH_1):PAGE524_I127@PASSIVE.FERRITEBEAD(CHIPS)':
 C_PATH='@timecard_lib.timecard(sch_1):page524_i127@passive.ferritebead(chips)',
 P_PATH='@timecard_lib.timecard(sch_1):page24_i127@passive.ferritebead(chips)',
 PATH='I127',
 DRAWING='@TIMECARD_LIB.TIMECARD(SCH_1):PAGE524',
 PACKAGE='0603',
 PHYS_PAGE='24',
 XY='(-10000,11900)',
 ROT='0',
 VER='1',
 CDS_LIB='passive',
 CDS_PART_NAME='FERRITEBEAD-G191-10097-01,600OA',
 DCR='1300MA 0.15OHM',
 TOLERANCE='25%',
 CLS_PN='G191-10097-01',
 VALUE='600OHM',
 PRIM_FILE='./archive_libs/passive/ferritebead/chips/chips.prt';

PART_NAME
 L5 'INDUCTOR_2-G190-10418-01,1.0UHA':;

SECTION_NUMBER 1
 '@TIMECARD_LIB.TIMECARD(SCH_1):PAGE523_I25@PASSIVE.INDUCTOR_2(CHIPS)':
 C_PATH='@timecard_lib.timecard(sch_1):page523_i25@passive.inductor_2(chips)',
 P_PATH='@timecard_lib.timecard(sch_1):page29_i25@passive.inductor_2(chips)',
 PATH='I25',
 DRAWING='@TIMECARD_LIB.TIMECARD(SCH_1):PAGE523',
 PHYS_PAGE='29',
 XY='(-4050,4350)',
 ROT='0',
 VER='1',
 CDS_LIB='passive',
 CDS_PART_NAME='INDUCTOR_2-G190-10418-01,1.0UHA',
 TOLERANCE='20%',
 CLS_PN='G190-10418-01',
 VALUE='1.0UH',
 PRIM_FILE='./archive_libs/passive/inductor_2/chips/chips.prt';

PART_NAME
 L6 'FERRITEBEAD-G191-10101-01,26OHA':;

SECTION_NUMBER 1
 '@TIMECARD_LIB.TIMECARD(SCH_1):PAGE68_I43@PASSIVE.FERRITEBEAD(CHIPS)':
 C_PATH='@timecard_lib.timecard(sch_1):page68_i43@passive.ferritebead(chips)',
 P_PATH='@timecard_lib.timecard(sch_1):page30_i43@passive.ferritebead(chips)',
 PATH='I43',
 DRAWING='@TIMECARD_LIB.TIMECARD(SCH_1):PAGE68',
 PACKAGE='0603',
 PHYS_PAGE='30',
 XY='(-12450,3900)',
 ROT='0',
 VER='1',
 CDS_LIB='passive',
 CDS_PART_NAME='FERRITEBEAD-G191-10101-01,26OHA',
 TOLERANCE='25%',
 CLS_PN='G191-10101-01',
 VALUE='26OHM',
 PRIM_FILE='./archive_libs/passive/ferritebead/chips/chips.prt';

PART_NAME
 L7 'FERRITEBEAD-G191-10101-01,26OHA':;

SECTION_NUMBER 1
 '@TIMECARD_LIB.TIMECARD(SCH_1):PAGE516_I17@PASSIVE.FERRITEBEAD(CHIPS)':
 C_PATH='@timecard_lib.timecard(sch_1):page516_i17@passive.ferritebead(chips)',
 P_PATH='@timecard_lib.timecard(sch_1):page32_i17@passive.ferritebead(chips)',
 PATH='I17',
 DRAWING='@TIMECARD_LIB.TIMECARD(SCH_1):PAGE516',
 PACKAGE='0603',
 PHYS_PAGE='32',
 XY='(-13200,8300)',
 ROT='0',
 VER='1',
 CDS_LIB='passive',
 CDS_PART_NAME='FERRITEBEAD-G191-10101-01,26OHA',
 TOLERANCE='25%',
 CLS_PN='G191-10101-01',
 VALUE='26OHM',
 PRIM_FILE='./archive_libs/passive/ferritebead/chips/chips.prt';

PART_NAME
 L8 'FERRITEBEAD-G191-10101-01,26OHA':;

SECTION_NUMBER 1
 '@TIMECARD_LIB.TIMECARD(SCH_1):PAGE517_I7@PASSIVE.FERRITEBEAD(CHIPS)':
 C_PATH='@timecard_lib.timecard(sch_1):page517_i7@passive.ferritebead(chips)',
 P_PATH='@timecard_lib.timecard(sch_1):page28_i7@passive.ferritebead(chips)',
 PATH='I7',
 DRAWING='@TIMECARD_LIB.TIMECARD(SCH_1):PAGE517',
 PACKAGE='0603',
 PHYS_PAGE='28',
 XY='(-13250,7500)',
 ROT='0',
 VER='1',
 CDS_LIB='passive',
 CDS_PART_NAME='FERRITEBEAD-G191-10101-01,26OHA',
 TOLERANCE='25%',
 CLS_PN='G191-10101-01',
 VALUE='26OHM',
 PRIM_FILE='./archive_libs/passive/ferritebead/chips/chips.prt';

PART_NAME
 L9 'FERRITEBEAD-G191-10101-01,26OHA':;

SECTION_NUMBER 1
 '@TIMECARD_LIB.TIMECARD(SCH_1):PAGE523_I48@PASSIVE.FERRITEBEAD(CHIPS)':
 C_PATH='@timecard_lib.timecard(sch_1):page523_i48@passive.ferritebead(chips)',
 P_PATH='@timecard_lib.timecard(sch_1):page29_i48@passive.ferritebead(chips)',
 PATH='I48',
 DRAWING='@TIMECARD_LIB.TIMECARD(SCH_1):PAGE523',
 PACKAGE='0603',
 PHYS_PAGE='29',
 XY='(-12550,5550)',
 ROT='0',
 VER='1',
 CDS_LIB='passive',
 CDS_PART_NAME='FERRITEBEAD-G191-10101-01,26OHA',
 TOLERANCE='25%',
 CLS_PN='G191-10101-01',
 VALUE='26OHM',
 PRIM_FILE='./archive_libs/passive/ferritebead/chips/chips.prt';

PART_NAME
 L10 'FERRITEBEAD-G191-10097-01,600OA':;

SECTION_NUMBER 1
 '@TIMECARD_LIB.TIMECARD(SCH_1):PAGE522_I159@PASSIVE.FERRITEBEAD(CHIPS)':
 C_PATH='@timecard_lib.timecard(sch_1):page522_i159@passive.ferritebead(chips)',
 P_PATH='@timecard_lib.timecard(sch_1):page15_i159@passive.ferritebead(chips)',
 PATH='I159',
 DRAWING='@TIMECARD_LIB.TIMECARD(SCH_1):PAGE522',
 PACKAGE='0603',
 PHYS_PAGE='15',
 XY='(-11050,3150)',
 ROT='2',
 VER='1',
 CDS_LIB='passive',
 CDS_PART_NAME='FERRITEBEAD-G191-10097-01,600OA',
 DCR='1300MA 0.15OHM',
 TOLERANCE='25%',
 CLS_PN='G191-10097-01',
 VALUE='600OHM',
 PRIM_FILE='./archive_libs/passive/ferritebead/chips/chips.prt';

PART_NAME
 L11 'FERRITEBEAD-G191-10101-01,26OHA':;

SECTION_NUMBER 1
 '@TIMECARD_LIB.TIMECARD(SCH_1):PAGE68_I25@PASSIVE.FERRITEBEAD(CHIPS)':
 C_PATH='@timecard_lib.timecard(sch_1):page68_i25@passive.ferritebead(chips)',
 P_PATH='@timecard_lib.timecard(sch_1):page30_i25@passive.ferritebead(chips)',
 PATH='I25',
 DRAWING='@TIMECARD_LIB.TIMECARD(SCH_1):PAGE68',
 PACKAGE='0603',
 PHYS_PAGE='30',
 XY='(-12500,8800)',
 ROT='0',
 VER='1',
 CDS_LIB='passive',
 CDS_PART_NAME='FERRITEBEAD-G191-10101-01,26OHA',
 TOLERANCE='25%',
 CLS_PN='G191-10101-01',
 VALUE='26OHM',
 PRIM_FILE='./archive_libs/passive/ferritebead/chips/chips.prt';

PART_NAME
 L12 'FERRITEBEAD-G191-10100-01,120OA':;

SECTION_NUMBER 1
 '@TIMECARD_LIB.TIMECARD(SCH_1):PAGE164_I139@PASSIVE.FERRITEBEAD(CHIPS)':
 C_PATH='@timecard_lib.timecard(sch_1):page164_i139@passive.ferritebead(chips)',
 P_PATH='@timecard_lib.timecard(sch_1):page14_i139@passive.ferritebead(chips)',
 PATH='I139',
 DRAWING='@TIMECARD_LIB.TIMECARD(SCH_1):PAGE164',
 PACKAGE='0603',
 PHYS_PAGE='14',
 XY='(-3350,6000)',
 ROT='0',
 VER='1',
 CDS_LIB='passive',
 CDS_PART_NAME='FERRITEBEAD-G191-10100-01,120OA',
 TOLERANCE='25%',
 CLS_PN='G191-10100-01',
 VALUE='120OHM',
 PRIM_FILE='./archive_libs/passive/ferritebead/chips/chips.prt';

PART_NAME
 L13 'FERRITEBEAD-G191-10101-01,26OHA':;

SECTION_NUMBER 1
 '@TIMECARD_LIB.TIMECARD(SCH_1):PAGE515_I135@PASSIVE.FERRITEBEAD(CHIPS)':
 C_PATH='@timecard_lib.timecard(sch_1):page515_i135@passive.ferritebead(chips)',
 P_PATH='@timecard_lib.timecard(sch_1):page31_i135@passive.ferritebead(chips)',
 PATH='I135',
 DRAWING='@TIMECARD_LIB.TIMECARD(SCH_1):PAGE515',
 PACKAGE='0603',
 PHYS_PAGE='31',
 XY='(-10550,2200)',
 ROT='0',
 VER='1',
 CDS_LIB='passive',
 CDS_PART_NAME='FERRITEBEAD-G191-10101-01,26OHA',
 TOLERANCE='25%',
 CLS_PN='G191-10101-01',
 VALUE='26OHM',
 PRIM_FILE='./archive_libs/passive/ferritebead/chips/chips.prt';

PART_NAME
 L14 'FERRITEBEAD-G191-10097-01,600OA':;

SECTION_NUMBER 1
 '@TIMECARD_LIB.TIMECARD(SCH_1):PAGE522_I146@PASSIVE.FERRITEBEAD(CHIPS)':
 C_PATH='@timecard_lib.timecard(sch_1):page522_i146@passive.ferritebead(chips)',
 P_PATH='@timecard_lib.timecard(sch_1):page15_i146@passive.ferritebead(chips)',
 PATH='I146',
 DRAWING='@TIMECARD_LIB.TIMECARD(SCH_1):PAGE522',
 PACKAGE='0603',
 PHYS_PAGE='15',
 XY='(-11050,6700)',
 ROT='2',
 VER='1',
 CDS_LIB='passive',
 CDS_PART_NAME='FERRITEBEAD-G191-10097-01,600OA',
 DCR='1300MA 0.15OHM',
 TOLERANCE='25%',
 CLS_PN='G191-10097-01',
 VALUE='600OHM',
 PRIM_FILE='./archive_libs/passive/ferritebead/chips/chips.prt';

PART_NAME
 L15 'FERRITEBEAD-G191-10100-01,120OA':;

SECTION_NUMBER 1
 '@TIMECARD_LIB.TIMECARD(SCH_1):PAGE11_I56@PASSIVE.FERRITEBEAD(CHIPS)':
 C_PATH='@timecard_lib.timecard(sch_1):page11_i56@passive.ferritebead(chips)',
 P_PATH='@timecard_lib.timecard(sch_1):page22_i56@passive.ferritebead(chips)',
 PATH='I56',
 DRAWING='@TIMECARD_LIB.TIMECARD(SCH_1):PAGE11',
 PACKAGE='0603',
 PHYS_PAGE='22',
 XY='(-6550,7300)',
 ROT='0',
 VER='1',
 LOCATION='L15',
 CDS_LIB='passive',
 CDS_PART_NAME='FERRITEBEAD-G191-10100-01,120OA',
 TOLERANCE='25%',
 CLS_PN='G191-10100-01',
 VALUE='120OHM',
 PRIM_FILE='./archive_libs/passive/ferritebead/chips/chips.prt';

PART_NAME
 L16 'FERRITEBEAD-G191-10100-01,120OA':;

SECTION_NUMBER 1
 '@TIMECARD_LIB.TIMECARD(SCH_1):PAGE11_I55@PASSIVE.FERRITEBEAD(CHIPS)':
 C_PATH='@timecard_lib.timecard(sch_1):page11_i55@passive.ferritebead(chips)',
 P_PATH='@timecard_lib.timecard(sch_1):page22_i55@passive.ferritebead(chips)',
 PATH='I55',
 DRAWING='@TIMECARD_LIB.TIMECARD(SCH_1):PAGE11',
 PACKAGE='0603',
 PHYS_PAGE='22',
 XY='(-1300,7200)',
 ROT='0',
 VER='1',
 LOCATION='L16',
 CDS_LIB='passive',
 CDS_PART_NAME='FERRITEBEAD-G191-10100-01,120OA',
 TOLERANCE='25%',
 CLS_PN='G191-10100-01',
 VALUE='120OHM',
 PRIM_FILE='./archive_libs/passive/ferritebead/chips/chips.prt';

PART_NAME
 L17 'FERRITEBEAD-G191-10097-01,600OA':;

SECTION_NUMBER 1
 '@TIMECARD_LIB.TIMECARD(SCH_1):PAGE7_I21@PASSIVE.FERRITEBEAD(CHIPS)':
 C_PATH='@timecard_lib.timecard(sch_1):page7_i21@passive.ferritebead(chips)',
 P_PATH='@timecard_lib.timecard(sch_1):page18_i21@passive.ferritebead(chips)',
 PATH='I21',
 DRAWING='@TIMECARD_LIB.TIMECARD(SCH_1):PAGE7',
 PACKAGE='0603',
 PHYS_PAGE='18',
 XY='(-4650,9100)',
 ROT='2',
 VER='1',
 CDS_LIB='passive',
 CDS_PART_NAME='FERRITEBEAD-G191-10097-01,600OA',
 DCR='1300MA 0.15OHM',
 TOLERANCE='25%',
 CLS_PN='G191-10097-01',
 VALUE='600OHM',
 PRIM_FILE='./archive_libs/passive/ferritebead/chips/chips.prt';

PART_NAME
 L18 'FERRITEBEAD-G191-10097-01,600OA':;

SECTION_NUMBER 1
 '@TIMECARD_LIB.TIMECARD(SCH_1):PAGE8_I18@PASSIVE.FERRITEBEAD(CHIPS)':
 C_PATH='@timecard_lib.timecard(sch_1):page8_i18@passive.ferritebead(chips)',
 P_PATH='@timecard_lib.timecard(sch_1):page19_i18@passive.ferritebead(chips)',
 PATH='I18',
 DRAWING='@TIMECARD_LIB.TIMECARD(SCH_1):PAGE8',
 PACKAGE='0603',
 PHYS_PAGE='19',
 XY='(-3300,8900)',
 ROT='2',
 VER='1',
 CDS_LIB='passive',
 CDS_PART_NAME='FERRITEBEAD-G191-10097-01,600OA',
 DCR='1300MA 0.15OHM',
 TOLERANCE='25%',
 CLS_PN='G191-10097-01',
 VALUE='600OHM',
 PRIM_FILE='./archive_libs/passive/ferritebead/chips/chips.prt';

PART_NAME
 L19 'FERRITEBEAD-G191-10097-01,600OA':;

SECTION_NUMBER 1
 '@TIMECARD_LIB.TIMECARD(SCH_1):PAGE9_I22@PASSIVE.FERRITEBEAD(CHIPS)':
 C_PATH='@timecard_lib.timecard(sch_1):page9_i22@passive.ferritebead(chips)',
 P_PATH='@timecard_lib.timecard(sch_1):page20_i22@passive.ferritebead(chips)',
 PATH='I22',
 DRAWING='@TIMECARD_LIB.TIMECARD(SCH_1):PAGE9',
 PACKAGE='0603',
 PHYS_PAGE='20',
 XY='(-9650,12050)',
 ROT='2',
 VER='1',
 CDS_LIB='passive',
 CDS_PART_NAME='FERRITEBEAD-G191-10097-01,600OA',
 DCR='1300MA 0.15OHM',
 TOLERANCE='25%',
 CLS_PN='G191-10097-01',
 VALUE='600OHM',
 PRIM_FILE='./archive_libs/passive/ferritebead/chips/chips.prt';

PART_NAME
 L20 'FERRITEBEAD-G191-10101-01,26OHA':;

SECTION_NUMBER 1
 '@TIMECARD_LIB.TIMECARD(SCH_1):PAGE15_I240@PASSIVE.FERRITEBEAD(CHIPS)':
 C_PATH='@timecard_lib.timecard(sch_1):page15_i240@passive.ferritebead(chips)',
 P_PATH='@timecard_lib.timecard(sch_1):page27_i240@passive.ferritebead(chips)',
 PATH='I240',
 DRAWING='@TIMECARD_LIB.TIMECARD(SCH_1):PAGE15',
 PACKAGE='0603',
 PHYS_PAGE='27',
 XY='(-11900,9700)',
 ROT='0',
 VER='1',
 LOCATION='L20',
 CDS_LIB='passive',
 CDS_PART_NAME='FERRITEBEAD-G191-10101-01,26OHA',
 NO_ASSY='TRUE',
 TOLERANCE='25%',
 CLS_PN='G191-10101-01',
 VALUE='26OHM',
 PRIM_FILE='./archive_libs/passive/ferritebead/chips/chips.prt';

PART_NAME
 L21 'FERRITEBEAD-G191-10101-01,26OHA':;

SECTION_NUMBER 1
 '@TIMECARD_LIB.TIMECARD(SCH_1):PAGE3_I132@PASSIVE.FERRITEBEAD(CHIPS)':
 C_PATH='@timecard_lib.timecard(sch_1):page3_i132@passive.ferritebead(chips)',
 P_PATH='@timecard_lib.timecard(sch_1):page9_i132@passive.ferritebead(chips)',
 PATH='I132',
 DRAWING='@TIMECARD_LIB.TIMECARD(SCH_1):PAGE3',
 PACKAGE='0603',
 PHYS_PAGE='9',
 XY='(-5150,4150)',
 ROT='0',
 VER='1',
 CDS_LIB='passive',
 CDS_PART_NAME='FERRITEBEAD-G191-10101-01,26OHA',
 NO_ASSY='TRUE',
 TOLERANCE='25%',
 CLS_PN='G191-10101-01',
 VALUE='26OHM',
 PRIM_FILE='./archive_libs/passive/ferritebead/chips/chips.prt';

PART_NAME
 L22 'FERRITEBEAD-G191-10097-01,600OA':;

SECTION_NUMBER 1
 '@TIMECARD_LIB.TIMECARD(SCH_1):PAGE524_I118@PASSIVE.FERRITEBEAD(CHIPS)':
 C_PATH='@timecard_lib.timecard(sch_1):page524_i118@passive.ferritebead(chips)',
 P_PATH='@timecard_lib.timecard(sch_1):page24_i118@passive.ferritebead(chips)',
 PATH='I118',
 DRAWING='@TIMECARD_LIB.TIMECARD(SCH_1):PAGE524',
 PACKAGE='0603',
 PHYS_PAGE='24',
 XY='(-10050,11100)',
 ROT='0',
 VER='1',
 CDS_LIB='passive',
 CDS_PART_NAME='FERRITEBEAD-G191-10097-01,600OA',
 DCR='1300MA 0.15OHM',
 TOLERANCE='25%',
 CLS_PN='G191-10097-01',
 VALUE='600OHM',
 PRIM_FILE='./archive_libs/passive/ferritebead/chips/chips.prt';

PART_NAME
 L23 'FERRITEBEAD-G191-10101-01,26OHA':;

SECTION_NUMBER 1
 '@TIMECARD_LIB.TIMECARD(SCH_1):PAGE525_I10@PASSIVE.FERRITEBEAD(CHIPS)':
 C_PATH='@timecard_lib.timecard(sch_1):page525_i10@passive.ferritebead(chips)',
 P_PATH='@timecard_lib.timecard(sch_1):page33_i10@passive.ferritebead(chips)',
 PATH='I10',
 DRAWING='@TIMECARD_LIB.TIMECARD(SCH_1):PAGE525',
 PACKAGE='0603',
 PHYS_PAGE='33',
 XY='(-300,3400)',
 ROT='0',
 VER='1',
 CDS_LIB='passive',
 CDS_PART_NAME='FERRITEBEAD-G191-10101-01,26OHA',
 TOLERANCE='25%',
 CLS_PN='G191-10101-01',
 VALUE='26OHM',
 PRIM_FILE='./archive_libs/passive/ferritebead/chips/chips.prt';

PART_NAME
 L24 'FERRITEBEAD-G191-10100-01,120OA':;

SECTION_NUMBER 1
 '@TIMECARD_LIB.TIMECARD(SCH_1):PAGE525_I108@PASSIVE.FERRITEBEAD(CHIPS)':
 C_PATH='@timecard_lib.timecard(sch_1):page525_i108@passive.ferritebead(chips)',
 P_PATH='@timecard_lib.timecard(sch_1):page33_i108@passive.ferritebead(chips)',
 PATH='I108',
 DRAWING='@TIMECARD_LIB.TIMECARD(SCH_1):PAGE525',
 PACKAGE='0603',
 PHYS_PAGE='33',
 XY='(5700,3750)',
 ROT='0',
 VER='1',
 CDS_LIB='passive',
 CDS_PART_NAME='FERRITEBEAD-G191-10100-01,120OA',
 NO_ASSY='TRUE',
 TOLERANCE='25%',
 CLS_PN='G191-10100-01',
 VALUE='120OHM',
 PRIM_FILE='./archive_libs/passive/ferritebead/chips/chips.prt';

PART_NAME
 L33 'FERRITEBEAD-G191-10100-01,120OA':;

SECTION_NUMBER 1
 '@TIMECARD_LIB.TIMECARD(SCH_1):PAGE164_I102@PASSIVE.FERRITEBEAD(CHIPS)':
 C_PATH='@timecard_lib.timecard(sch_1):page164_i102@passive.ferritebead(chips)',
 P_PATH='@timecard_lib.timecard(sch_1):page14_i102@passive.ferritebead(chips)',
 PATH='I102',
 DRAWING='@TIMECARD_LIB.TIMECARD(SCH_1):PAGE164',
 PACKAGE='0603',
 PHYS_PAGE='14',
 XY='(-7500,7450)',
 ROT='0',
 VER='1',
 CDS_LIB='passive',
 CDS_PART_NAME='FERRITEBEAD-G191-10100-01,120OA',
 TOLERANCE='25%',
 CLS_PN='G191-10100-01',
 VALUE='120OHM',
 PRIM_FILE='./archive_libs/passive/ferritebead/chips/chips.prt';

PART_NAME
 L34 'FERRITEBEAD-G191-10100-01,120OA':;

SECTION_NUMBER 1
 '@TIMECARD_LIB.TIMECARD(SCH_1):PAGE164_I37@PASSIVE.FERRITEBEAD(CHIPS)':
 C_PATH='@timecard_lib.timecard(sch_1):page164_i37@passive.ferritebead(chips)',
 P_PATH='@timecard_lib.timecard(sch_1):page14_i37@passive.ferritebead(chips)',
 PATH='I37',
 DRAWING='@TIMECARD_LIB.TIMECARD(SCH_1):PAGE164',
 PACKAGE='0603',
 PHYS_PAGE='14',
 XY='(-7650,750)',
 ROT='0',
 VER='1',
 CDS_LIB='passive',
 CDS_PART_NAME='FERRITEBEAD-G191-10100-01,120OA',
 TOLERANCE='25%',
 CLS_PN='G191-10100-01',
 VALUE='120OHM',
 PRIM_FILE='./archive_libs/passive/ferritebead/chips/chips.prt';

PART_NAME
 L35 'FERRITEBEAD-G191-10100-01,120OA':;

SECTION_NUMBER 1
 '@TIMECARD_LIB.TIMECARD(SCH_1):PAGE164_I36@PASSIVE.FERRITEBEAD(CHIPS)':
 C_PATH='@timecard_lib.timecard(sch_1):page164_i36@passive.ferritebead(chips)',
 P_PATH='@timecard_lib.timecard(sch_1):page14_i36@passive.ferritebead(chips)',
 PATH='I36',
 DRAWING='@TIMECARD_LIB.TIMECARD(SCH_1):PAGE164',
 PACKAGE='0603',
 PHYS_PAGE='14',
 XY='(-8400,-350)',
 ROT='0',
 VER='1',
 CDS_LIB='passive',
 CDS_PART_NAME='FERRITEBEAD-G191-10100-01,120OA',
 TOLERANCE='25%',
 CLS_PN='G191-10100-01',
 VALUE='120OHM',
 PRIM_FILE='./archive_libs/passive/ferritebead/chips/chips.prt';

PART_NAME
 MAC_PIN1 'NUT-A200-00029-FB':;

SECTION_NUMBER 1
 '@TIMECARD_LIB.TIMECARD(SCH_1):PAGE527_I227@MECH.NUT(CHIPS)':
 C_PATH='@timecard_lib.timecard(sch_1):page527_i227@mech.nut(chips)',
 P_PATH='@timecard_lib.timecard(sch_1):page21_i227@mech.nut(chips)',
 PATH='I227',
 DRAWING='@TIMECARD_LIB.TIMECARD(SCH_1):PAGE527',
 PHYS_PAGE='21',
 XY='(-11000,3800)',
 ROT='2',
 VER='1',
 CDS_LIB='mech',
 CDS_PART_NAME='NUT-A200-00029-FB',
 CLS_PN='A200-00029-FB',
 PART_NUMBER='0332-0-43-80-18-27-10-0',
 PRIM_FILE='./archive_libs/mech/nut/chips/chips.prt';

PART_NAME
 MAC_PIN2 'NUT-A200-00029-FB':;

SECTION_NUMBER 1
 '@TIMECARD_LIB.TIMECARD(SCH_1):PAGE527_I229@MECH.NUT(CHIPS)':
 C_PATH='@timecard_lib.timecard(sch_1):page527_i229@mech.nut(chips)',
 P_PATH='@timecard_lib.timecard(sch_1):page21_i229@mech.nut(chips)',
 PATH='I229',
 DRAWING='@TIMECARD_LIB.TIMECARD(SCH_1):PAGE527',
 PHYS_PAGE='21',
 XY='(-11000,4400)',
 ROT='2',
 VER='1',
 CDS_LIB='mech',
 CDS_PART_NAME='NUT-A200-00029-FB',
 CLS_PN='A200-00029-FB',
 PART_NUMBER='0332-0-43-80-18-27-10-0',
 PRIM_FILE='./archive_libs/mech/nut/chips/chips.prt';

PART_NAME
 MAC_PIN3 'NUT-A200-00029-FB':;

SECTION_NUMBER 1
 '@TIMECARD_LIB.TIMECARD(SCH_1):PAGE527_I226@MECH.NUT(CHIPS)':
 C_PATH='@timecard_lib.timecard(sch_1):page527_i226@mech.nut(chips)',
 P_PATH='@timecard_lib.timecard(sch_1):page21_i226@mech.nut(chips)',
 PATH='I226',
 DRAWING='@TIMECARD_LIB.TIMECARD(SCH_1):PAGE527',
 PHYS_PAGE='21',
 XY='(-11000,3550)',
 ROT='2',
 VER='1',
 CDS_LIB='mech',
 CDS_PART_NAME='NUT-A200-00029-FB',
 CLS_PN='A200-00029-FB',
 PART_NUMBER='0332-0-43-80-18-27-10-0',
 PRIM_FILE='./archive_libs/mech/nut/chips/chips.prt';

PART_NAME
 MAC_PIN4 'NUT-A200-00029-FB':;

SECTION_NUMBER 1
 '@TIMECARD_LIB.TIMECARD(SCH_1):PAGE527_I228@MECH.NUT(CHIPS)':
 C_PATH='@timecard_lib.timecard(sch_1):page527_i228@mech.nut(chips)',
 P_PATH='@timecard_lib.timecard(sch_1):page21_i228@mech.nut(chips)',
 PATH='I228',
 DRAWING='@TIMECARD_LIB.TIMECARD(SCH_1):PAGE527',
 PHYS_PAGE='21',
 XY='(-11000,4150)',
 ROT='2',
 VER='1',
 CDS_LIB='mech',
 CDS_PART_NAME='NUT-A200-00029-FB',
 CLS_PN='A200-00029-FB',
 PART_NUMBER='0332-0-43-80-18-27-10-0',
 PRIM_FILE='./archive_libs/mech/nut/chips/chips.prt';

PART_NAME
 MAC_PIN5 'NUT-A200-00029-FB':;

SECTION_NUMBER 1
 '@TIMECARD_LIB.TIMECARD(SCH_1):PAGE527_I230@MECH.NUT(CHIPS)':
 C_PATH='@timecard_lib.timecard(sch_1):page527_i230@mech.nut(chips)',
 P_PATH='@timecard_lib.timecard(sch_1):page21_i230@mech.nut(chips)',
 PATH='I230',
 DRAWING='@TIMECARD_LIB.TIMECARD(SCH_1):PAGE527',
 PHYS_PAGE='21',
 XY='(-11000,4750)',
 ROT='2',
 VER='1',
 CDS_LIB='mech',
 CDS_PART_NAME='NUT-A200-00029-FB',
 CLS_PN='A200-00029-FB',
 PART_NUMBER='0332-0-43-80-18-27-10-0',
 PRIM_FILE='./archive_libs/mech/nut/chips/chips.prt';

PART_NAME
 MAC_PIN6 'NUT-A200-00029-FB':;

SECTION_NUMBER 1
 '@TIMECARD_LIB.TIMECARD(SCH_1):PAGE527_I225@MECH.NUT(CHIPS)':
 C_PATH='@timecard_lib.timecard(sch_1):page527_i225@mech.nut(chips)',
 P_PATH='@timecard_lib.timecard(sch_1):page21_i225@mech.nut(chips)',
 PATH='I225',
 DRAWING='@TIMECARD_LIB.TIMECARD(SCH_1):PAGE527',
 PHYS_PAGE='21',
 XY='(-11000,3300)',
 ROT='2',
 VER='1',
 CDS_LIB='mech',
 CDS_PART_NAME='NUT-A200-00029-FB',
 CLS_PN='A200-00029-FB',
 PART_NUMBER='0332-0-43-80-18-27-10-0',
 PRIM_FILE='./archive_libs/mech/nut/chips/chips.prt';

PART_NAME
 MAC_PIN7 'NUT-A200-00029-FB':;

SECTION_NUMBER 1
 '@TIMECARD_LIB.TIMECARD(SCH_1):PAGE527_I224@MECH.NUT(CHIPS)':
 C_PATH='@timecard_lib.timecard(sch_1):page527_i224@mech.nut(chips)',
 P_PATH='@timecard_lib.timecard(sch_1):page21_i224@mech.nut(chips)',
 PATH='I224',
 DRAWING='@TIMECARD_LIB.TIMECARD(SCH_1):PAGE527',
 PHYS_PAGE='21',
 XY='(-11000,3050)',
 ROT='2',
 VER='1',
 CDS_LIB='mech',
 CDS_PART_NAME='NUT-A200-00029-FB',
 CLS_PN='A200-00029-FB',
 PART_NUMBER='0332-0-43-80-18-27-10-0',
 PRIM_FILE='./archive_libs/mech/nut/chips/chips.prt';

PART_NAME
 MAC_PIN8 'NUT-A200-00029-FB':;

SECTION_NUMBER 1
 '@TIMECARD_LIB.TIMECARD(SCH_1):PAGE527_I220@MECH.NUT(CHIPS)':
 C_PATH='@timecard_lib.timecard(sch_1):page527_i220@mech.nut(chips)',
 P_PATH='@timecard_lib.timecard(sch_1):page21_i220@mech.nut(chips)',
 PATH='I220',
 DRAWING='@TIMECARD_LIB.TIMECARD(SCH_1):PAGE527',
 PHYS_PAGE='21',
 XY='(-11000,2800)',
 ROT='2',
 VER='1',
 CDS_LIB='mech',
 CDS_PART_NAME='NUT-A200-00029-FB',
 CLS_PN='A200-00029-FB',
 PART_NUMBER='0332-0-43-80-18-27-10-0',
 PRIM_FILE='./archive_libs/mech/nut/chips/chips.prt';

PART_NAME
 ME1 'NUT-G340-10437-01':;

SECTION_NUMBER 1
 '@TIMECARD_LIB.TIMECARD(SCH_1):PAGE33_I127@MECH.NUT(CHIPS)':
 C_PATH='@timecard_lib.timecard(sch_1):page33_i127@mech.nut(chips)',
 P_PATH='@timecard_lib.timecard(sch_1):page34_i127@mech.nut(chips)',
 PATH='I127',
 DRAWING='@TIMECARD_LIB.TIMECARD(SCH_1):PAGE33',
 PHYS_PAGE='34',
 XY='(-11400,6850)',
 ROT='2',
 VER='1',
 LOCATION='ME1',
 CDS_LIB='mech',
 CDS_PART_NAME='NUT-G340-10437-01',
 CLS_PN='G340-10437-01',
 PART_NUMBER='SMTSO-440-12ET',
 PRIM_FILE='./archive_libs/mech/nut/chips/chips.prt';

PART_NAME
 ME2 'NUT-G340-10437-01':;

SECTION_NUMBER 1
 '@TIMECARD_LIB.TIMECARD(SCH_1):PAGE33_I129@MECH.NUT(CHIPS)':
 C_PATH='@timecard_lib.timecard(sch_1):page33_i129@mech.nut(chips)',
 P_PATH='@timecard_lib.timecard(sch_1):page34_i129@mech.nut(chips)',
 PATH='I129',
 DRAWING='@TIMECARD_LIB.TIMECARD(SCH_1):PAGE33',
 PHYS_PAGE='34',
 XY='(-11400,6150)',
 ROT='2',
 VER='1',
 LOCATION='ME2',
 CDS_LIB='mech',
 CDS_PART_NAME='NUT-G340-10437-01',
 CLS_PN='G340-10437-01',
 PART_NUMBER='SMTSO-440-12ET',
 PRIM_FILE='./archive_libs/mech/nut/chips/chips.prt';

PART_NAME
 ME3 'NUT-G340-10437-01':;

SECTION_NUMBER 1
 '@TIMECARD_LIB.TIMECARD(SCH_1):PAGE33_I125@MECH.NUT(CHIPS)':
 C_PATH='@timecard_lib.timecard(sch_1):page33_i125@mech.nut(chips)',
 P_PATH='@timecard_lib.timecard(sch_1):page34_i125@mech.nut(chips)',
 PATH='I125',
 DRAWING='@TIMECARD_LIB.TIMECARD(SCH_1):PAGE33',
 PHYS_PAGE='34',
 XY='(-9350,6850)',
 ROT='2',
 VER='1',
 LOCATION='ME3',
 CDS_LIB='mech',
 CDS_PART_NAME='NUT-G340-10437-01',
 CLS_PN='G340-10437-01',
 PART_NUMBER='SMTSO-440-12ET',
 PRIM_FILE='./archive_libs/mech/nut/chips/chips.prt';

PART_NAME
 ME4 'NUT-G340-10437-01':;

SECTION_NUMBER 1
 '@TIMECARD_LIB.TIMECARD(SCH_1):PAGE33_I126@MECH.NUT(CHIPS)':
 C_PATH='@timecard_lib.timecard(sch_1):page33_i126@mech.nut(chips)',
 P_PATH='@timecard_lib.timecard(sch_1):page34_i126@mech.nut(chips)',
 PATH='I126',
 DRAWING='@TIMECARD_LIB.TIMECARD(SCH_1):PAGE33',
 PHYS_PAGE='34',
 XY='(-9350,6150)',
 ROT='2',
 VER='1',
 LOCATION='ME4',
 CDS_LIB='mech',
 CDS_PART_NAME='NUT-G340-10437-01',
 CLS_PN='G340-10437-01',
 PART_NUMBER='SMTSO-440-12ET',
 PRIM_FILE='./archive_libs/mech/nut/chips/chips.prt';

PART_NAME
 ME5 'MEC_NPTH-MTH100C240N-MTH100C24A':;

SECTION_NUMBER -1
 '@TIMECARD_LIB.TIMECARD(SCH_1):PAGE33_I123@MECH.MEC_NPTH(CHIPS)':
 C_PATH='@timecard_lib.timecard(sch_1):page33_i123@mech.mec_npth(chips)',
 P_PATH='@timecard_lib.timecard(sch_1):page34_i123@mech.mec_npth(chips)',
 PATH='I123',
 DRAWING='@TIMECARD_LIB.TIMECARD(SCH_1):PAGE33',
 PHYS_PAGE='34',
 XY='(-6750,7550)',
 ROT='0',
 VER='1',
 JEDEC_TYPE='MTH100C240N',
 CDS_LIB='mech',
 CDS_PART_NAME='MEC_NPTH-MTH100C240N-MTH100C24A',
 BOM_IGNORE='TRUE',
 PRIM_FILE='./archive_libs/mech/mec_npth/chips/chips.prt';

PART_NAME
 ME6 'MEC_NPTH-MTH100C240N-MTH100C24A':;

SECTION_NUMBER -1
 '@TIMECARD_LIB.TIMECARD(SCH_1):PAGE33_I122@MECH.MEC_NPTH(CHIPS)':
 C_PATH='@timecard_lib.timecard(sch_1):page33_i122@mech.mec_npth(chips)',
 P_PATH='@timecard_lib.timecard(sch_1):page34_i122@mech.mec_npth(chips)',
 PATH='I122',
 DRAWING='@TIMECARD_LIB.TIMECARD(SCH_1):PAGE33',
 PHYS_PAGE='34',
 XY='(-6250,7550)',
 ROT='0',
 VER='1',
 JEDEC_TYPE='MTH100C240N',
 CDS_LIB='mech',
 CDS_PART_NAME='MEC_NPTH-MTH100C240N-MTH100C24A',
 BOM_IGNORE='TRUE',
 PRIM_FILE='./archive_libs/mech/mec_npth/chips/chips.prt';

PART_NAME
 ME7 'MEC_NPTH-MTH100C240N-MTH100C24A':;

SECTION_NUMBER -1
 '@TIMECARD_LIB.TIMECARD(SCH_1):PAGE33_I121@MECH.MEC_NPTH(CHIPS)':
 C_PATH='@timecard_lib.timecard(sch_1):page33_i121@mech.mec_npth(chips)',
 P_PATH='@timecard_lib.timecard(sch_1):page34_i121@mech.mec_npth(chips)',
 PATH='I121',
 DRAWING='@TIMECARD_LIB.TIMECARD(SCH_1):PAGE33',
 PHYS_PAGE='34',
 XY='(-5750,7550)',
 ROT='0',
 VER='1',
 JEDEC_TYPE='MTH100C240N',
 CDS_LIB='mech',
 CDS_PART_NAME='MEC_NPTH-MTH100C240N-MTH100C24A',
 BOM_IGNORE='TRUE',
 PRIM_FILE='./archive_libs/mech/mec_npth/chips/chips.prt';

PART_NAME
 ME8 'MEC_NPTH-MTH100C240N-MTH100C24A':;

SECTION_NUMBER -1
 '@TIMECARD_LIB.TIMECARD(SCH_1):PAGE33_I120@MECH.MEC_NPTH(CHIPS)':
 C_PATH='@timecard_lib.timecard(sch_1):page33_i120@mech.mec_npth(chips)',
 P_PATH='@timecard_lib.timecard(sch_1):page34_i120@mech.mec_npth(chips)',
 PATH='I120',
 DRAWING='@TIMECARD_LIB.TIMECARD(SCH_1):PAGE33',
 PHYS_PAGE='34',
 XY='(-5250,7550)',
 ROT='0',
 VER='1',
 JEDEC_TYPE='MTH100C240N',
 CDS_LIB='mech',
 CDS_PART_NAME='MEC_NPTH-MTH100C240N-MTH100C24A',
 BOM_IGNORE='TRUE',
 PRIM_FILE='./archive_libs/mech/mec_npth/chips/chips.prt';

PART_NAME
 ME9 'MEC_MTH8-MTH125C236N_V8-MTH125A':;

SECTION_NUMBER 1
 '@TIMECARD_LIB.TIMECARD(SCH_1):PAGE33_I7@MECH.MEC_MTH8(CHIPS)':
 C_PATH='@timecard_lib.timecard(sch_1):page33_i7@mech.mec_mth8(chips)',
 P_PATH='@timecard_lib.timecard(sch_1):page34_i7@mech.mec_mth8(chips)',
 PATH='I7',
 DRAWING='@TIMECARD_LIB.TIMECARD(SCH_1):PAGE33',
 PHYS_PAGE='34',
 XY='(-6500,6550)',
 ROT='0',
 VER='1',
 JEDEC_TYPE='MTH125C236N_V8',
 CDS_LIB='mech',
 CDS_PART_NAME='MEC_MTH8-MTH125C236N_V8-MTH125A',
 BOM_IGNORE='TRUE',
 PRIM_FILE='./archive_libs/mech/mec_mth8/chips/chips.prt';

PART_NAME
 ME10 'MEC_MTH8-MTH125C236N_V8-MTH125A':;

SECTION_NUMBER 1
 '@TIMECARD_LIB.TIMECARD(SCH_1):PAGE33_I5@MECH.MEC_MTH8(CHIPS)':
 C_PATH='@timecard_lib.timecard(sch_1):page33_i5@mech.mec_mth8(chips)',
 P_PATH='@timecard_lib.timecard(sch_1):page34_i5@mech.mec_mth8(chips)',
 PATH='I5',
 DRAWING='@TIMECARD_LIB.TIMECARD(SCH_1):PAGE33',
 PHYS_PAGE='34',
 XY='(-4950,6550)',
 ROT='0',
 VER='1',
 JEDEC_TYPE='MTH125C236N_V8',
 CDS_LIB='mech',
 CDS_PART_NAME='MEC_MTH8-MTH125C236N_V8-MTH125A',
 BOM_IGNORE='TRUE',
 PRIM_FILE='./archive_libs/mech/mec_mth8/chips/chips.prt';

PART_NAME
 ME11 'MEC_MTH8-MTH125C236N_V8-MTH125A':;

SECTION_NUMBER 1
 '@TIMECARD_LIB.TIMECARD(SCH_1):PAGE33_I1@MECH.MEC_MTH8(CHIPS)':
 C_PATH='@timecard_lib.timecard(sch_1):page33_i1@mech.mec_mth8(chips)',
 P_PATH='@timecard_lib.timecard(sch_1):page34_i1@mech.mec_mth8(chips)',
 PATH='I1',
 DRAWING='@TIMECARD_LIB.TIMECARD(SCH_1):PAGE33',
 PHYS_PAGE='34',
 XY='(-3400,6550)',
 ROT='0',
 VER='1',
 JEDEC_TYPE='MTH125C236N_V8',
 CDS_LIB='mech',
 CDS_PART_NAME='MEC_MTH8-MTH125C236N_V8-MTH125A',
 BOM_IGNORE='TRUE',
 PRIM_FILE='./archive_libs/mech/mec_mth8/chips/chips.prt';

PART_NAME
 ME12 'MEC_MTH8-MTH125C236N_V8-MTH125A':;

SECTION_NUMBER 1
 '@TIMECARD_LIB.TIMECARD(SCH_1):PAGE33_I2@MECH.MEC_MTH8(CHIPS)':
 C_PATH='@timecard_lib.timecard(sch_1):page33_i2@mech.mec_mth8(chips)',
 P_PATH='@timecard_lib.timecard(sch_1):page34_i2@mech.mec_mth8(chips)',
 PATH='I2',
 DRAWING='@TIMECARD_LIB.TIMECARD(SCH_1):PAGE33',
 PHYS_PAGE='34',
 XY='(-1850,6550)',
 ROT='0',
 VER='1',
 JEDEC_TYPE='MTH125C236N_V8',
 CDS_LIB='mech',
 CDS_PART_NAME='MEC_MTH8-MTH125C236N_V8-MTH125A',
 BOM_IGNORE='TRUE',
 PRIM_FILE='./archive_libs/mech/mec_mth8/chips/chips.prt';

PART_NAME
 P1 'CONN_HDR_2X10_M_S_SMT-G200-130A':;

SECTION_NUMBER 1
 '@TIMECARD_LIB.TIMECARD(SCH_1):PAGE527_I193@CONNECTOR.CONN_HDR_2X10_M_S_SMT(CHIPS)':
 C_PATH='@timecard_lib.timecard(sch_1):page527_i193@connector.conn_hdr_2x10_m_s_~
smt(chips)',
 P_PATH='@timecard_lib.timecard(sch_1):page21_i193@connector.conn_hdr_2x10_m_s_s~
mt(chips)',
 PATH='I193',
 DRAWING='@TIMECARD_LIB.TIMECARD(SCH_1):PAGE527',
 PHYS_PAGE='21',
 XY='(-5150,7550)',
 ROT='0',
 VER='1',
 CDS_LIB='connector',
 CDS_PART_NAME='CONN_HDR_2X10_M_S_SMT-G200-130A',
 CLS_PN='G200-13077-01',
 VALUE='52991-0208',
 PRIM_FILE='./archive_libs/connector/conn_hdr_2x10_m_s_smt/chips/chips.prt';

PART_NAME
 P2 'CONN_HDR_2X4_F_S_SMT-G200-1307A':;

SECTION_NUMBER 1
 '@TIMECARD_LIB.TIMECARD(SCH_1):PAGE11_I36@CONNECTOR.CONN_HDR_2X4_F_S_SMT(CHIPS)':
 C_PATH='@timecard_lib.timecard(sch_1):page11_i36@connector.conn_hdr_2x4_f_s_smt~
(chips)',
 P_PATH='@timecard_lib.timecard(sch_1):page22_i36@connector.conn_hdr_2x4_f_s_smt~
(chips)',
 PATH='I36',
 DRAWING='@TIMECARD_LIB.TIMECARD(SCH_1):PAGE11',
 PHYS_PAGE='22',
 XY='(-4150,6350)',
 ROT='2',
 VER='1',
 LOCATION='P2',
 CDS_LIB='connector',
 CDS_PART_NAME='CONN_HDR_2X4_F_S_SMT-G200-1307A',
 CLS_PN='G200-13079-01',
 VALUE='SQW-104-01-F-D-VS-K-TR',
 PRIM_FILE='./archive_libs/connector/conn_hdr_2x4_f_s_smt/chips/chips.prt';

PART_NAME
 P3 'CONN_HDR_2X3_M_RA_TH-G200-1251A':;

SECTION_NUMBER 1
 '@TIMECARD_LIB.TIMECARD(SCH_1):PAGE15_I238@CONNECTOR.CONN_HDR_2X3_M_RA_TH(CHIPS)':
 C_PATH='@timecard_lib.timecard(sch_1):page15_i238@connector.conn_hdr_2x3_m_ra_t~
h(chips)',
 P_PATH='@timecard_lib.timecard(sch_1):page27_i238@connector.conn_hdr_2x3_m_ra_t~
h(chips)',
 PATH='I238',
 DRAWING='@TIMECARD_LIB.TIMECARD(SCH_1):PAGE15',
 PHYS_PAGE='27',
 XY='(-12850,8450)',
 ROT='0',
 VER='1',
 LOCATION='P3',
 CDS_LIB='connector',
 CDS_PART_NAME='CONN_HDR_2X3_M_RA_TH-G200-1251A',
 CLS_PN='G200-12517-01',
 PART_NUMBER='457320001',
 PRIM_FILE='./archive_libs/connector/conn_hdr_2x3_m_ra_th/chips/chips.prt';

PART_NAME
 Q1 'POWERMOS_3P_NCH_V1-G121-10200-A':;

SECTION_NUMBER 1
 '@TIMECARD_LIB.TIMECARD(SCH_1):PAGE524_I445@DISCRETE.POWERMOS_3P_NCH_V1(CHIPS)':
 C_PATH='@timecard_lib.timecard(sch_1):page524_i445@discrete.powermos_3p_nch_v1(~
chips)',
 P_PATH='@timecard_lib.timecard(sch_1):page24_i445@discrete.powermos_3p_nch_v1(c~
hips)',
 PATH='I445',
 DRAWING='@TIMECARD_LIB.TIMECARD(SCH_1):PAGE524',
 PHYS_PAGE='24',
 XY='(-13000,4100)',
 ROT='0',
 VER='1',
 CDS_LIB='discrete',
 CDS_PART_NAME='POWERMOS_3P_NCH_V1-G121-10200-A',
 CLS_PN='G121-10200-01',
 PART_NUMBER='BSS138',
 PRIM_FILE='./archive_libs/discrete/powermos_3p_nch_v1/chips/chips.prt';

PART_NAME
 Q2 'POWERMOS_3P_NCH_V1-G121-10200-A':;

SECTION_NUMBER 1
 '@TIMECARD_LIB.TIMECARD(SCH_1):PAGE527_I232@DISCRETE.POWERMOS_3P_NCH_V1(CHIPS)':
 C_PATH='@timecard_lib.timecard(sch_1):page527_i232@discrete.powermos_3p_nch_v1(~
chips)',
 P_PATH='@timecard_lib.timecard(sch_1):page21_i232@discrete.powermos_3p_nch_v1(c~
hips)',
 PATH='I232',
 DRAWING='@TIMECARD_LIB.TIMECARD(SCH_1):PAGE527',
 PHYS_PAGE='21',
 XY='(450,800)',
 ROT='2',
 VER='1',
 CDS_LIB='discrete',
 CDS_PART_NAME='POWERMOS_3P_NCH_V1-G121-10200-A',
 NO_ASSY='TRUE',
 CLS_PN='G121-10200-01',
 PART_NUMBER='BSS138',
 PRIM_FILE='./archive_libs/discrete/powermos_3p_nch_v1/chips/chips.prt';

PART_NAME
 Q3 'POWERMOS_3P_PCH-G121-10216-01':;

SECTION_NUMBER 1
 '@TIMECARD_LIB.TIMECARD(SCH_1):PAGE527_I231@DISCRETE.POWERMOS_3P_PCH(CHIPS)':
 C_PATH='@timecard_lib.timecard(sch_1):page527_i231@discrete.powermos_3p_pch(chi~
ps)',
 P_PATH='@timecard_lib.timecard(sch_1):page21_i231@discrete.powermos_3p_pch(chip~
s)',
 PATH='I231',
 DRAWING='@TIMECARD_LIB.TIMECARD(SCH_1):PAGE527',
 PHYS_PAGE='21',
 XY='(800,1450)',
 ROT='7',
 VER='1',
 CDS_LIB='discrete',
 CDS_PART_NAME='POWERMOS_3P_PCH-G121-10216-01',
 NO_ASSY='TRUE',
 CLS_PN='G121-10216-01',
 PART_NUMBER='DMP3099L-7',
 PRIM_FILE='./archive_libs/discrete/powermos_3p_pch/chips/chips.prt';

PART_NAME
 R1 'RESISTOR-G155-13300-01,330OHM,A':;

SECTION_NUMBER 1
 '@TIMECARD_LIB.TIMECARD(SCH_1):PAGE5_I130@PASSIVE.RESISTOR(CHIPS)':
 C_PATH='@timecard_lib.timecard(sch_1):page5_i130@passive.resistor(chips)',
 P_PATH='@timecard_lib.timecard(sch_1):page16_i130@passive.resistor(chips)',
 PATH='I130',
 DRAWING='@TIMECARD_LIB.TIMECARD(SCH_1):PAGE5',
 PACKAGE='0402',
 PHYS_PAGE='16',
 XY='(-11000,5550)',
 ROT='0',
 VER='1',
 CDS_LIB='passive',
 CDS_PART_NAME='RESISTOR-G155-13300-01,330OHM,A',
 NO_ASSY='TRUE',
 TOLERANCE='1%',
 CLS_PN='G155-13300-01',
 VALUE='330OHM',
 PRIM_FILE='./archive_libs/passive/resistor/chips/chips.prt';

PART_NAME
 R2 'RESISTOR-G155-13300-01,330OHM,A':;

SECTION_NUMBER 1
 '@TIMECARD_LIB.TIMECARD(SCH_1):PAGE5_I173@PASSIVE.RESISTOR(CHIPS)':
 C_PATH='@timecard_lib.timecard(sch_1):page5_i173@passive.resistor(chips)',
 P_PATH='@timecard_lib.timecard(sch_1):page16_i173@passive.resistor(chips)',
 PATH='I173',
 DRAWING='@TIMECARD_LIB.TIMECARD(SCH_1):PAGE5',
 PACKAGE='0402',
 PHYS_PAGE='16',
 XY='(-9750,4300)',
 ROT='0',
 VER='1',
 CDS_LIB='passive',
 CDS_PART_NAME='RESISTOR-G155-13300-01,330OHM,A',
 TOLERANCE='1%',
 CLS_PN='G155-13300-01',
 VALUE='330OHM',
 PRIM_FILE='./archive_libs/passive/resistor/chips/chips.prt';

PART_NAME
 R3 'RESISTOR-G155-14701-01,4.7KOHMA':;

SECTION_NUMBER 1
 '@TIMECARD_LIB.TIMECARD(SCH_1):PAGE5_I169@PASSIVE.RESISTOR(CHIPS)':
 C_PATH='@timecard_lib.timecard(sch_1):page5_i169@passive.resistor(chips)',
 P_PATH='@timecard_lib.timecard(sch_1):page16_i169@passive.resistor(chips)',
 PATH='I169',
 DRAWING='@TIMECARD_LIB.TIMECARD(SCH_1):PAGE5',
 PACKAGE='0402',
 PHYS_PAGE='16',
 XY='(-8900,4650)',
 ROT='0',
 VER='2',
 CDS_LIB='passive',
 CDS_PART_NAME='RESISTOR-G155-14701-01,4.7KOHMA',
 NO_ASSY='TRUE',
 TOLERANCE='1%',
 CLS_PN='G155-14701-01',
 VALUE='4.7KOHM',
 PRIM_FILE='./archive_libs/passive/resistor/chips/chips.prt';

PART_NAME
 R4 'RESISTOR-G155-11002-01,10KOHM,A':;

SECTION_NUMBER 1
 '@TIMECARD_LIB.TIMECARD(SCH_1):PAGE15_I170@PASSIVE.RESISTOR(CHIPS)':
 C_PATH='@timecard_lib.timecard(sch_1):page15_i170@passive.resistor(chips)',
 P_PATH='@timecard_lib.timecard(sch_1):page27_i170@passive.resistor(chips)',
 PATH='I170',
 DRAWING='@TIMECARD_LIB.TIMECARD(SCH_1):PAGE15',
 PACKAGE='0402',
 PHYS_PAGE='27',
 XY='(-8450,8850)',
 ROT='0',
 VER='2',
 CDS_LIB='passive',
 CDS_PART_NAME='RESISTOR-G155-11002-01,10KOHM,A',
 NO_ASSY='TRUE',
 TOLERANCE='1%',
 CLS_PN='G155-11002-01',
 VALUE='10KOHM',
 PRIM_FILE='./archive_libs/passive/resistor/chips/chips.prt';

PART_NAME
 R5 'RESISTOR-G155-11002-01,10KOHM,A':;

SECTION_NUMBER 1
 '@TIMECARD_LIB.TIMECARD(SCH_1):PAGE15_I169@PASSIVE.RESISTOR(CHIPS)':
 C_PATH='@timecard_lib.timecard(sch_1):page15_i169@passive.resistor(chips)',
 P_PATH='@timecard_lib.timecard(sch_1):page27_i169@passive.resistor(chips)',
 PATH='I169',
 DRAWING='@TIMECARD_LIB.TIMECARD(SCH_1):PAGE15',
 PACKAGE='0402',
 PHYS_PAGE='27',
 XY='(-8450,7400)',
 ROT='0',
 VER='2',
 CDS_LIB='passive',
 CDS_PART_NAME='RESISTOR-G155-11002-01,10KOHM,A',
 NO_ASSY='TRUE',
 TOLERANCE='1%',
 CLS_PN='G155-11002-01',
 VALUE='10KOHM',
 PRIM_FILE='./archive_libs/passive/resistor/chips/chips.prt';

PART_NAME
 R6 'RESISTOR-G155-120R0-01,20OHM,1%':;

SECTION_NUMBER 1
 '@TIMECARD_LIB.TIMECARD(SCH_1):PAGE516_I31@PASSIVE.RESISTOR(CHIPS)':
 C_PATH='@timecard_lib.timecard(sch_1):page516_i31@passive.resistor(chips)',
 P_PATH='@timecard_lib.timecard(sch_1):page32_i31@passive.resistor(chips)',
 PATH='I31',
 DRAWING='@TIMECARD_LIB.TIMECARD(SCH_1):PAGE516',
 PACKAGE='0402',
 PHYS_PAGE='32',
 XY='(-3350,6700)',
 ROT='0',
 VER='2',
 CDS_LIB='passive',
 CDS_PART_NAME='RESISTOR-G155-120R0-01,20OHM,1%',
 TOLERANCE='1%',
 CLS_PN='G155-120R0-01',
 VALUE='20OHM',
 PRIM_FILE='./archive_libs/passive/resistor/chips/chips.prt';

PART_NAME
 R7 'RESISTOR-G155-100R0-J0,0OHM,-':;

SECTION_NUMBER 1
 '@TIMECARD_LIB.TIMECARD(SCH_1):PAGE15_I174@PASSIVE.RESISTOR(CHIPS)':
 C_PATH='@timecard_lib.timecard(sch_1):page15_i174@passive.resistor(chips)',
 P_PATH='@timecard_lib.timecard(sch_1):page27_i174@passive.resistor(chips)',
 PATH='I174',
 DRAWING='@TIMECARD_LIB.TIMECARD(SCH_1):PAGE15',
 PACKAGE='0402',
 PHYS_PAGE='27',
 XY='(-7500,8100)',
 ROT='0',
 VER='1',
 CDS_LIB='passive',
 CDS_PART_NAME='RESISTOR-G155-100R0-J0,0OHM,-',
 TOLERANCE='-',
 CLS_PN='G155-100R0-J0',
 VALUE='0OHM',
 PRIM_FILE='./archive_libs/passive/resistor/chips/chips.prt';

PART_NAME
 R8 'RESISTOR-G155-100R0-J0,0OHM,-':;

SECTION_NUMBER 1
 '@TIMECARD_LIB.TIMECARD(SCH_1):PAGE15_I173@PASSIVE.RESISTOR(CHIPS)':
 C_PATH='@timecard_lib.timecard(sch_1):page15_i173@passive.resistor(chips)',
 P_PATH='@timecard_lib.timecard(sch_1):page27_i173@passive.resistor(chips)',
 PATH='I173',
 DRAWING='@TIMECARD_LIB.TIMECARD(SCH_1):PAGE15',
 PACKAGE='0402',
 PHYS_PAGE='27',
 XY='(-7500,7900)',
 ROT='0',
 VER='1',
 CDS_LIB='passive',
 CDS_PART_NAME='RESISTOR-G155-100R0-J0,0OHM,-',
 TOLERANCE='-',
 CLS_PN='G155-100R0-J0',
 VALUE='0OHM',
 PRIM_FILE='./archive_libs/passive/resistor/chips/chips.prt';

PART_NAME
 R9 'RESISTOR-G156-049R9-01,49.9OHMA':;

SECTION_NUMBER 1
 '@TIMECARD_LIB.TIMECARD(SCH_1):PAGE15_I198@PASSIVE.RESISTOR(CHIPS)':
 C_PATH='@timecard_lib.timecard(sch_1):page15_i198@passive.resistor(chips)',
 P_PATH='@timecard_lib.timecard(sch_1):page27_i198@passive.resistor(chips)',
 PATH='I198',
 DRAWING='@TIMECARD_LIB.TIMECARD(SCH_1):PAGE15',
 PACKAGE='0603',
 PHYS_PAGE='27',
 XY='(-5000,8800)',
 ROT='0',
 VER='2',
 CDS_LIB='passive',
 CDS_PART_NAME='RESISTOR-G156-049R9-01,49.9OHMA',
 TOLERANCE='1%',
 CLS_PN='G156-049R9-01',
 VALUE='49.9OHM',
 PRIM_FILE='./archive_libs/passive/resistor/chips/chips.prt';

PART_NAME
 R10 'RESISTOR-G155-11002-01,10KOHM,A':;

SECTION_NUMBER 1
 '@TIMECARD_LIB.TIMECARD(SCH_1):PAGE15_I183@PASSIVE.RESISTOR(CHIPS)':
 C_PATH='@timecard_lib.timecard(sch_1):page15_i183@passive.resistor(chips)',
 P_PATH='@timecard_lib.timecard(sch_1):page27_i183@passive.resistor(chips)',
 PATH='I183',
 DRAWING='@TIMECARD_LIB.TIMECARD(SCH_1):PAGE15',
 PACKAGE='0402',
 PHYS_PAGE='27',
 XY='(-4650,6950)',
 ROT='0',
 VER='2',
 CDS_LIB='passive',
 CDS_PART_NAME='RESISTOR-G155-11002-01,10KOHM,A',
 TOLERANCE='1%',
 CLS_PN='G155-11002-01',
 VALUE='10KOHM',
 PRIM_FILE='./archive_libs/passive/resistor/chips/chips.prt';

PART_NAME
 R11 'RESISTOR-G155-01203-01,120KOHMA':;

SECTION_NUMBER 1
 '@TIMECARD_LIB.TIMECARD(SCH_1):PAGE15_I199@PASSIVE.RESISTOR(CHIPS)':
 C_PATH='@timecard_lib.timecard(sch_1):page15_i199@passive.resistor(chips)',
 P_PATH='@timecard_lib.timecard(sch_1):page27_i199@passive.resistor(chips)',
 PATH='I199',
 DRAWING='@TIMECARD_LIB.TIMECARD(SCH_1):PAGE15',
 PACKAGE='0402',
 PHYS_PAGE='27',
 XY='(-4450,8750)',
 ROT='0',
 VER='2',
 CDS_LIB='passive',
 CDS_PART_NAME='RESISTOR-G155-01203-01,120KOHMA',
 TOLERANCE='1%',
 CLS_PN='G155-01203-01',
 VALUE='120KOHM',
 PRIM_FILE='./archive_libs/passive/resistor/chips/chips.prt';

PART_NAME
 R12 'RESISTOR-G155-11002-01,10KOHM,A':;

SECTION_NUMBER 1
 '@TIMECARD_LIB.TIMECARD(SCH_1):PAGE15_I197@PASSIVE.RESISTOR(CHIPS)':
 C_PATH='@timecard_lib.timecard(sch_1):page15_i197@passive.resistor(chips)',
 P_PATH='@timecard_lib.timecard(sch_1):page27_i197@passive.resistor(chips)',
 PATH='I197',
 DRAWING='@TIMECARD_LIB.TIMECARD(SCH_1):PAGE15',
 PACKAGE='0402',
 PHYS_PAGE='27',
 XY='(-4450,8250)',
 ROT='0',
 VER='2',
 CDS_LIB='passive',
 CDS_PART_NAME='RESISTOR-G155-11002-01,10KOHM,A',
 TOLERANCE='1%',
 CLS_PN='G155-11002-01',
 VALUE='10KOHM',
 PRIM_FILE='./archive_libs/passive/resistor/chips/chips.prt';

PART_NAME
 R13 'RESISTOR-G155-11002-01,10KOHM,A':;

SECTION_NUMBER 1
 '@TIMECARD_LIB.TIMECARD(SCH_1):PAGE15_I202@PASSIVE.RESISTOR(CHIPS)':
 C_PATH='@timecard_lib.timecard(sch_1):page15_i202@passive.resistor(chips)',
 P_PATH='@timecard_lib.timecard(sch_1):page27_i202@passive.resistor(chips)',
 PATH='I202',
 DRAWING='@TIMECARD_LIB.TIMECARD(SCH_1):PAGE15',
 PACKAGE='0402',
 PHYS_PAGE='27',
 XY='(-3600,8050)',
 ROT='0',
 VER='2',
 CDS_LIB='passive',
 CDS_PART_NAME='RESISTOR-G155-11002-01,10KOHM,A',
 TOLERANCE='1%',
 CLS_PN='G155-11002-01',
 VALUE='10KOHM',
 PRIM_FILE='./archive_libs/passive/resistor/chips/chips.prt';

PART_NAME
 R14 'RESISTOR-G155-03921-01,3.92KOHA':;

SECTION_NUMBER 1
 '@TIMECARD_LIB.TIMECARD(SCH_1):PAGE15_I186@PASSIVE.RESISTOR(CHIPS)':
 C_PATH='@timecard_lib.timecard(sch_1):page15_i186@passive.resistor(chips)',
 P_PATH='@timecard_lib.timecard(sch_1):page27_i186@passive.resistor(chips)',
 PATH='I186',
 DRAWING='@TIMECARD_LIB.TIMECARD(SCH_1):PAGE15',
 PACKAGE='0402',
 PHYS_PAGE='27',
 XY='(-3600,7250)',
 ROT='0',
 VER='2',
 CDS_LIB='passive',
 CDS_PART_NAME='RESISTOR-G155-03921-01,3.92KOHA',
 TOLERANCE='1%',
 CLS_PN='G155-03921-01',
 VALUE='3.92KOHM',
 PRIM_FILE='./archive_libs/passive/resistor/chips/chips.prt';

PART_NAME
 R15 'RESISTOR-G155-11002-01,10KOHM,A':;

SECTION_NUMBER 1
 '@TIMECARD_LIB.TIMECARD(SCH_1):PAGE15_I203@PASSIVE.RESISTOR(CHIPS)':
 C_PATH='@timecard_lib.timecard(sch_1):page15_i203@passive.resistor(chips)',
 P_PATH='@timecard_lib.timecard(sch_1):page27_i203@passive.resistor(chips)',
 PATH='I203',
 DRAWING='@TIMECARD_LIB.TIMECARD(SCH_1):PAGE15',
 PACKAGE='0402',
 PHYS_PAGE='27',
 XY='(-3050,8050)',
 ROT='0',
 VER='2',
 CDS_LIB='passive',
 CDS_PART_NAME='RESISTOR-G155-11002-01,10KOHM,A',
 TOLERANCE='1%',
 CLS_PN='G155-11002-01',
 VALUE='10KOHM',
 PRIM_FILE='./archive_libs/passive/resistor/chips/chips.prt';

PART_NAME
 R16 'RESISTOR-G155-03921-01,3.92KOHA':;

SECTION_NUMBER 1
 '@TIMECARD_LIB.TIMECARD(SCH_1):PAGE15_I188@PASSIVE.RESISTOR(CHIPS)':
 C_PATH='@timecard_lib.timecard(sch_1):page15_i188@passive.resistor(chips)',
 P_PATH='@timecard_lib.timecard(sch_1):page27_i188@passive.resistor(chips)',
 PATH='I188',
 DRAWING='@TIMECARD_LIB.TIMECARD(SCH_1):PAGE15',
 PACKAGE='0402',
 PHYS_PAGE='27',
 XY='(-3050,7250)',
 ROT='0',
 VER='2',
 CDS_LIB='passive',
 CDS_PART_NAME='RESISTOR-G155-03921-01,3.92KOHA',
 TOLERANCE='1%',
 CLS_PN='G155-03921-01',
 VALUE='3.92KOHM',
 PRIM_FILE='./archive_libs/passive/resistor/chips/chips.prt';

PART_NAME
 R17 'RESISTOR-G155-120R0-01,20OHM,1%':;

SECTION_NUMBER 1
 '@TIMECARD_LIB.TIMECARD(SCH_1):PAGE517_I33@PASSIVE.RESISTOR(CHIPS)':
 C_PATH='@timecard_lib.timecard(sch_1):page517_i33@passive.resistor(chips)',
 P_PATH='@timecard_lib.timecard(sch_1):page28_i33@passive.resistor(chips)',
 PATH='I33',
 DRAWING='@TIMECARD_LIB.TIMECARD(SCH_1):PAGE517',
 PACKAGE='0402',
 PHYS_PAGE='28',
 XY='(-3100,5900)',
 ROT='0',
 VER='2',
 CDS_LIB='passive',
 CDS_PART_NAME='RESISTOR-G155-120R0-01,20OHM,1%',
 TOLERANCE='1%',
 CLS_PN='G155-120R0-01',
 VALUE='20OHM',
 PRIM_FILE='./archive_libs/passive/resistor/chips/chips.prt';

PART_NAME
 R18 'RESISTOR-G155-14701-01,4.7KOHMA':;

SECTION_NUMBER 1
 '@TIMECARD_LIB.TIMECARD(SCH_1):PAGE524_I27@PASSIVE.RESISTOR(CHIPS)':
 C_PATH='@timecard_lib.timecard(sch_1):page524_i27@passive.resistor(chips)',
 P_PATH='@timecard_lib.timecard(sch_1):page24_i27@passive.resistor(chips)',
 PATH='I27',
 DRAWING='@TIMECARD_LIB.TIMECARD(SCH_1):PAGE524',
 PACKAGE='0402',
 PHYS_PAGE='24',
 XY='(-9600,9350)',
 ROT='1',
 VER='2',
 CDS_LIB='passive',
 CDS_PART_NAME='RESISTOR-G155-14701-01,4.7KOHMA',
 TOLERANCE='1%',
 CLS_PN='G155-14701-01',
 VALUE='4.7KOHM',
 PRIM_FILE='./archive_libs/passive/resistor/chips/chips.prt';

PART_NAME
 R19 'RESISTOR-G155-11002-01,10KOHM,A':;

SECTION_NUMBER 1
 '@TIMECARD_LIB.TIMECARD(SCH_1):PAGE5_I95@PASSIVE.RESISTOR(CHIPS)':
 C_PATH='@timecard_lib.timecard(sch_1):page5_i95@passive.resistor(chips)',
 P_PATH='@timecard_lib.timecard(sch_1):page16_i95@passive.resistor(chips)',
 PATH='I95',
 DRAWING='@TIMECARD_LIB.TIMECARD(SCH_1):PAGE5',
 PACKAGE='0402',
 PHYS_PAGE='16',
 XY='(-8900,6300)',
 ROT='0',
 VER='2',
 CDS_LIB='passive',
 CDS_PART_NAME='RESISTOR-G155-11002-01,10KOHM,A',
 TOLERANCE='1%',
 CLS_PN='G155-11002-01',
 VALUE='10KOHM',
 PRIM_FILE='./archive_libs/passive/resistor/chips/chips.prt';

PART_NAME
 R20 'RESISTOR-G155-14701-01,4.7KOHMA':;

SECTION_NUMBER 1
 '@TIMECARD_LIB.TIMECARD(SCH_1):PAGE6_I14@PASSIVE.RESISTOR(CHIPS)':
 C_PATH='@timecard_lib.timecard(sch_1):page6_i14@passive.resistor(chips)',
 P_PATH='@timecard_lib.timecard(sch_1):page17_i14@passive.resistor(chips)',
 PATH='I14',
 DRAWING='@TIMECARD_LIB.TIMECARD(SCH_1):PAGE6',
 PACKAGE='0402',
 PHYS_PAGE='17',
 XY='(-5900,8150)',
 ROT='0',
 VER='2',
 CDS_LIB='passive',
 CDS_PART_NAME='RESISTOR-G155-14701-01,4.7KOHMA',
 TOLERANCE='1%',
 CLS_PN='G155-14701-01',
 VALUE='4.7KOHM',
 PRIM_FILE='./archive_libs/passive/resistor/chips/chips.prt';

PART_NAME
 R21 'RESISTOR-G155-14701-01,4.7KOHMA':;

SECTION_NUMBER 1
 '@TIMECARD_LIB.TIMECARD(SCH_1):PAGE6_I16@PASSIVE.RESISTOR(CHIPS)':
 C_PATH='@timecard_lib.timecard(sch_1):page6_i16@passive.resistor(chips)',
 P_PATH='@timecard_lib.timecard(sch_1):page17_i16@passive.resistor(chips)',
 PATH='I16',
 DRAWING='@TIMECARD_LIB.TIMECARD(SCH_1):PAGE6',
 PACKAGE='0402',
 PHYS_PAGE='17',
 XY='(-5350,8150)',
 ROT='0',
 VER='2',
 CDS_LIB='passive',
 CDS_PART_NAME='RESISTOR-G155-14701-01,4.7KOHMA',
 TOLERANCE='1%',
 CLS_PN='G155-14701-01',
 VALUE='4.7KOHM',
 PRIM_FILE='./archive_libs/passive/resistor/chips/chips.prt';

PART_NAME
 R22 'RESISTOR-G155-100R0-J0,0OHM,-':;

SECTION_NUMBER 1
 '@TIMECARD_LIB.TIMECARD(SCH_1):PAGE3_I16@PASSIVE.RESISTOR(CHIPS)':
 C_PATH='@timecard_lib.timecard(sch_1):page3_i16@passive.resistor(chips)',
 P_PATH='@timecard_lib.timecard(sch_1):page9_i16@passive.resistor(chips)',
 PATH='I16',
 DRAWING='@TIMECARD_LIB.TIMECARD(SCH_1):PAGE3',
 PACKAGE='0402',
 PHYS_PAGE='9',
 XY='(-8400,6450)',
 ROT='0',
 VER='1',
 CDS_LIB='passive',
 CDS_PART_NAME='RESISTOR-G155-100R0-J0,0OHM,-',
 NO_ASSY='TRUE',
 TOLERANCE='-',
 CLS_PN='G155-100R0-J0',
 VALUE='0OHM',
 PRIM_FILE='./archive_libs/passive/resistor/chips/chips.prt';

PART_NAME
 R23 'RESISTOR-G155-100R0-J0,0OHM,-':;

SECTION_NUMBER 1
 '@TIMECARD_LIB.TIMECARD(SCH_1):PAGE3_I15@PASSIVE.RESISTOR(CHIPS)':
 C_PATH='@timecard_lib.timecard(sch_1):page3_i15@passive.resistor(chips)',
 P_PATH='@timecard_lib.timecard(sch_1):page9_i15@passive.resistor(chips)',
 PATH='I15',
 DRAWING='@TIMECARD_LIB.TIMECARD(SCH_1):PAGE3',
 PACKAGE='0402',
 PHYS_PAGE='9',
 XY='(-8250,5050)',
 ROT='0',
 VER='1',
 CDS_LIB='passive',
 CDS_PART_NAME='RESISTOR-G155-100R0-J0,0OHM,-',
 TOLERANCE='-',
 CLS_PN='G155-100R0-J0',
 VALUE='0OHM',
 PRIM_FILE='./archive_libs/passive/resistor/chips/chips.prt';

PART_NAME
 R24 'RESISTOR-G155-14701-01,4.7KOHMA':;

SECTION_NUMBER 1
 '@TIMECARD_LIB.TIMECARD(SCH_1):PAGE5_I167@PASSIVE.RESISTOR(CHIPS)':
 C_PATH='@timecard_lib.timecard(sch_1):page5_i167@passive.resistor(chips)',
 P_PATH='@timecard_lib.timecard(sch_1):page16_i167@passive.resistor(chips)',
 PATH='I167',
 DRAWING='@TIMECARD_LIB.TIMECARD(SCH_1):PAGE5',
 PACKAGE='0402',
 PHYS_PAGE='16',
 XY='(-8850,4000)',
 ROT='0',
 VER='2',
 CDS_LIB='passive',
 CDS_PART_NAME='RESISTOR-G155-14701-01,4.7KOHMA',
 TOLERANCE='1%',
 CLS_PN='G155-14701-01',
 VALUE='4.7KOHM',
 PRIM_FILE='./archive_libs/passive/resistor/chips/chips.prt';

PART_NAME
 R25 'RESISTOR-G155-14701-01,4.7KOHMA':;

SECTION_NUMBER 1
 '@TIMECARD_LIB.TIMECARD(SCH_1):PAGE3_I103@PASSIVE.RESISTOR(CHIPS)':
 C_PATH='@timecard_lib.timecard(sch_1):page3_i103@passive.resistor(chips)',
 P_PATH='@timecard_lib.timecard(sch_1):page9_i103@passive.resistor(chips)',
 PATH='I103',
 DRAWING='@TIMECARD_LIB.TIMECARD(SCH_1):PAGE3',
 PACKAGE='0402',
 PHYS_PAGE='9',
 XY='(-7350,2600)',
 ROT='0',
 VER='2',
 CDS_LIB='passive',
 CDS_PART_NAME='RESISTOR-G155-14701-01,4.7KOHMA',
 NO_ASSY='TRUE',
 TOLERANCE='1%',
 CLS_PN='G155-14701-01',
 VALUE='4.7KOHM',
 PRIM_FILE='./archive_libs/passive/resistor/chips/chips.prt';

PART_NAME
 R26 'RESISTOR-G155-133R0-01,33OHM,1%':;

SECTION_NUMBER 1
 '@TIMECARD_LIB.TIMECARD(SCH_1):PAGE5_I69@PASSIVE.RESISTOR(CHIPS)':
 C_PATH='@timecard_lib.timecard(sch_1):page5_i69@passive.resistor(chips)',
 P_PATH='@timecard_lib.timecard(sch_1):page16_i69@passive.resistor(chips)',
 PATH='I69',
 DRAWING='@TIMECARD_LIB.TIMECARD(SCH_1):PAGE5',
 PACKAGE='0402',
 PHYS_PAGE='16',
 XY='(-9750,10200)',
 ROT='0',
 VER='1',
 CDS_LIB='passive',
 CDS_PART_NAME='RESISTOR-G155-133R0-01,33OHM,1%',
 NO_ASSY='TRUE',
 TOLERANCE='1%',
 CLS_PN='G155-133R0-01',
 VALUE='33OHM',
 PRIM_FILE='./archive_libs/passive/resistor/chips/chips.prt';

PART_NAME
 R27 'RESISTOR-G155-133R0-01,33OHM,1%':;

SECTION_NUMBER 1
 '@TIMECARD_LIB.TIMECARD(SCH_1):PAGE5_I72@PASSIVE.RESISTOR(CHIPS)':
 C_PATH='@timecard_lib.timecard(sch_1):page5_i72@passive.resistor(chips)',
 P_PATH='@timecard_lib.timecard(sch_1):page16_i72@passive.resistor(chips)',
 PATH='I72',
 DRAWING='@TIMECARD_LIB.TIMECARD(SCH_1):PAGE5',
 PACKAGE='0402',
 PHYS_PAGE='16',
 XY='(-9750,10100)',
 ROT='0',
 VER='1',
 CDS_LIB='passive',
 CDS_PART_NAME='RESISTOR-G155-133R0-01,33OHM,1%',
 NO_ASSY='TRUE',
 TOLERANCE='1%',
 CLS_PN='G155-133R0-01',
 VALUE='33OHM',
 PRIM_FILE='./archive_libs/passive/resistor/chips/chips.prt';

PART_NAME
 R28 'RESISTOR-G155-100R0-J0,0OHM,-':;

SECTION_NUMBER 1
 '@TIMECARD_LIB.TIMECARD(SCH_1):PAGE3_I54@PASSIVE.RESISTOR(CHIPS)':
 C_PATH='@timecard_lib.timecard(sch_1):page3_i54@passive.resistor(chips)',
 P_PATH='@timecard_lib.timecard(sch_1):page9_i54@passive.resistor(chips)',
 PATH='I54',
 DRAWING='@TIMECARD_LIB.TIMECARD(SCH_1):PAGE3',
 PACKAGE='0402',
 PHYS_PAGE='9',
 XY='(-3950,7750)',
 ROT='0',
 VER='1',
 CDS_LIB='passive',
 CDS_PART_NAME='RESISTOR-G155-100R0-J0,0OHM,-',
 NO_ASSY='TRUE',
 TOLERANCE='-',
 CLS_PN='G155-100R0-J0',
 VALUE='0OHM',
 PRIM_FILE='./archive_libs/passive/resistor/chips/chips.prt';

PART_NAME
 R29 'RESISTOR-G155-11003-01,100KOHMA':;

SECTION_NUMBER 1
 '@TIMECARD_LIB.TIMECARD(SCH_1):PAGE516_I12@PASSIVE.RESISTOR(CHIPS)':
 C_PATH='@timecard_lib.timecard(sch_1):page516_i12@passive.resistor(chips)',
 P_PATH='@timecard_lib.timecard(sch_1):page32_i12@passive.resistor(chips)',
 PATH='I12',
 DRAWING='@TIMECARD_LIB.TIMECARD(SCH_1):PAGE516',
 PACKAGE='0402',
 PHYS_PAGE='32',
 XY='(-11300,5900)',
 ROT='0',
 VER='2',
 CDS_LIB='passive',
 CDS_PART_NAME='RESISTOR-G155-11003-01,100KOHMA',
 TOLERANCE='1%',
 CLS_PN='G155-11003-01',
 VALUE='100KOHM',
 PRIM_FILE='./archive_libs/passive/resistor/chips/chips.prt';

PART_NAME
 R30 'RESISTOR-G155-12201-01,2.2KOHMA':;

SECTION_NUMBER 1
 '@TIMECARD_LIB.TIMECARD(SCH_1):PAGE516_I14@PASSIVE.RESISTOR(CHIPS)':
 C_PATH='@timecard_lib.timecard(sch_1):page516_i14@passive.resistor(chips)',
 P_PATH='@timecard_lib.timecard(sch_1):page32_i14@passive.resistor(chips)',
 PATH='I14',
 DRAWING='@TIMECARD_LIB.TIMECARD(SCH_1):PAGE516',
 PACKAGE='0402',
 PHYS_PAGE='32',
 XY='(-10700,6050)',
 ROT='0',
 VER='2',
 CDS_LIB='passive',
 CDS_PART_NAME='RESISTOR-G155-12201-01,2.2KOHMA',
 TOLERANCE='1%',
 CLS_PN='G155-12201-01',
 VALUE='2.2KOHM',
 PRIM_FILE='./archive_libs/passive/resistor/chips/chips.prt';

PART_NAME
 R31 'RESISTOR-G155-100R0-J0,0OHM,-':;

SECTION_NUMBER 1
 '@TIMECARD_LIB.TIMECARD(SCH_1):PAGE516_I26@PASSIVE.RESISTOR(CHIPS)':
 C_PATH='@timecard_lib.timecard(sch_1):page516_i26@passive.resistor(chips)',
 P_PATH='@timecard_lib.timecard(sch_1):page32_i26@passive.resistor(chips)',
 PATH='I26',
 DRAWING='@TIMECARD_LIB.TIMECARD(SCH_1):PAGE516',
 PACKAGE='0402',
 PHYS_PAGE='32',
 XY='(-7100,7300)',
 ROT='0',
 VER='1',
 CDS_LIB='passive',
 CDS_PART_NAME='RESISTOR-G155-100R0-J0,0OHM,-',
 TOLERANCE='-',
 CLS_PN='G155-100R0-J0',
 VALUE='0OHM',
 PRIM_FILE='./archive_libs/passive/resistor/chips/chips.prt';

PART_NAME
 R32 'RESISTOR-G155-03241-01,3.24KOHA':;

SECTION_NUMBER 1
 '@TIMECARD_LIB.TIMECARD(SCH_1):PAGE516_I25@PASSIVE.RESISTOR(CHIPS)':
 C_PATH='@timecard_lib.timecard(sch_1):page516_i25@passive.resistor(chips)',
 P_PATH='@timecard_lib.timecard(sch_1):page32_i25@passive.resistor(chips)',
 PATH='I25',
 DRAWING='@TIMECARD_LIB.TIMECARD(SCH_1):PAGE516',
 PACKAGE='0402',
 PHYS_PAGE='32',
 XY='(-5400,5450)',
 ROT='0',
 VER='2',
 CDS_LIB='passive',
 CDS_PART_NAME='RESISTOR-G155-03241-01,3.24KOHA',
 TOLERANCE='1%',
 CLS_PN='G155-03241-01',
 VALUE='3.24KOHM',
 PRIM_FILE='./archive_libs/passive/resistor/chips/chips.prt';

PART_NAME
 R33 'RESISTOR-G157-12R20-01,2.2OHM,A':;

SECTION_NUMBER 1
 '@TIMECARD_LIB.TIMECARD(SCH_1):PAGE516_I38@PASSIVE.RESISTOR(CHIPS)':
 C_PATH='@timecard_lib.timecard(sch_1):page516_i38@passive.resistor(chips)',
 P_PATH='@timecard_lib.timecard(sch_1):page32_i38@passive.resistor(chips)',
 PATH='I38',
 DRAWING='@TIMECARD_LIB.TIMECARD(SCH_1):PAGE516',
 PACKAGE='0805',
 PHYS_PAGE='32',
 XY='(-3950,7450)',
 ROT='0',
 VER='1',
 CDS_LIB='passive',
 CDS_PART_NAME='RESISTOR-G157-12R20-01,2.2OHM,A',
 NO_ASSY='TRUE',
 TOLERANCE='1%',
 CLS_PN='G157-12R20-01',
 VALUE='2.2OHM',
 PRIM_FILE='./archive_libs/passive/resistor/chips/chips.prt';

PART_NAME
 R34 'RESISTOR-G155-02402-01,24KOHM,A':;

SECTION_NUMBER 1
 '@TIMECARD_LIB.TIMECARD(SCH_1):PAGE516_I30@PASSIVE.RESISTOR(CHIPS)':
 C_PATH='@timecard_lib.timecard(sch_1):page516_i30@passive.resistor(chips)',
 P_PATH='@timecard_lib.timecard(sch_1):page32_i30@passive.resistor(chips)',
 PATH='I30',
 DRAWING='@TIMECARD_LIB.TIMECARD(SCH_1):PAGE516',
 PACKAGE='0402',
 PHYS_PAGE='32',
 XY='(-3350,6150)',
 ROT='0',
 VER='2',
 CDS_LIB='passive',
 CDS_PART_NAME='RESISTOR-G155-02402-01,24KOHM,A',
 TOLERANCE='1%',
 CLS_PN='G155-02402-01',
 VALUE='24KOHM',
 PRIM_FILE='./archive_libs/passive/resistor/chips/chips.prt';

PART_NAME
 R35 'RESISTOR-G155-11003-01,100KOHMA':;

SECTION_NUMBER 1
 '@TIMECARD_LIB.TIMECARD(SCH_1):PAGE517_I10@PASSIVE.RESISTOR(CHIPS)':
 C_PATH='@timecard_lib.timecard(sch_1):page517_i10@passive.resistor(chips)',
 P_PATH='@timecard_lib.timecard(sch_1):page28_i10@passive.resistor(chips)',
 PATH='I10',
 DRAWING='@TIMECARD_LIB.TIMECARD(SCH_1):PAGE517',
 PACKAGE='0402',
 PHYS_PAGE='28',
 XY='(-11050,5300)',
 ROT='0',
 VER='2',
 CDS_LIB='passive',
 CDS_PART_NAME='RESISTOR-G155-11003-01,100KOHMA',
 TOLERANCE='1%',
 CLS_PN='G155-11003-01',
 VALUE='100KOHM',
 PRIM_FILE='./archive_libs/passive/resistor/chips/chips.prt';

PART_NAME
 R36 'RESISTOR-G155-11002-01,10KOHM,A':;

SECTION_NUMBER 1
 '@TIMECARD_LIB.TIMECARD(SCH_1):PAGE517_I18@PASSIVE.RESISTOR(CHIPS)':
 C_PATH='@timecard_lib.timecard(sch_1):page517_i18@passive.resistor(chips)',
 P_PATH='@timecard_lib.timecard(sch_1):page28_i18@passive.resistor(chips)',
 PATH='I18',
 DRAWING='@TIMECARD_LIB.TIMECARD(SCH_1):PAGE517',
 PACKAGE='0402',
 PHYS_PAGE='28',
 XY='(-10400,5200)',
 ROT='0',
 VER='2',
 CDS_LIB='passive',
 CDS_PART_NAME='RESISTOR-G155-11002-01,10KOHM,A',
 TOLERANCE='1%',
 CLS_PN='G155-11002-01',
 VALUE='10KOHM',
 PRIM_FILE='./archive_libs/passive/resistor/chips/chips.prt';

PART_NAME
 R37 'RESISTOR-G155-100R0-J0,0OHM,-':;

SECTION_NUMBER 1
 '@TIMECARD_LIB.TIMECARD(SCH_1):PAGE517_I25@PASSIVE.RESISTOR(CHIPS)':
 C_PATH='@timecard_lib.timecard(sch_1):page517_i25@passive.resistor(chips)',
 P_PATH='@timecard_lib.timecard(sch_1):page28_i25@passive.resistor(chips)',
 PATH='I25',
 DRAWING='@TIMECARD_LIB.TIMECARD(SCH_1):PAGE517',
 PACKAGE='0402',
 PHYS_PAGE='28',
 XY='(-6850,6500)',
 ROT='0',
 VER='1',
 CDS_LIB='passive',
 CDS_PART_NAME='RESISTOR-G155-100R0-J0,0OHM,-',
 TOLERANCE='-',
 CLS_PN='G155-100R0-J0',
 VALUE='0OHM',
 PRIM_FILE='./archive_libs/passive/resistor/chips/chips.prt';

PART_NAME
 R38 'RESISTOR-G155-04421-01,4.42KOHA':;

SECTION_NUMBER 1
 '@TIMECARD_LIB.TIMECARD(SCH_1):PAGE517_I26@PASSIVE.RESISTOR(CHIPS)':
 C_PATH='@timecard_lib.timecard(sch_1):page517_i26@passive.resistor(chips)',
 P_PATH='@timecard_lib.timecard(sch_1):page28_i26@passive.resistor(chips)',
 PATH='I26',
 DRAWING='@TIMECARD_LIB.TIMECARD(SCH_1):PAGE517',
 PACKAGE='0402',
 PHYS_PAGE='28',
 XY='(-5150,4600)',
 ROT='0',
 VER='2',
 CDS_LIB='passive',
 CDS_PART_NAME='RESISTOR-G155-04421-01,4.42KOHA',
 TOLERANCE='1%',
 CLS_PN='G155-04421-01',
 VALUE='4.42KOHM',
 PRIM_FILE='./archive_libs/passive/resistor/chips/chips.prt';

PART_NAME
 R39 'RESISTOR-G157-12R20-01,2.2OHM,A':;

SECTION_NUMBER 1
 '@TIMECARD_LIB.TIMECARD(SCH_1):PAGE517_I32@PASSIVE.RESISTOR(CHIPS)':
 C_PATH='@timecard_lib.timecard(sch_1):page517_i32@passive.resistor(chips)',
 P_PATH='@timecard_lib.timecard(sch_1):page28_i32@passive.resistor(chips)',
 PATH='I32',
 DRAWING='@TIMECARD_LIB.TIMECARD(SCH_1):PAGE517',
 PACKAGE='0805',
 PHYS_PAGE='28',
 XY='(-3650,6650)',
 ROT='0',
 VER='1',
 CDS_LIB='passive',
 CDS_PART_NAME='RESISTOR-G157-12R20-01,2.2OHM,A',
 NO_ASSY='TRUE',
 TOLERANCE='1%',
 CLS_PN='G157-12R20-01',
 VALUE='2.2OHM',
 PRIM_FILE='./archive_libs/passive/resistor/chips/chips.prt';

PART_NAME
 R40 'RESISTOR-G155-12002-01,20KOHM,A':;

SECTION_NUMBER 1
 '@TIMECARD_LIB.TIMECARD(SCH_1):PAGE517_I31@PASSIVE.RESISTOR(CHIPS)':
 C_PATH='@timecard_lib.timecard(sch_1):page517_i31@passive.resistor(chips)',
 P_PATH='@timecard_lib.timecard(sch_1):page28_i31@passive.resistor(chips)',
 PATH='I31',
 DRAWING='@TIMECARD_LIB.TIMECARD(SCH_1):PAGE517',
 PACKAGE='0402',
 PHYS_PAGE='28',
 XY='(-3100,5350)',
 ROT='0',
 VER='2',
 CDS_LIB='passive',
 CDS_PART_NAME='RESISTOR-G155-12002-01,20KOHM,A',
 TOLERANCE='1%',
 CLS_PN='G155-12002-01',
 VALUE='20KOHM',
 PRIM_FILE='./archive_libs/passive/resistor/chips/chips.prt';

PART_NAME
 R41 'RESISTOR-G155-100R0-J0,0OHM,-':;

SECTION_NUMBER 1
 '@TIMECARD_LIB.TIMECARD(SCH_1):PAGE3_I53@PASSIVE.RESISTOR(CHIPS)':
 C_PATH='@timecard_lib.timecard(sch_1):page3_i53@passive.resistor(chips)',
 P_PATH='@timecard_lib.timecard(sch_1):page9_i53@passive.resistor(chips)',
 PATH='I53',
 DRAWING='@TIMECARD_LIB.TIMECARD(SCH_1):PAGE3',
 PACKAGE='0402',
 PHYS_PAGE='9',
 XY='(-3950,7650)',
 ROT='0',
 VER='1',
 CDS_LIB='passive',
 CDS_PART_NAME='RESISTOR-G155-100R0-J0,0OHM,-',
 NO_ASSY='TRUE',
 TOLERANCE='-',
 CLS_PN='G155-100R0-J0',
 VALUE='0OHM',
 PRIM_FILE='./archive_libs/passive/resistor/chips/chips.prt';

PART_NAME
 R42 'RESISTOR-G155-100R0-J0,0OHM,-':;

SECTION_NUMBER 1
 '@TIMECARD_LIB.TIMECARD(SCH_1):PAGE3_I52@PASSIVE.RESISTOR(CHIPS)':
 C_PATH='@timecard_lib.timecard(sch_1):page3_i52@passive.resistor(chips)',
 P_PATH='@timecard_lib.timecard(sch_1):page9_i52@passive.resistor(chips)',
 PATH='I52',
 DRAWING='@TIMECARD_LIB.TIMECARD(SCH_1):PAGE3',
 PACKAGE='0402',
 PHYS_PAGE='9',
 XY='(-3950,7550)',
 ROT='0',
 VER='1',
 CDS_LIB='passive',
 CDS_PART_NAME='RESISTOR-G155-100R0-J0,0OHM,-',
 NO_ASSY='TRUE',
 TOLERANCE='-',
 CLS_PN='G155-100R0-J0',
 VALUE='0OHM',
 PRIM_FILE='./archive_libs/passive/resistor/chips/chips.prt';

PART_NAME
 R43 'RESISTOR-G155-100R0-J0,0OHM,-':;

SECTION_NUMBER 1
 '@TIMECARD_LIB.TIMECARD(SCH_1):PAGE3_I51@PASSIVE.RESISTOR(CHIPS)':
 C_PATH='@timecard_lib.timecard(sch_1):page3_i51@passive.resistor(chips)',
 P_PATH='@timecard_lib.timecard(sch_1):page9_i51@passive.resistor(chips)',
 PATH='I51',
 DRAWING='@TIMECARD_LIB.TIMECARD(SCH_1):PAGE3',
 PACKAGE='0402',
 PHYS_PAGE='9',
 XY='(-3950,7450)',
 ROT='0',
 VER='1',
 CDS_LIB='passive',
 CDS_PART_NAME='RESISTOR-G155-100R0-J0,0OHM,-',
 NO_ASSY='TRUE',
 TOLERANCE='-',
 CLS_PN='G155-100R0-J0',
 VALUE='0OHM',
 PRIM_FILE='./archive_libs/passive/resistor/chips/chips.prt';

PART_NAME
 R44 'RESISTOR-G155-14701-01,4.7KOHMA':;

SECTION_NUMBER 1
 '@TIMECARD_LIB.TIMECARD(SCH_1):PAGE527_I233@PASSIVE.RESISTOR(CHIPS)':
 C_PATH='@timecard_lib.timecard(sch_1):page527_i233@passive.resistor(chips)',
 P_PATH='@timecard_lib.timecard(sch_1):page21_i233@passive.resistor(chips)',
 PATH='I233',
 DRAWING='@TIMECARD_LIB.TIMECARD(SCH_1):PAGE527',
 PACKAGE='0402',
 PHYS_PAGE='21',
 XY='(100,1400)',
 ROT='0',
 VER='2',
 CDS_LIB='passive',
 CDS_PART_NAME='RESISTOR-G155-14701-01,4.7KOHMA',
 NO_ASSY='TRUE',
 TOLERANCE='1%',
 CLS_PN='G155-14701-01',
 VALUE='4.7KOHM',
 PRIM_FILE='./archive_libs/passive/resistor/chips/chips.prt';

PART_NAME
 R45 'RESISTOR-G155-133R0-01,33OHM,1%':;

SECTION_NUMBER 1
 '@TIMECARD_LIB.TIMECARD(SCH_1):PAGE5_I162@PASSIVE.RESISTOR(CHIPS)':
 C_PATH='@timecard_lib.timecard(sch_1):page5_i162@passive.resistor(chips)',
 P_PATH='@timecard_lib.timecard(sch_1):page16_i162@passive.resistor(chips)',
 PATH='I162',
 DRAWING='@TIMECARD_LIB.TIMECARD(SCH_1):PAGE5',
 PACKAGE='0402',
 PHYS_PAGE='16',
 XY='(-7500,4600)',
 ROT='0',
 VER='1',
 CDS_LIB='passive',
 CDS_PART_NAME='RESISTOR-G155-133R0-01,33OHM,1%',
 TOLERANCE='1%',
 CLS_PN='G155-133R0-01',
 VALUE='33OHM',
 PRIM_FILE='./archive_libs/passive/resistor/chips/chips.prt';

PART_NAME
 R46 'RESISTOR-G155-02672-01,26.7K,1%':;

SECTION_NUMBER 1
 '@TIMECARD_LIB.TIMECARD(SCH_1):PAGE15_I171@PASSIVE.RESISTOR(CHIPS)':
 C_PATH='@timecard_lib.timecard(sch_1):page15_i171@passive.resistor(chips)',
 P_PATH='@timecard_lib.timecard(sch_1):page27_i171@passive.resistor(chips)',
 PATH='I171',
 DRAWING='@TIMECARD_LIB.TIMECARD(SCH_1):PAGE15',
 PACKAGE='0402',
 PHYS_PAGE='27',
 XY='(-7550,7500)',
 ROT='0',
 VER='1',
 CDS_LIB='passive',
 CDS_PART_NAME='RESISTOR-G155-02672-01,26.7K,1%',
 TOLERANCE='1%',
 CLS_PN='G155-02672-01',
 VALUE='26.7K',
 PRIM_FILE='./archive_libs/passive/resistor/chips/chips.prt';

PART_NAME
 R47 'RESISTOR-G155-11002-01,10KOHM,A':;

SECTION_NUMBER 1
 '@TIMECARD_LIB.TIMECARD(SCH_1):PAGE516_I1@PASSIVE.RESISTOR(CHIPS)':
 C_PATH='@timecard_lib.timecard(sch_1):page516_i1@passive.resistor(chips)',
 P_PATH='@timecard_lib.timecard(sch_1):page32_i1@passive.resistor(chips)',
 PATH='I1',
 DRAWING='@TIMECARD_LIB.TIMECARD(SCH_1):PAGE516',
 PACKAGE='0402',
 PHYS_PAGE='32',
 XY='(-13950,6100)',
 ROT='0',
 VER='2',
 CDS_LIB='passive',
 CDS_PART_NAME='RESISTOR-G155-11002-01,10KOHM,A',
 NO_ASSY='TRUE',
 TOLERANCE='1%',
 CLS_PN='G155-11002-01',
 VALUE='10KOHM',
 PRIM_FILE='./archive_libs/passive/resistor/chips/chips.prt';

PART_NAME
 R48 'RESISTOR-A155-05101-DL,5.1KOHMA':;

SECTION_NUMBER 1
 '@TIMECARD_LIB.TIMECARD(SCH_1):PAGE516_I9@PASSIVE.RESISTOR(CHIPS)':
 C_PATH='@timecard_lib.timecard(sch_1):page516_i9@passive.resistor(chips)',
 P_PATH='@timecard_lib.timecard(sch_1):page32_i9@passive.resistor(chips)',
 PATH='I9',
 DRAWING='@TIMECARD_LIB.TIMECARD(SCH_1):PAGE516',
 PACKAGE='0402',
 PHYS_PAGE='32',
 XY='(-12950,6600)',
 ROT='0',
 VER='2',
 CDS_LIB='passive',
 CDS_PART_NAME='RESISTOR-A155-05101-DL,5.1KOHMA',
 NO_ASSY='TRUE',
 TOLERANCE='1%',
 CLS_PN='A155-05101-DL',
 VALUE='5.1KOHM',
 PRIM_FILE='./archive_libs/passive/resistor/chips/chips.prt';

PART_NAME
 R49 'RESISTOR-G155-11002-01,10KOHM,A':;

SECTION_NUMBER 1
 '@TIMECARD_LIB.TIMECARD(SCH_1):PAGE516_I16@PASSIVE.RESISTOR(CHIPS)':
 C_PATH='@timecard_lib.timecard(sch_1):page516_i16@passive.resistor(chips)',
 P_PATH='@timecard_lib.timecard(sch_1):page32_i16@passive.resistor(chips)',
 PATH='I16',
 DRAWING='@TIMECARD_LIB.TIMECARD(SCH_1):PAGE516',
 PACKAGE='0402',
 PHYS_PAGE='32',
 XY='(-12700,7900)',
 ROT='0',
 VER='2',
 CDS_LIB='passive',
 CDS_PART_NAME='RESISTOR-G155-11002-01,10KOHM,A',
 NO_ASSY='TRUE',
 TOLERANCE='1%',
 CLS_PN='G155-11002-01',
 VALUE='10KOHM',
 PRIM_FILE='./archive_libs/passive/resistor/chips/chips.prt';

PART_NAME
 R50 'RESISTOR-G156-100R0-J0,0OHM,-':;

SECTION_NUMBER 1
 '@TIMECARD_LIB.TIMECARD(SCH_1):PAGE516_I28@PASSIVE.RESISTOR(CHIPS)':
 C_PATH='@timecard_lib.timecard(sch_1):page516_i28@passive.resistor(chips)',
 P_PATH='@timecard_lib.timecard(sch_1):page32_i28@passive.resistor(chips)',
 PATH='I28',
 DRAWING='@TIMECARD_LIB.TIMECARD(SCH_1):PAGE516',
 PACKAGE='0603',
 PHYS_PAGE='32',
 XY='(-4800,5400)',
 ROT='1',
 VER='1',
 CDS_LIB='passive',
 CDS_PART_NAME='RESISTOR-G156-100R0-J0,0OHM,-',
 NO_ASSY='TRUE',
 TOLERANCE='-',
 CLS_PN='G156-100R0-J0',
 VALUE='0OHM',
 PRIM_FILE='./archive_libs/passive/resistor/chips/chips.prt';

PART_NAME
 R51 'RESISTOR-G155-11002-01,10KOHM,A':;

SECTION_NUMBER 1
 '@TIMECARD_LIB.TIMECARD(SCH_1):PAGE517_I3@PASSIVE.RESISTOR(CHIPS)':
 C_PATH='@timecard_lib.timecard(sch_1):page517_i3@passive.resistor(chips)',
 P_PATH='@timecard_lib.timecard(sch_1):page28_i3@passive.resistor(chips)',
 PATH='I3',
 DRAWING='@TIMECARD_LIB.TIMECARD(SCH_1):PAGE517',
 PACKAGE='0402',
 PHYS_PAGE='28',
 XY='(-13000,4450)',
 ROT='0',
 VER='2',
 CDS_LIB='passive',
 CDS_PART_NAME='RESISTOR-G155-11002-01,10KOHM,A',
 TOLERANCE='1%',
 CLS_PN='G155-11002-01',
 VALUE='10KOHM',
 PRIM_FILE='./archive_libs/passive/resistor/chips/chips.prt';

PART_NAME
 R52 'RESISTOR-G155-05101-01,5.1KOHMA':;

SECTION_NUMBER 1
 '@TIMECARD_LIB.TIMECARD(SCH_1):PAGE517_I11@PASSIVE.RESISTOR(CHIPS)':
 C_PATH='@timecard_lib.timecard(sch_1):page517_i11@passive.resistor(chips)',
 P_PATH='@timecard_lib.timecard(sch_1):page28_i11@passive.resistor(chips)',
 PATH='I11',
 DRAWING='@TIMECARD_LIB.TIMECARD(SCH_1):PAGE517',
 PACKAGE='0402',
 PHYS_PAGE='28',
 XY='(-13300,5750)',
 ROT='0',
 VER='2',
 CDS_LIB='passive',
 CDS_PART_NAME='RESISTOR-G155-05101-01,5.1KOHMA',
 TOLERANCE='1%',
 CLS_PN='G155-05101-01',
 VALUE='5.1KOHM',
 PRIM_FILE='./archive_libs/passive/resistor/chips/chips.prt';

PART_NAME
 R53 'RESISTOR-G152-10344-01,30KOHM,A':;

SECTION_NUMBER 1
 '@TIMECARD_LIB.TIMECARD(SCH_1):PAGE517_I13@PASSIVE.RESISTOR(CHIPS)':
 C_PATH='@timecard_lib.timecard(sch_1):page517_i13@passive.resistor(chips)',
 P_PATH='@timecard_lib.timecard(sch_1):page28_i13@passive.resistor(chips)',
 PATH='I13',
 DRAWING='@TIMECARD_LIB.TIMECARD(SCH_1):PAGE517',
 PACKAGE='0402',
 PHYS_PAGE='28',
 XY='(-12550,6850)',
 ROT='0',
 VER='2',
 CDS_LIB='passive',
 CDS_PART_NAME='RESISTOR-G152-10344-01,30KOHM,A',
 TOLERANCE='0.1%',
 CLS_PN='G152-10344-01',
 VALUE='30KOHM',
 PRIM_FILE='./archive_libs/passive/resistor/chips/chips.prt';

PART_NAME
 R54 'RESISTOR-G156-100R0-J0,0OHM,-':;

SECTION_NUMBER 1
 '@TIMECARD_LIB.TIMECARD(SCH_1):PAGE517_I41@PASSIVE.RESISTOR(CHIPS)':
 C_PATH='@timecard_lib.timecard(sch_1):page517_i41@passive.resistor(chips)',
 P_PATH='@timecard_lib.timecard(sch_1):page28_i41@passive.resistor(chips)',
 PATH='I41',
 DRAWING='@TIMECARD_LIB.TIMECARD(SCH_1):PAGE517',
 PACKAGE='0603',
 PHYS_PAGE='28',
 XY='(-4550,4550)',
 ROT='1',
 VER='1',
 CDS_LIB='passive',
 CDS_PART_NAME='RESISTOR-G156-100R0-J0,0OHM,-',
 NO_ASSY='TRUE',
 TOLERANCE='-',
 CLS_PN='G156-100R0-J0',
 VALUE='0OHM',
 PRIM_FILE='./archive_libs/passive/resistor/chips/chips.prt';

PART_NAME
 R55 'RESISTOR-G155-14701-01,4.7KOHMA':;

SECTION_NUMBER 1
 '@TIMECARD_LIB.TIMECARD(SCH_1):PAGE3_I62@PASSIVE.RESISTOR(CHIPS)':
 C_PATH='@timecard_lib.timecard(sch_1):page3_i62@passive.resistor(chips)',
 P_PATH='@timecard_lib.timecard(sch_1):page9_i62@passive.resistor(chips)',
 PATH='I62',
 DRAWING='@TIMECARD_LIB.TIMECARD(SCH_1):PAGE3',
 PACKAGE='0402',
 PHYS_PAGE='9',
 XY='(-1250,6700)',
 ROT='0',
 VER='2',
 CDS_LIB='passive',
 CDS_PART_NAME='RESISTOR-G155-14701-01,4.7KOHMA',
 NO_ASSY='TRUE',
 TOLERANCE='1%',
 CLS_PN='G155-14701-01',
 VALUE='4.7KOHM',
 PRIM_FILE='./archive_libs/passive/resistor/chips/chips.prt';

PART_NAME
 R56 'RESISTOR-G155-14701-01,4.7KOHMA':;

SECTION_NUMBER 1
 '@TIMECARD_LIB.TIMECARD(SCH_1):PAGE3_I63@PASSIVE.RESISTOR(CHIPS)':
 C_PATH='@timecard_lib.timecard(sch_1):page3_i63@passive.resistor(chips)',
 P_PATH='@timecard_lib.timecard(sch_1):page9_i63@passive.resistor(chips)',
 PATH='I63',
 DRAWING='@TIMECARD_LIB.TIMECARD(SCH_1):PAGE3',
 PACKAGE='0402',
 PHYS_PAGE='9',
 XY='(-1300,7600)',
 ROT='0',
 VER='2',
 CDS_LIB='passive',
 CDS_PART_NAME='RESISTOR-G155-14701-01,4.7KOHMA',
 TOLERANCE='1%',
 CLS_PN='G155-14701-01',
 VALUE='4.7KOHM',
 PRIM_FILE='./archive_libs/passive/resistor/chips/chips.prt';

PART_NAME
 R57 'RESISTOR-G155-133R0-01,33OHM,1%':;

SECTION_NUMBER 1
 '@TIMECARD_LIB.TIMECARD(SCH_1):PAGE3_I153@PASSIVE.RESISTOR(CHIPS)':
 C_PATH='@timecard_lib.timecard(sch_1):page3_i153@passive.resistor(chips)',
 P_PATH='@timecard_lib.timecard(sch_1):page9_i153@passive.resistor(chips)',
 PATH='I153',
 DRAWING='@TIMECARD_LIB.TIMECARD(SCH_1):PAGE3',
 PACKAGE='0402',
 PHYS_PAGE='9',
 XY='(900,7000)',
 ROT='0',
 VER='1',
 CDS_LIB='passive',
 CDS_PART_NAME='RESISTOR-G155-133R0-01,33OHM,1%',
 TOLERANCE='1%',
 CLS_PN='G155-133R0-01',
 VALUE='33OHM',
 PRIM_FILE='./archive_libs/passive/resistor/chips/chips.prt';

PART_NAME
 R58 'RESISTOR-G155-133R0-01,33OHM,1%':
 SIGNAL_MODEL='DEFAULT_RESISTOR_33OHM_2_1';

SECTION_NUMBER 1
 '@TIMECARD_LIB.TIMECARD(SCH_1):PAGE5_I88@PASSIVE.RESISTOR(CHIPS)':
 C_PATH='@timecard_lib.timecard(sch_1):page5_i88@passive.resistor(chips)',
 P_PATH='@timecard_lib.timecard(sch_1):page16_i88@passive.resistor(chips)',
 PATH='I88',
 DRAWING='@TIMECARD_LIB.TIMECARD(SCH_1):PAGE5',
 PACKAGE='0402',
 PHYS_PAGE='16',
 XY='(-9550,9350)',
 ROT='0',
 VER='1',
 LOCATION='R58',
 CDS_LIB='passive',
 CDS_PART_NAME='RESISTOR-G155-133R0-01,33OHM,1%',
 TOLERANCE='1%',
 CLS_PN='G155-133R0-01',
 SIGNAL_MODEL='DEFAULT_RESISTOR_33OHM_2_1',
 VALUE='33OHM',
 PRIM_FILE='./archive_libs/passive/resistor/chips/chips.prt';

PART_NAME
 R59 'RESISTOR-G155-133R0-01,33OHM,1%':
 SIGNAL_MODEL='DEFAULT_RESISTOR_33OHM_2_1';

SECTION_NUMBER 1
 '@TIMECARD_LIB.TIMECARD(SCH_1):PAGE5_I4@PASSIVE.RESISTOR(CHIPS)':
 C_PATH='@timecard_lib.timecard(sch_1):page5_i4@passive.resistor(chips)',
 P_PATH='@timecard_lib.timecard(sch_1):page16_i4@passive.resistor(chips)',
 PATH='I4',
 DRAWING='@TIMECARD_LIB.TIMECARD(SCH_1):PAGE5',
 PACKAGE='0402',
 PHYS_PAGE='16',
 XY='(-9550,9250)',
 ROT='0',
 VER='1',
 CDS_LIB='passive',
 CDS_PART_NAME='RESISTOR-G155-133R0-01,33OHM,1%',
 TOLERANCE='1%',
 CLS_PN='G155-133R0-01',
 SIGNAL_MODEL='DEFAULT_RESISTOR_33OHM_2_1',
 VALUE='33OHM',
 PRIM_FILE='./archive_libs/passive/resistor/chips/chips.prt';

PART_NAME
 R60 'RESISTOR-G155-133R0-01,33OHM,1%':
 SIGNAL_MODEL='DEFAULT_RESISTOR_33OHM_2_1';

SECTION_NUMBER 1
 '@TIMECARD_LIB.TIMECARD(SCH_1):PAGE5_I125@PASSIVE.RESISTOR(CHIPS)':
 C_PATH='@timecard_lib.timecard(sch_1):page5_i125@passive.resistor(chips)',
 P_PATH='@timecard_lib.timecard(sch_1):page16_i125@passive.resistor(chips)',
 PATH='I125',
 DRAWING='@TIMECARD_LIB.TIMECARD(SCH_1):PAGE5',
 PACKAGE='0402',
 PHYS_PAGE='16',
 XY='(-9750,10800)',
 ROT='0',
 VER='1',
 CDS_LIB='passive',
 CDS_PART_NAME='RESISTOR-G155-133R0-01,33OHM,1%',
 TOLERANCE='1%',
 CLS_PN='G155-133R0-01',
 SIGNAL_MODEL='DEFAULT_RESISTOR_33OHM_2_1',
 VALUE='33OHM',
 PRIM_FILE='./archive_libs/passive/resistor/chips/chips.prt';

PART_NAME
 R61 'RESISTOR-G155-100R0-J0,0OHM,-':;

SECTION_NUMBER 1
 '@TIMECARD_LIB.TIMECARD(SCH_1):PAGE5_I52@PASSIVE.RESISTOR(CHIPS)':
 C_PATH='@timecard_lib.timecard(sch_1):page5_i52@passive.resistor(chips)',
 P_PATH='@timecard_lib.timecard(sch_1):page16_i52@passive.resistor(chips)',
 PATH='I52',
 DRAWING='@TIMECARD_LIB.TIMECARD(SCH_1):PAGE5',
 PACKAGE='0402',
 PHYS_PAGE='16',
 XY='(-5150,9350)',
 ROT='0',
 VER='1',
 CDS_LIB='passive',
 CDS_PART_NAME='RESISTOR-G155-100R0-J0,0OHM,-',
 NO_ASSY='TRUE',
 TOLERANCE='-',
 CLS_PN='G155-100R0-J0',
 VALUE='0OHM',
 PRIM_FILE='./archive_libs/passive/resistor/chips/chips.prt';

PART_NAME
 R62 'RESISTOR-G155-100R0-J0,0OHM,-':;

SECTION_NUMBER 1
 '@TIMECARD_LIB.TIMECARD(SCH_1):PAGE5_I55@PASSIVE.RESISTOR(CHIPS)':
 C_PATH='@timecard_lib.timecard(sch_1):page5_i55@passive.resistor(chips)',
 P_PATH='@timecard_lib.timecard(sch_1):page16_i55@passive.resistor(chips)',
 PATH='I55',
 DRAWING='@TIMECARD_LIB.TIMECARD(SCH_1):PAGE5',
 PACKAGE='0402',
 PHYS_PAGE='16',
 XY='(-5150,9200)',
 ROT='1',
 VER='2',
 CDS_LIB='passive',
 CDS_PART_NAME='RESISTOR-G155-100R0-J0,0OHM,-',
 TOLERANCE='-',
 CLS_PN='G155-100R0-J0',
 VALUE='0OHM',
 PRIM_FILE='./archive_libs/passive/resistor/chips/chips.prt';

PART_NAME
 R63 'RESISTOR-G155-14701-01,4.7KOHMA':;

SECTION_NUMBER 1
 '@TIMECARD_LIB.TIMECARD(SCH_1):PAGE3_I144@PASSIVE.RESISTOR(CHIPS)':
 C_PATH='@timecard_lib.timecard(sch_1):page3_i144@passive.resistor(chips)',
 P_PATH='@timecard_lib.timecard(sch_1):page9_i144@passive.resistor(chips)',
 PATH='I144',
 DRAWING='@TIMECARD_LIB.TIMECARD(SCH_1):PAGE3',
 PACKAGE='0402',
 PHYS_PAGE='9',
 XY='(-1350,3650)',
 ROT='0',
 VER='2',
 CDS_LIB='passive',
 CDS_PART_NAME='RESISTOR-G155-14701-01,4.7KOHMA',
 TOLERANCE='1%',
 CLS_PN='G155-14701-01',
 VALUE='4.7KOHM',
 PRIM_FILE='./archive_libs/passive/resistor/chips/chips.prt';

PART_NAME
 R64 'RESISTOR-G155-14701-01,4.7KOHMA':;

SECTION_NUMBER 1
 '@TIMECARD_LIB.TIMECARD(SCH_1):PAGE7_I3@PASSIVE.RESISTOR(CHIPS)':
 C_PATH='@timecard_lib.timecard(sch_1):page7_i3@passive.resistor(chips)',
 P_PATH='@timecard_lib.timecard(sch_1):page18_i3@passive.resistor(chips)',
 PATH='I3',
 DRAWING='@TIMECARD_LIB.TIMECARD(SCH_1):PAGE7',
 PACKAGE='0402',
 PHYS_PAGE='18',
 XY='(-10400,9550)',
 ROT='0',
 VER='2',
 CDS_LIB='passive',
 CDS_PART_NAME='RESISTOR-G155-14701-01,4.7KOHMA',
 TOLERANCE='1%',
 CLS_PN='G155-14701-01',
 VALUE='4.7KOHM',
 PRIM_FILE='./archive_libs/passive/resistor/chips/chips.prt';

PART_NAME
 R65 'RESISTOR-G155-14701-01,4.7KOHMA':;

SECTION_NUMBER 1
 '@TIMECARD_LIB.TIMECARD(SCH_1):PAGE7_I4@PASSIVE.RESISTOR(CHIPS)':
 C_PATH='@timecard_lib.timecard(sch_1):page7_i4@passive.resistor(chips)',
 P_PATH='@timecard_lib.timecard(sch_1):page18_i4@passive.resistor(chips)',
 PATH='I4',
 DRAWING='@TIMECARD_LIB.TIMECARD(SCH_1):PAGE7',
 PACKAGE='0402',
 PHYS_PAGE='18',
 XY='(-9950,9550)',
 ROT='0',
 VER='2',
 CDS_LIB='passive',
 CDS_PART_NAME='RESISTOR-G155-14701-01,4.7KOHMA',
 TOLERANCE='1%',
 CLS_PN='G155-14701-01',
 VALUE='4.7KOHM',
 PRIM_FILE='./archive_libs/passive/resistor/chips/chips.prt';

PART_NAME
 R66 'RESISTOR-G155-133R0-01,33OHM,1%':
 SIGNAL_MODEL='DEFAULT_RESISTOR_33OHM_2_1';

SECTION_NUMBER 1
 '@TIMECARD_LIB.TIMECARD(SCH_1):PAGE7_I14@PASSIVE.RESISTOR(CHIPS)':
 C_PATH='@timecard_lib.timecard(sch_1):page7_i14@passive.resistor(chips)',
 P_PATH='@timecard_lib.timecard(sch_1):page18_i14@passive.resistor(chips)',
 PATH='I14',
 DRAWING='@TIMECARD_LIB.TIMECARD(SCH_1):PAGE7',
 PACKAGE='0402',
 PHYS_PAGE='18',
 XY='(-9300,9050)',
 ROT='0',
 VER='1',
 CDS_LIB='passive',
 CDS_PART_NAME='RESISTOR-G155-133R0-01,33OHM,1%',
 TOLERANCE='1%',
 CLS_PN='G155-133R0-01',
 SIGNAL_MODEL='DEFAULT_RESISTOR_33OHM_2_1',
 VALUE='33OHM',
 PRIM_FILE='./archive_libs/passive/resistor/chips/chips.prt';

PART_NAME
 R67 'RESISTOR-G155-133R0-01,33OHM,1%':
 SIGNAL_MODEL='DEFAULT_RESISTOR_33OHM_2_1';

SECTION_NUMBER 1
 '@TIMECARD_LIB.TIMECARD(SCH_1):PAGE7_I13@PASSIVE.RESISTOR(CHIPS)':
 C_PATH='@timecard_lib.timecard(sch_1):page7_i13@passive.resistor(chips)',
 P_PATH='@timecard_lib.timecard(sch_1):page18_i13@passive.resistor(chips)',
 PATH='I13',
 DRAWING='@TIMECARD_LIB.TIMECARD(SCH_1):PAGE7',
 PACKAGE='0402',
 PHYS_PAGE='18',
 XY='(-9300,8950)',
 ROT='0',
 VER='1',
 CDS_LIB='passive',
 CDS_PART_NAME='RESISTOR-G155-133R0-01,33OHM,1%',
 TOLERANCE='1%',
 CLS_PN='G155-133R0-01',
 SIGNAL_MODEL='DEFAULT_RESISTOR_33OHM_2_1',
 VALUE='33OHM',
 PRIM_FILE='./archive_libs/passive/resistor/chips/chips.prt';

PART_NAME
 R68 'RESISTOR-G155-14701-01,4.7KOHMA':;

SECTION_NUMBER 1
 '@TIMECARD_LIB.TIMECARD(SCH_1):PAGE7_I8@PASSIVE.RESISTOR(CHIPS)':
 C_PATH='@timecard_lib.timecard(sch_1):page7_i8@passive.resistor(chips)',
 P_PATH='@timecard_lib.timecard(sch_1):page18_i8@passive.resistor(chips)',
 PATH='I8',
 DRAWING='@TIMECARD_LIB.TIMECARD(SCH_1):PAGE7',
 PACKAGE='0402',
 PHYS_PAGE='18',
 XY='(-9100,8200)',
 ROT='0',
 VER='2',
 CDS_LIB='passive',
 CDS_PART_NAME='RESISTOR-G155-14701-01,4.7KOHMA',
 NO_ASSY='TRUE',
 TOLERANCE='1%',
 CLS_PN='G155-14701-01',
 VALUE='4.7KOHM',
 PRIM_FILE='./archive_libs/passive/resistor/chips/chips.prt';

PART_NAME
 R69 'RESISTOR-G155-11001-01,1KOHM,1%':;

SECTION_NUMBER 1
 '@TIMECARD_LIB.TIMECARD(SCH_1):PAGE7_I7@PASSIVE.RESISTOR(CHIPS)':
 C_PATH='@timecard_lib.timecard(sch_1):page7_i7@passive.resistor(chips)',
 P_PATH='@timecard_lib.timecard(sch_1):page18_i7@passive.resistor(chips)',
 PATH='I7',
 DRAWING='@TIMECARD_LIB.TIMECARD(SCH_1):PAGE7',
 PACKAGE='0402',
 PHYS_PAGE='18',
 XY='(-9100,7600)',
 ROT='0',
 VER='2',
 CDS_LIB='passive',
 CDS_PART_NAME='RESISTOR-G155-11001-01,1KOHM,1%',
 TOLERANCE='1%',
 CLS_PN='G155-11001-01',
 VALUE='1KOHM',
 PRIM_FILE='./archive_libs/passive/resistor/chips/chips.prt';

PART_NAME
 R70 'RESISTOR-G155-14701-01,4.7KOHMA':;

SECTION_NUMBER 1
 '@TIMECARD_LIB.TIMECARD(SCH_1):PAGE8_I3@PASSIVE.RESISTOR(CHIPS)':
 C_PATH='@timecard_lib.timecard(sch_1):page8_i3@passive.resistor(chips)',
 P_PATH='@timecard_lib.timecard(sch_1):page19_i3@passive.resistor(chips)',
 PATH='I3',
 DRAWING='@TIMECARD_LIB.TIMECARD(SCH_1):PAGE8',
 PACKAGE='0402',
 PHYS_PAGE='19',
 XY='(-9550,9400)',
 ROT='0',
 VER='2',
 CDS_LIB='passive',
 CDS_PART_NAME='RESISTOR-G155-14701-01,4.7KOHMA',
 TOLERANCE='1%',
 CLS_PN='G155-14701-01',
 VALUE='4.7KOHM',
 PRIM_FILE='./archive_libs/passive/resistor/chips/chips.prt';

PART_NAME
 R71 'RESISTOR-G155-14701-01,4.7KOHMA':;

SECTION_NUMBER 1
 '@TIMECARD_LIB.TIMECARD(SCH_1):PAGE8_I5@PASSIVE.RESISTOR(CHIPS)':
 C_PATH='@timecard_lib.timecard(sch_1):page8_i5@passive.resistor(chips)',
 P_PATH='@timecard_lib.timecard(sch_1):page19_i5@passive.resistor(chips)',
 PATH='I5',
 DRAWING='@TIMECARD_LIB.TIMECARD(SCH_1):PAGE8',
 PACKAGE='0402',
 PHYS_PAGE='19',
 XY='(-9100,9400)',
 ROT='0',
 VER='2',
 CDS_LIB='passive',
 CDS_PART_NAME='RESISTOR-G155-14701-01,4.7KOHMA',
 TOLERANCE='1%',
 CLS_PN='G155-14701-01',
 VALUE='4.7KOHM',
 PRIM_FILE='./archive_libs/passive/resistor/chips/chips.prt';

PART_NAME
 R72 'RESISTOR-G155-133R0-01,33OHM,1%':
 SIGNAL_MODEL='DEFAULT_RESISTOR_33OHM_2_1';

SECTION_NUMBER 1
 '@TIMECARD_LIB.TIMECARD(SCH_1):PAGE8_I7@PASSIVE.RESISTOR(CHIPS)':
 C_PATH='@timecard_lib.timecard(sch_1):page8_i7@passive.resistor(chips)',
 P_PATH='@timecard_lib.timecard(sch_1):page19_i7@passive.resistor(chips)',
 PATH='I7',
 DRAWING='@TIMECARD_LIB.TIMECARD(SCH_1):PAGE8',
 PACKAGE='0402',
 PHYS_PAGE='19',
 XY='(-8600,8850)',
 ROT='0',
 VER='1',
 CDS_LIB='passive',
 CDS_PART_NAME='RESISTOR-G155-133R0-01,33OHM,1%',
 TOLERANCE='1%',
 CLS_PN='G155-133R0-01',
 SIGNAL_MODEL='DEFAULT_RESISTOR_33OHM_2_1',
 VALUE='33OHM',
 PRIM_FILE='./archive_libs/passive/resistor/chips/chips.prt';

PART_NAME
 R73 'RESISTOR-G155-133R0-01,33OHM,1%':
 SIGNAL_MODEL='DEFAULT_RESISTOR_33OHM_2_1';

SECTION_NUMBER 1
 '@TIMECARD_LIB.TIMECARD(SCH_1):PAGE8_I6@PASSIVE.RESISTOR(CHIPS)':
 C_PATH='@timecard_lib.timecard(sch_1):page8_i6@passive.resistor(chips)',
 P_PATH='@timecard_lib.timecard(sch_1):page19_i6@passive.resistor(chips)',
 PATH='I6',
 DRAWING='@TIMECARD_LIB.TIMECARD(SCH_1):PAGE8',
 PACKAGE='0402',
 PHYS_PAGE='19',
 XY='(-8600,8750)',
 ROT='0',
 VER='1',
 CDS_LIB='passive',
 CDS_PART_NAME='RESISTOR-G155-133R0-01,33OHM,1%',
 TOLERANCE='1%',
 CLS_PN='G155-133R0-01',
 SIGNAL_MODEL='DEFAULT_RESISTOR_33OHM_2_1',
 VALUE='33OHM',
 PRIM_FILE='./archive_libs/passive/resistor/chips/chips.prt';

PART_NAME
 R74 'RESISTOR-G155-14701-01,4.7KOHMA':;

SECTION_NUMBER 1
 '@TIMECARD_LIB.TIMECARD(SCH_1):PAGE9_I6@PASSIVE.RESISTOR(CHIPS)':
 C_PATH='@timecard_lib.timecard(sch_1):page9_i6@passive.resistor(chips)',
 P_PATH='@timecard_lib.timecard(sch_1):page20_i6@passive.resistor(chips)',
 PATH='I6',
 DRAWING='@TIMECARD_LIB.TIMECARD(SCH_1):PAGE9',
 PACKAGE='0402',
 PHYS_PAGE='20',
 XY='(-11500,10700)',
 ROT='0',
 VER='2',
 CDS_LIB='passive',
 CDS_PART_NAME='RESISTOR-G155-14701-01,4.7KOHMA',
 TOLERANCE='1%',
 CLS_PN='G155-14701-01',
 VALUE='4.7KOHM',
 PRIM_FILE='./archive_libs/passive/resistor/chips/chips.prt';

PART_NAME
 R75 'RESISTOR-G155-14701-01,4.7KOHMA':;

SECTION_NUMBER 1
 '@TIMECARD_LIB.TIMECARD(SCH_1):PAGE9_I7@PASSIVE.RESISTOR(CHIPS)':
 C_PATH='@timecard_lib.timecard(sch_1):page9_i7@passive.resistor(chips)',
 P_PATH='@timecard_lib.timecard(sch_1):page20_i7@passive.resistor(chips)',
 PATH='I7',
 DRAWING='@TIMECARD_LIB.TIMECARD(SCH_1):PAGE9',
 PACKAGE='0402',
 PHYS_PAGE='20',
 XY='(-11100,10700)',
 ROT='0',
 VER='2',
 CDS_LIB='passive',
 CDS_PART_NAME='RESISTOR-G155-14701-01,4.7KOHMA',
 TOLERANCE='1%',
 CLS_PN='G155-14701-01',
 VALUE='4.7KOHM',
 PRIM_FILE='./archive_libs/passive/resistor/chips/chips.prt';

PART_NAME
 R76 'RESISTOR-G155-133R0-01,33OHM,1%':
 SIGNAL_MODEL='DEFAULT_RESISTOR_33OHM_2_1';

SECTION_NUMBER 1
 '@TIMECARD_LIB.TIMECARD(SCH_1):PAGE9_I12@PASSIVE.RESISTOR(CHIPS)':
 C_PATH='@timecard_lib.timecard(sch_1):page9_i12@passive.resistor(chips)',
 P_PATH='@timecard_lib.timecard(sch_1):page20_i12@passive.resistor(chips)',
 PATH='I12',
 DRAWING='@TIMECARD_LIB.TIMECARD(SCH_1):PAGE9',
 PACKAGE='0402',
 PHYS_PAGE='20',
 XY='(-10200,10000)',
 ROT='0',
 VER='1',
 CDS_LIB='passive',
 CDS_PART_NAME='RESISTOR-G155-133R0-01,33OHM,1%',
 TOLERANCE='1%',
 CLS_PN='G155-133R0-01',
 SIGNAL_MODEL='DEFAULT_RESISTOR_33OHM_2_1',
 VALUE='33OHM',
 PRIM_FILE='./archive_libs/passive/resistor/chips/chips.prt';

PART_NAME
 R77 'RESISTOR-G155-133R0-01,33OHM,1%':
 SIGNAL_MODEL='DEFAULT_RESISTOR_33OHM_2_1';

SECTION_NUMBER 1
 '@TIMECARD_LIB.TIMECARD(SCH_1):PAGE9_I11@PASSIVE.RESISTOR(CHIPS)':
 C_PATH='@timecard_lib.timecard(sch_1):page9_i11@passive.resistor(chips)',
 P_PATH='@timecard_lib.timecard(sch_1):page20_i11@passive.resistor(chips)',
 PATH='I11',
 DRAWING='@TIMECARD_LIB.TIMECARD(SCH_1):PAGE9',
 PACKAGE='0402',
 PHYS_PAGE='20',
 XY='(-10200,9900)',
 ROT='0',
 VER='1',
 CDS_LIB='passive',
 CDS_PART_NAME='RESISTOR-G155-133R0-01,33OHM,1%',
 TOLERANCE='1%',
 CLS_PN='G155-133R0-01',
 SIGNAL_MODEL='DEFAULT_RESISTOR_33OHM_2_1',
 VALUE='33OHM',
 PRIM_FILE='./archive_libs/passive/resistor/chips/chips.prt';

PART_NAME
 R78 'RESISTOR-G155-133R0-01,33OHM,1%':
 SIGNAL_MODEL='DEFAULT_RESISTOR_33OHM_2_1';

SECTION_NUMBER 1
 '@TIMECARD_LIB.TIMECARD(SCH_1):PAGE9_I41@PASSIVE.RESISTOR(CHIPS)':
 C_PATH='@timecard_lib.timecard(sch_1):page9_i41@passive.resistor(chips)',
 P_PATH='@timecard_lib.timecard(sch_1):page20_i41@passive.resistor(chips)',
 PATH='I41',
 DRAWING='@TIMECARD_LIB.TIMECARD(SCH_1):PAGE9',
 PACKAGE='0402',
 PHYS_PAGE='20',
 XY='(-2450,9700)',
 ROT='0',
 VER='1',
 CDS_LIB='passive',
 CDS_PART_NAME='RESISTOR-G155-133R0-01,33OHM,1%',
 TOLERANCE='1%',
 CLS_PN='G155-133R0-01',
 SIGNAL_MODEL='DEFAULT_RESISTOR_33OHM_2_1',
 VALUE='33OHM',
 PRIM_FILE='./archive_libs/passive/resistor/chips/chips.prt';

PART_NAME
 R79 'RESISTOR-G155-133R0-01,33OHM,1%':
 SIGNAL_MODEL='DEFAULT_RESISTOR_33OHM_2_1';

SECTION_NUMBER 1
 '@TIMECARD_LIB.TIMECARD(SCH_1):PAGE9_I31@PASSIVE.RESISTOR(CHIPS)':
 C_PATH='@timecard_lib.timecard(sch_1):page9_i31@passive.resistor(chips)',
 P_PATH='@timecard_lib.timecard(sch_1):page20_i31@passive.resistor(chips)',
 PATH='I31',
 DRAWING='@TIMECARD_LIB.TIMECARD(SCH_1):PAGE9',
 PACKAGE='0402',
 PHYS_PAGE='20',
 XY='(-10200,9800)',
 ROT='0',
 VER='1',
 CDS_LIB='passive',
 CDS_PART_NAME='RESISTOR-G155-133R0-01,33OHM,1%',
 TOLERANCE='1%',
 CLS_PN='G155-133R0-01',
 SIGNAL_MODEL='DEFAULT_RESISTOR_33OHM_2_1',
 VALUE='33OHM',
 PRIM_FILE='./archive_libs/passive/resistor/chips/chips.prt';

PART_NAME
 R80 'RESISTOR-G155-133R0-01,33OHM,1%':
 SIGNAL_MODEL='DEFAULT_RESISTOR_33OHM_2_1';

SECTION_NUMBER 1
 '@TIMECARD_LIB.TIMECARD(SCH_1):PAGE9_I32@PASSIVE.RESISTOR(CHIPS)':
 C_PATH='@timecard_lib.timecard(sch_1):page9_i32@passive.resistor(chips)',
 P_PATH='@timecard_lib.timecard(sch_1):page20_i32@passive.resistor(chips)',
 PATH='I32',
 DRAWING='@TIMECARD_LIB.TIMECARD(SCH_1):PAGE9',
 PACKAGE='0402',
 PHYS_PAGE='20',
 XY='(-10200,9700)',
 ROT='0',
 VER='1',
 CDS_LIB='passive',
 CDS_PART_NAME='RESISTOR-G155-133R0-01,33OHM,1%',
 TOLERANCE='1%',
 CLS_PN='G155-133R0-01',
 SIGNAL_MODEL='DEFAULT_RESISTOR_33OHM_2_1',
 VALUE='33OHM',
 PRIM_FILE='./archive_libs/passive/resistor/chips/chips.prt';

PART_NAME
 R81 'RESISTOR-G155-133R0-01,33OHM,1%':
 SIGNAL_MODEL='DEFAULT_RESISTOR_33OHM_2_1';

SECTION_NUMBER 1
 '@TIMECARD_LIB.TIMECARD(SCH_1):PAGE527_I240@PASSIVE.RESISTOR(CHIPS)':
 C_PATH='@timecard_lib.timecard(sch_1):page527_i240@passive.resistor(chips)',
 P_PATH='@timecard_lib.timecard(sch_1):page21_i240@passive.resistor(chips)',
 PATH='I240',
 DRAWING='@TIMECARD_LIB.TIMECARD(SCH_1):PAGE527',
 PACKAGE='0402',
 PHYS_PAGE='21',
 XY='(-9100,2200)',
 ROT='0',
 VER='1',
 CDS_LIB='passive',
 CDS_PART_NAME='RESISTOR-G155-133R0-01,33OHM,1%',
 TOLERANCE='1%',
 CLS_PN='G155-133R0-01',
 SIGNAL_MODEL='DEFAULT_RESISTOR_33OHM_2_1',
 VALUE='33OHM',
 PRIM_FILE='./archive_libs/passive/resistor/chips/chips.prt';

PART_NAME
 R82 'RESISTOR-G155-133R0-01,33OHM,1%':
 SIGNAL_MODEL='DEFAULT_RESISTOR_33OHM_2_1';

SECTION_NUMBER 1
 '@TIMECARD_LIB.TIMECARD(SCH_1):PAGE527_I241@PASSIVE.RESISTOR(CHIPS)':
 C_PATH='@timecard_lib.timecard(sch_1):page527_i241@passive.resistor(chips)',
 P_PATH='@timecard_lib.timecard(sch_1):page21_i241@passive.resistor(chips)',
 PATH='I241',
 DRAWING='@TIMECARD_LIB.TIMECARD(SCH_1):PAGE527',
 PACKAGE='0402',
 PHYS_PAGE='21',
 XY='(-9100,2100)',
 ROT='0',
 VER='1',
 CDS_LIB='passive',
 CDS_PART_NAME='RESISTOR-G155-133R0-01,33OHM,1%',
 TOLERANCE='1%',
 CLS_PN='G155-133R0-01',
 SIGNAL_MODEL='DEFAULT_RESISTOR_33OHM_2_1',
 VALUE='33OHM',
 PRIM_FILE='./archive_libs/passive/resistor/chips/chips.prt';

PART_NAME
 R83 'RESISTOR-G155-100R0-J0,0OHM,-':;

SECTION_NUMBER 1
 '@TIMECARD_LIB.TIMECARD(SCH_1):PAGE527_I32@PASSIVE.RESISTOR(CHIPS)':
 C_PATH='@timecard_lib.timecard(sch_1):page527_i32@passive.resistor(chips)',
 P_PATH='@timecard_lib.timecard(sch_1):page21_i32@passive.resistor(chips)',
 PATH='I32',
 DRAWING='@TIMECARD_LIB.TIMECARD(SCH_1):PAGE527',
 PACKAGE='0402',
 PHYS_PAGE='21',
 XY='(-7100,7450)',
 ROT='0',
 VER='1',
 CDS_LIB='passive',
 CDS_PART_NAME='RESISTOR-G155-100R0-J0,0OHM,-',
 TOLERANCE='-',
 CLS_PN='G155-100R0-J0',
 VALUE='0OHM',
 PRIM_FILE='./archive_libs/passive/resistor/chips/chips.prt';

PART_NAME
 R84 'RESISTOR-G155-100R0-J0,0OHM,-':;

SECTION_NUMBER 1
 '@TIMECARD_LIB.TIMECARD(SCH_1):PAGE527_I31@PASSIVE.RESISTOR(CHIPS)':
 C_PATH='@timecard_lib.timecard(sch_1):page527_i31@passive.resistor(chips)',
 P_PATH='@timecard_lib.timecard(sch_1):page21_i31@passive.resistor(chips)',
 PATH='I31',
 DRAWING='@TIMECARD_LIB.TIMECARD(SCH_1):PAGE527',
 PACKAGE='0402',
 PHYS_PAGE='21',
 XY='(-7100,7350)',
 ROT='0',
 VER='1',
 CDS_LIB='passive',
 CDS_PART_NAME='RESISTOR-G155-100R0-J0,0OHM,-',
 TOLERANCE='-',
 CLS_PN='G155-100R0-J0',
 VALUE='0OHM',
 PRIM_FILE='./archive_libs/passive/resistor/chips/chips.prt';

PART_NAME
 R85 'RESISTOR-G155-100R0-J0,0OHM,-':;

SECTION_NUMBER 1
 '@TIMECARD_LIB.TIMECARD(SCH_1):PAGE527_I30@PASSIVE.RESISTOR(CHIPS)':
 C_PATH='@timecard_lib.timecard(sch_1):page527_i30@passive.resistor(chips)',
 P_PATH='@timecard_lib.timecard(sch_1):page21_i30@passive.resistor(chips)',
 PATH='I30',
 DRAWING='@TIMECARD_LIB.TIMECARD(SCH_1):PAGE527',
 PACKAGE='0402',
 PHYS_PAGE='21',
 XY='(-7100,7250)',
 ROT='0',
 VER='1',
 CDS_LIB='passive',
 CDS_PART_NAME='RESISTOR-G155-100R0-J0,0OHM,-',
 TOLERANCE='-',
 CLS_PN='G155-100R0-J0',
 VALUE='0OHM',
 PRIM_FILE='./archive_libs/passive/resistor/chips/chips.prt';

PART_NAME
 R86 'RESISTOR-G155-100R0-J0,0OHM,-':;

SECTION_NUMBER 1
 '@TIMECARD_LIB.TIMECARD(SCH_1):PAGE527_I29@PASSIVE.RESISTOR(CHIPS)':
 C_PATH='@timecard_lib.timecard(sch_1):page527_i29@passive.resistor(chips)',
 P_PATH='@timecard_lib.timecard(sch_1):page21_i29@passive.resistor(chips)',
 PATH='I29',
 DRAWING='@TIMECARD_LIB.TIMECARD(SCH_1):PAGE527',
 PACKAGE='0402',
 PHYS_PAGE='21',
 XY='(-7100,7150)',
 ROT='0',
 VER='1',
 CDS_LIB='passive',
 CDS_PART_NAME='RESISTOR-G155-100R0-J0,0OHM,-',
 TOLERANCE='-',
 CLS_PN='G155-100R0-J0',
 VALUE='0OHM',
 PRIM_FILE='./archive_libs/passive/resistor/chips/chips.prt';

PART_NAME
 R87 'RESISTOR-G155-100R0-J0,0OHM,-':;

SECTION_NUMBER 1
 '@TIMECARD_LIB.TIMECARD(SCH_1):PAGE527_I14@PASSIVE.RESISTOR(CHIPS)':
 C_PATH='@timecard_lib.timecard(sch_1):page527_i14@passive.resistor(chips)',
 P_PATH='@timecard_lib.timecard(sch_1):page21_i14@passive.resistor(chips)',
 PATH='I14',
 DRAWING='@TIMECARD_LIB.TIMECARD(SCH_1):PAGE527',
 PACKAGE='0402',
 PHYS_PAGE='21',
 XY='(-7100,6650)',
 ROT='0',
 VER='1',
 CDS_LIB='passive',
 CDS_PART_NAME='RESISTOR-G155-100R0-J0,0OHM,-',
 TOLERANCE='-',
 CLS_PN='G155-100R0-J0',
 VALUE='0OHM',
 PRIM_FILE='./archive_libs/passive/resistor/chips/chips.prt';

PART_NAME
 R88 'RESISTOR-G155-100R0-J0,0OHM,-':;

SECTION_NUMBER 1
 '@TIMECARD_LIB.TIMECARD(SCH_1):PAGE527_I13@PASSIVE.RESISTOR(CHIPS)':
 C_PATH='@timecard_lib.timecard(sch_1):page527_i13@passive.resistor(chips)',
 P_PATH='@timecard_lib.timecard(sch_1):page21_i13@passive.resistor(chips)',
 PATH='I13',
 DRAWING='@TIMECARD_LIB.TIMECARD(SCH_1):PAGE527',
 PACKAGE='0402',
 PHYS_PAGE='21',
 XY='(-7100,6550)',
 ROT='0',
 VER='1',
 CDS_LIB='passive',
 CDS_PART_NAME='RESISTOR-G155-100R0-J0,0OHM,-',
 TOLERANCE='-',
 CLS_PN='G155-100R0-J0',
 VALUE='0OHM',
 PRIM_FILE='./archive_libs/passive/resistor/chips/chips.prt';

PART_NAME
 R89 'RESISTOR-G155-11000-01,100OHM,A':;

SECTION_NUMBER 1
 '@TIMECARD_LIB.TIMECARD(SCH_1):PAGE527_I34@PASSIVE.RESISTOR(CHIPS)':
 C_PATH='@timecard_lib.timecard(sch_1):page527_i34@passive.resistor(chips)',
 P_PATH='@timecard_lib.timecard(sch_1):page21_i34@passive.resistor(chips)',
 PATH='I34',
 DRAWING='@TIMECARD_LIB.TIMECARD(SCH_1):PAGE527',
 PACKAGE='0402',
 PHYS_PAGE='21',
 XY='(-6050,7550)',
 ROT='0',
 VER='1',
 CDS_LIB='passive',
 CDS_PART_NAME='RESISTOR-G155-11000-01,100OHM,A',
 NO_ASSY='TRUE',
 TOLERANCE='1%',
 CLS_PN='G155-11000-01',
 VALUE='100OHM',
 PRIM_FILE='./archive_libs/passive/resistor/chips/chips.prt';

PART_NAME
 R90 'RESISTOR-G155-11000-01,100OHM,A':;

SECTION_NUMBER 1
 '@TIMECARD_LIB.TIMECARD(SCH_1):PAGE527_I33@PASSIVE.RESISTOR(CHIPS)':
 C_PATH='@timecard_lib.timecard(sch_1):page527_i33@passive.resistor(chips)',
 P_PATH='@timecard_lib.timecard(sch_1):page21_i33@passive.resistor(chips)',
 PATH='I33',
 DRAWING='@TIMECARD_LIB.TIMECARD(SCH_1):PAGE527',
 PACKAGE='0402',
 PHYS_PAGE='21',
 XY='(-6050,7050)',
 ROT='0',
 VER='1',
 CDS_LIB='passive',
 CDS_PART_NAME='RESISTOR-G155-11000-01,100OHM,A',
 NO_ASSY='TRUE',
 TOLERANCE='1%',
 CLS_PN='G155-11000-01',
 VALUE='100OHM',
 PRIM_FILE='./archive_libs/passive/resistor/chips/chips.prt';

PART_NAME
 R91 'RESISTOR-G155-133R0-01,33OHM,1%':
 SIGNAL_MODEL='DEFAULT_RESISTOR_33OHM_2_1';

SECTION_NUMBER 1
 '@TIMECARD_LIB.TIMECARD(SCH_1):PAGE527_I187@PASSIVE.RESISTOR(CHIPS)':
 C_PATH='@timecard_lib.timecard(sch_1):page527_i187@passive.resistor(chips)',
 P_PATH='@timecard_lib.timecard(sch_1):page21_i187@passive.resistor(chips)',
 PATH='I187',
 DRAWING='@TIMECARD_LIB.TIMECARD(SCH_1):PAGE527',
 PACKAGE='0402',
 PHYS_PAGE='21',
 XY='(-8050,3800)',
 ROT='0',
 VER='1',
 CDS_LIB='passive',
 CDS_PART_NAME='RESISTOR-G155-133R0-01,33OHM,1%',
 NO_ASSY='TRUE',
 TOLERANCE='1%',
 CLS_PN='G155-133R0-01',
 SIGNAL_MODEL='DEFAULT_RESISTOR_33OHM_2_1',
 VALUE='33OHM',
 PRIM_FILE='./archive_libs/passive/resistor/chips/chips.prt';

PART_NAME
 R92 'RESISTOR-G155-11000-01,100OHM,A':;

SECTION_NUMBER 1
 '@TIMECARD_LIB.TIMECARD(SCH_1):PAGE527_I55@PASSIVE.RESISTOR(CHIPS)':
 C_PATH='@timecard_lib.timecard(sch_1):page527_i55@passive.resistor(chips)',
 P_PATH='@timecard_lib.timecard(sch_1):page21_i55@passive.resistor(chips)',
 PATH='I55',
 DRAWING='@TIMECARD_LIB.TIMECARD(SCH_1):PAGE527',
 PACKAGE='0402',
 PHYS_PAGE='21',
 XY='(-8050,3550)',
 ROT='3',
 VER='2',
 CDS_LIB='passive',
 CDS_PART_NAME='RESISTOR-G155-11000-01,100OHM,A',
 TOLERANCE='1%',
 CLS_PN='G155-11000-01',
 VALUE='100OHM',
 PRIM_FILE='./archive_libs/passive/resistor/chips/chips.prt';

PART_NAME
 R93 'RESISTOR-G155-133R0-01,33OHM,1%':
 SIGNAL_MODEL='DEFAULT_RESISTOR_33OHM_2_1';

SECTION_NUMBER 1
 '@TIMECARD_LIB.TIMECARD(SCH_1):PAGE527_I53@PASSIVE.RESISTOR(CHIPS)':
 C_PATH='@timecard_lib.timecard(sch_1):page527_i53@passive.resistor(chips)',
 P_PATH='@timecard_lib.timecard(sch_1):page21_i53@passive.resistor(chips)',
 PATH='I53',
 DRAWING='@TIMECARD_LIB.TIMECARD(SCH_1):PAGE527',
 PACKAGE='0402',
 PHYS_PAGE='21',
 XY='(-8050,3300)',
 ROT='0',
 VER='1',
 CDS_LIB='passive',
 CDS_PART_NAME='RESISTOR-G155-133R0-01,33OHM,1%',
 TOLERANCE='1%',
 CLS_PN='G155-133R0-01',
 SIGNAL_MODEL='DEFAULT_RESISTOR_33OHM_2_1',
 VALUE='33OHM',
 PRIM_FILE='./archive_libs/passive/resistor/chips/chips.prt';

PART_NAME
 R94 'RESISTOR-G155-133R0-01,33OHM,1%':
 SIGNAL_MODEL='DEFAULT_RESISTOR_33OHM_2_1';

SECTION_NUMBER 1
 '@TIMECARD_LIB.TIMECARD(SCH_1):PAGE527_I54@PASSIVE.RESISTOR(CHIPS)':
 C_PATH='@timecard_lib.timecard(sch_1):page527_i54@passive.resistor(chips)',
 P_PATH='@timecard_lib.timecard(sch_1):page21_i54@passive.resistor(chips)',
 PATH='I54',
 DRAWING='@TIMECARD_LIB.TIMECARD(SCH_1):PAGE527',
 PACKAGE='0402',
 PHYS_PAGE='21',
 XY='(-8050,3050)',
 ROT='0',
 VER='1',
 CDS_LIB='passive',
 CDS_PART_NAME='RESISTOR-G155-133R0-01,33OHM,1%',
 TOLERANCE='1%',
 CLS_PN='G155-133R0-01',
 SIGNAL_MODEL='DEFAULT_RESISTOR_33OHM_2_1',
 VALUE='33OHM',
 PRIM_FILE='./archive_libs/passive/resistor/chips/chips.prt';

PART_NAME
 R95 'RESISTOR-G155-133R0-01,33OHM,1%':
 SIGNAL_MODEL='DEFAULT_RESISTOR_33OHM_2_1';

SECTION_NUMBER 1
 '@TIMECARD_LIB.TIMECARD(SCH_1):PAGE527_I52@PASSIVE.RESISTOR(CHIPS)':
 C_PATH='@timecard_lib.timecard(sch_1):page527_i52@passive.resistor(chips)',
 P_PATH='@timecard_lib.timecard(sch_1):page21_i52@passive.resistor(chips)',
 PATH='I52',
 DRAWING='@TIMECARD_LIB.TIMECARD(SCH_1):PAGE527',
 PACKAGE='0402',
 PHYS_PAGE='21',
 XY='(-8050,2800)',
 ROT='0',
 VER='1',
 CDS_LIB='passive',
 CDS_PART_NAME='RESISTOR-G155-133R0-01,33OHM,1%',
 TOLERANCE='1%',
 CLS_PN='G155-133R0-01',
 SIGNAL_MODEL='DEFAULT_RESISTOR_33OHM_2_1',
 VALUE='33OHM',
 PRIM_FILE='./archive_libs/passive/resistor/chips/chips.prt';

PART_NAME
 R96 'RESISTOR-G155-133R0-01,33OHM,1%':
 SIGNAL_MODEL='DEFAULT_RESISTOR_33OHM_2_1';

SECTION_NUMBER 1
 '@TIMECARD_LIB.TIMECARD(SCH_1):PAGE527_I23@PASSIVE.RESISTOR(CHIPS)':
 C_PATH='@timecard_lib.timecard(sch_1):page527_i23@passive.resistor(chips)',
 P_PATH='@timecard_lib.timecard(sch_1):page21_i23@passive.resistor(chips)',
 PATH='I23',
 DRAWING='@TIMECARD_LIB.TIMECARD(SCH_1):PAGE527',
 PACKAGE='0402',
 PHYS_PAGE='21',
 XY='(-2950,6550)',
 ROT='0',
 VER='1',
 CDS_LIB='passive',
 CDS_PART_NAME='RESISTOR-G155-133R0-01,33OHM,1%',
 TOLERANCE='1%',
 CLS_PN='G155-133R0-01',
 SIGNAL_MODEL='DEFAULT_RESISTOR_33OHM_2_1',
 VALUE='33OHM',
 PRIM_FILE='./archive_libs/passive/resistor/chips/chips.prt';

PART_NAME
 R97 'RESISTOR-G155-100R0-J0,0OHM,-':;

SECTION_NUMBER 1
 '@TIMECARD_LIB.TIMECARD(SCH_1):PAGE527_I176@PASSIVE.RESISTOR(CHIPS)':
 C_PATH='@timecard_lib.timecard(sch_1):page527_i176@passive.resistor(chips)',
 P_PATH='@timecard_lib.timecard(sch_1):page21_i176@passive.resistor(chips)',
 PATH='I176',
 DRAWING='@TIMECARD_LIB.TIMECARD(SCH_1):PAGE527',
 PACKAGE='0402',
 PHYS_PAGE='21',
 XY='(-2700,7450)',
 ROT='0',
 VER='1',
 CDS_LIB='passive',
 CDS_PART_NAME='RESISTOR-G155-100R0-J0,0OHM,-',
 TOLERANCE='-',
 CLS_PN='G155-100R0-J0',
 VALUE='0OHM',
 PRIM_FILE='./archive_libs/passive/resistor/chips/chips.prt';

PART_NAME
 R98 'RESISTOR-G155-100R0-J0,0OHM,-':;

SECTION_NUMBER 1
 '@TIMECARD_LIB.TIMECARD(SCH_1):PAGE527_I175@PASSIVE.RESISTOR(CHIPS)':
 C_PATH='@timecard_lib.timecard(sch_1):page527_i175@passive.resistor(chips)',
 P_PATH='@timecard_lib.timecard(sch_1):page21_i175@passive.resistor(chips)',
 PATH='I175',
 DRAWING='@TIMECARD_LIB.TIMECARD(SCH_1):PAGE527',
 PACKAGE='0402',
 PHYS_PAGE='21',
 XY='(-2700,7350)',
 ROT='0',
 VER='1',
 CDS_LIB='passive',
 CDS_PART_NAME='RESISTOR-G155-100R0-J0,0OHM,-',
 TOLERANCE='-',
 CLS_PN='G155-100R0-J0',
 VALUE='0OHM',
 PRIM_FILE='./archive_libs/passive/resistor/chips/chips.prt';

PART_NAME
 R99 'RESISTOR-G155-14701-01,4.7KOHMA':;

SECTION_NUMBER 1
 '@TIMECARD_LIB.TIMECARD(SCH_1):PAGE527_I149@PASSIVE.RESISTOR(CHIPS)':
 C_PATH='@timecard_lib.timecard(sch_1):page527_i149@passive.resistor(chips)',
 P_PATH='@timecard_lib.timecard(sch_1):page21_i149@passive.resistor(chips)',
 PATH='I149',
 DRAWING='@TIMECARD_LIB.TIMECARD(SCH_1):PAGE527',
 PACKAGE='0402',
 PHYS_PAGE='21',
 XY='(-2350,3400)',
 ROT='0',
 VER='2',
 CDS_LIB='passive',
 CDS_PART_NAME='RESISTOR-G155-14701-01,4.7KOHMA',
 TOLERANCE='1%',
 CLS_PN='G155-14701-01',
 VALUE='4.7KOHM',
 PRIM_FILE='./archive_libs/passive/resistor/chips/chips.prt';

PART_NAME
 R100 'RESISTOR-G155-133R0-01,33OHM,1%':
 SIGNAL_MODEL='DEFAULT_RESISTOR_33OHM_2_1';

SECTION_NUMBER 1
 '@TIMECARD_LIB.TIMECARD(SCH_1):PAGE527_I155@PASSIVE.RESISTOR(CHIPS)':
 C_PATH='@timecard_lib.timecard(sch_1):page527_i155@passive.resistor(chips)',
 P_PATH='@timecard_lib.timecard(sch_1):page21_i155@passive.resistor(chips)',
 PATH='I155',
 DRAWING='@TIMECARD_LIB.TIMECARD(SCH_1):PAGE527',
 PACKAGE='0402',
 PHYS_PAGE='21',
 XY='(-1950,4150)',
 ROT='0',
 VER='1',
 CDS_LIB='passive',
 CDS_PART_NAME='RESISTOR-G155-133R0-01,33OHM,1%',
 TOLERANCE='1%',
 CLS_PN='G155-133R0-01',
 SIGNAL_MODEL='DEFAULT_RESISTOR_33OHM_2_1',
 VALUE='33OHM',
 PRIM_FILE='./archive_libs/passive/resistor/chips/chips.prt';

PART_NAME
 R101 'RESISTOR-G155-11001-01,1KOHM,1%':;

SECTION_NUMBER 1
 '@TIMECARD_LIB.TIMECARD(SCH_1):PAGE527_I200@PASSIVE.RESISTOR(CHIPS)':
 C_PATH='@timecard_lib.timecard(sch_1):page527_i200@passive.resistor(chips)',
 P_PATH='@timecard_lib.timecard(sch_1):page21_i200@passive.resistor(chips)',
 PATH='I200',
 DRAWING='@TIMECARD_LIB.TIMECARD(SCH_1):PAGE527',
 PACKAGE='0402',
 PHYS_PAGE='21',
 XY='(-8050,500)',
 ROT='0',
 VER='2',
 CDS_LIB='passive',
 CDS_PART_NAME='RESISTOR-G155-11001-01,1KOHM,1%',
 NO_ASSY='TRUE',
 TOLERANCE='1%',
 CLS_PN='G155-11001-01',
 VALUE='1KOHM',
 PRIM_FILE='./archive_libs/passive/resistor/chips/chips.prt';

PART_NAME
 R102 'RESISTOR-G155-11001-01,1KOHM,1%':;

SECTION_NUMBER 1
 '@TIMECARD_LIB.TIMECARD(SCH_1):PAGE527_I201@PASSIVE.RESISTOR(CHIPS)':
 C_PATH='@timecard_lib.timecard(sch_1):page527_i201@passive.resistor(chips)',
 P_PATH='@timecard_lib.timecard(sch_1):page21_i201@passive.resistor(chips)',
 PATH='I201',
 DRAWING='@TIMECARD_LIB.TIMECARD(SCH_1):PAGE527',
 PACKAGE='0402',
 PHYS_PAGE='21',
 XY='(-8050,50)',
 ROT='0',
 VER='2',
 CDS_LIB='passive',
 CDS_PART_NAME='RESISTOR-G155-11001-01,1KOHM,1%',
 NO_ASSY='TRUE',
 TOLERANCE='1%',
 CLS_PN='G155-11001-01',
 VALUE='1KOHM',
 PRIM_FILE='./archive_libs/passive/resistor/chips/chips.prt';

PART_NAME
 R103 'RESISTOR-G155-11001-01,1KOHM,1%':;

SECTION_NUMBER 1
 '@TIMECARD_LIB.TIMECARD(SCH_1):PAGE527_I202@PASSIVE.RESISTOR(CHIPS)':
 C_PATH='@timecard_lib.timecard(sch_1):page527_i202@passive.resistor(chips)',
 P_PATH='@timecard_lib.timecard(sch_1):page21_i202@passive.resistor(chips)',
 PATH='I202',
 DRAWING='@TIMECARD_LIB.TIMECARD(SCH_1):PAGE527',
 PACKAGE='0402',
 PHYS_PAGE='21',
 XY='(-8050,-300)',
 ROT='0',
 VER='2',
 CDS_LIB='passive',
 CDS_PART_NAME='RESISTOR-G155-11001-01,1KOHM,1%',
 NO_ASSY='TRUE',
 TOLERANCE='1%',
 CLS_PN='G155-11001-01',
 VALUE='1KOHM',
 PRIM_FILE='./archive_libs/passive/resistor/chips/chips.prt';

PART_NAME
 R104 'RESISTOR-G155-14701-01,4.7KOHMA':;

SECTION_NUMBER 1
 '@TIMECARD_LIB.TIMECARD(SCH_1):PAGE527_I126@PASSIVE.RESISTOR(CHIPS)':
 C_PATH='@timecard_lib.timecard(sch_1):page527_i126@passive.resistor(chips)',
 P_PATH='@timecard_lib.timecard(sch_1):page21_i126@passive.resistor(chips)',
 PATH='I126',
 DRAWING='@TIMECARD_LIB.TIMECARD(SCH_1):PAGE527',
 PACKAGE='0402',
 PHYS_PAGE='21',
 XY='(-3500,-100)',
 ROT='0',
 VER='2',
 CDS_LIB='passive',
 CDS_PART_NAME='RESISTOR-G155-14701-01,4.7KOHMA',
 NO_ASSY='TRUE',
 TOLERANCE='1%',
 CLS_PN='G155-14701-01',
 VALUE='4.7KOHM',
 PRIM_FILE='./archive_libs/passive/resistor/chips/chips.prt';

PART_NAME
 R105 'RESISTOR-G155-100R0-J0,0OHM,-':;

SECTION_NUMBER 1
 '@TIMECARD_LIB.TIMECARD(SCH_1):PAGE527_I123@PASSIVE.RESISTOR(CHIPS)':
 C_PATH='@timecard_lib.timecard(sch_1):page527_i123@passive.resistor(chips)',
 P_PATH='@timecard_lib.timecard(sch_1):page21_i123@passive.resistor(chips)',
 PATH='I123',
 DRAWING='@TIMECARD_LIB.TIMECARD(SCH_1):PAGE527',
 PACKAGE='0402',
 PHYS_PAGE='21',
 XY='(-3000,1200)',
 ROT='0',
 VER='1',
 CDS_LIB='passive',
 CDS_PART_NAME='RESISTOR-G155-100R0-J0,0OHM,-',
 TOLERANCE='-',
 CLS_PN='G155-100R0-J0',
 VALUE='0OHM',
 PRIM_FILE='./archive_libs/passive/resistor/chips/chips.prt';

PART_NAME
 R106 'RESISTOR-G155-100R0-J0,0OHM,-':;

SECTION_NUMBER 1
 '@TIMECARD_LIB.TIMECARD(SCH_1):PAGE527_I124@PASSIVE.RESISTOR(CHIPS)':
 C_PATH='@timecard_lib.timecard(sch_1):page527_i124@passive.resistor(chips)',
 P_PATH='@timecard_lib.timecard(sch_1):page21_i124@passive.resistor(chips)',
 PATH='I124',
 DRAWING='@TIMECARD_LIB.TIMECARD(SCH_1):PAGE527',
 PACKAGE='0402',
 PHYS_PAGE='21',
 XY='(-3000,1100)',
 ROT='0',
 VER='1',
 CDS_LIB='passive',
 CDS_PART_NAME='RESISTOR-G155-100R0-J0,0OHM,-',
 TOLERANCE='-',
 CLS_PN='G155-100R0-J0',
 VALUE='0OHM',
 PRIM_FILE='./archive_libs/passive/resistor/chips/chips.prt';

PART_NAME
 R107 'RESISTOR-G155-14701-01,4.7KOHMA':;

SECTION_NUMBER 1
 '@TIMECARD_LIB.TIMECARD(SCH_1):PAGE527_I83@PASSIVE.RESISTOR(CHIPS)':
 C_PATH='@timecard_lib.timecard(sch_1):page527_i83@passive.resistor(chips)',
 P_PATH='@timecard_lib.timecard(sch_1):page21_i83@passive.resistor(chips)',
 PATH='I83',
 DRAWING='@TIMECARD_LIB.TIMECARD(SCH_1):PAGE527',
 PACKAGE='0402',
 PHYS_PAGE='21',
 XY='(1350,4150)',
 ROT='1',
 VER='2',
 CDS_LIB='passive',
 CDS_PART_NAME='RESISTOR-G155-14701-01,4.7KOHMA',
 TOLERANCE='1%',
 CLS_PN='G155-14701-01',
 VALUE='4.7KOHM',
 PRIM_FILE='./archive_libs/passive/resistor/chips/chips.prt';

PART_NAME
 R108 'RESISTOR-G155-11000-01,100OHM,A':;

SECTION_NUMBER 1
 '@TIMECARD_LIB.TIMECARD(SCH_1):PAGE14_I58@PASSIVE.RESISTOR(CHIPS)':
 C_PATH='@timecard_lib.timecard(sch_1):page14_i58@passive.resistor(chips)',
 P_PATH='@timecard_lib.timecard(sch_1):page26_i58@passive.resistor(chips)',
 PATH='I58',
 DRAWING='@TIMECARD_LIB.TIMECARD(SCH_1):PAGE14',
 PACKAGE='0402',
 PHYS_PAGE='26',
 XY='(-9600,8850)',
 ROT='0',
 VER='1',
 CDS_LIB='passive',
 CDS_PART_NAME='RESISTOR-G155-11000-01,100OHM,A',
 TOLERANCE='1%',
 CLS_PN='G155-11000-01',
 VALUE='100OHM',
 PRIM_FILE='./archive_libs/passive/resistor/chips/chips.prt';

PART_NAME
 R109 'RESISTOR-G155-133R0-01,33OHM,1%':
 SIGNAL_MODEL='DEFAULT_RESISTOR_33OHM_2_1';

SECTION_NUMBER 1
 '@TIMECARD_LIB.TIMECARD(SCH_1):PAGE11_I11@PASSIVE.RESISTOR(CHIPS)':
 C_PATH='@timecard_lib.timecard(sch_1):page11_i11@passive.resistor(chips)',
 P_PATH='@timecard_lib.timecard(sch_1):page22_i11@passive.resistor(chips)',
 PATH='I11',
 DRAWING='@TIMECARD_LIB.TIMECARD(SCH_1):PAGE11',
 PACKAGE='0402',
 PHYS_PAGE='22',
 XY='(-6300,6150)',
 ROT='0',
 VER='1',
 CDS_LIB='passive',
 CDS_PART_NAME='RESISTOR-G155-133R0-01,33OHM,1%',
 TOLERANCE='1%',
 CLS_PN='G155-133R0-01',
 SIGNAL_MODEL='DEFAULT_RESISTOR_33OHM_2_1',
 VALUE='33OHM',
 PRIM_FILE='./archive_libs/passive/resistor/chips/chips.prt';

PART_NAME
 R110 'RESISTOR-G155-133R0-01,33OHM,1%':
 SIGNAL_MODEL='DEFAULT_RESISTOR_33OHM_2_1';

SECTION_NUMBER 1
 '@TIMECARD_LIB.TIMECARD(SCH_1):PAGE11_I29@PASSIVE.RESISTOR(CHIPS)':
 C_PATH='@timecard_lib.timecard(sch_1):page11_i29@passive.resistor(chips)',
 P_PATH='@timecard_lib.timecard(sch_1):page22_i29@passive.resistor(chips)',
 PATH='I29',
 DRAWING='@TIMECARD_LIB.TIMECARD(SCH_1):PAGE11',
 PACKAGE='0402',
 PHYS_PAGE='22',
 XY='(-6300,6050)',
 ROT='0',
 VER='1',
 CDS_LIB='passive',
 CDS_PART_NAME='RESISTOR-G155-133R0-01,33OHM,1%',
 TOLERANCE='1%',
 CLS_PN='G155-133R0-01',
 SIGNAL_MODEL='DEFAULT_RESISTOR_33OHM_2_1',
 VALUE='33OHM',
 PRIM_FILE='./archive_libs/passive/resistor/chips/chips.prt';

PART_NAME
 R111 'RESISTOR-G155-133R0-01,33OHM,1%':
 SIGNAL_MODEL='DEFAULT_RESISTOR_33OHM_2_1';

SECTION_NUMBER 1
 '@TIMECARD_LIB.TIMECARD(SCH_1):PAGE11_I5@PASSIVE.RESISTOR(CHIPS)':
 C_PATH='@timecard_lib.timecard(sch_1):page11_i5@passive.resistor(chips)',
 P_PATH='@timecard_lib.timecard(sch_1):page22_i5@passive.resistor(chips)',
 PATH='I5',
 DRAWING='@TIMECARD_LIB.TIMECARD(SCH_1):PAGE11',
 PACKAGE='0402',
 PHYS_PAGE='22',
 XY='(-6300,5950)',
 ROT='0',
 VER='1',
 CDS_LIB='passive',
 CDS_PART_NAME='RESISTOR-G155-133R0-01,33OHM,1%',
 TOLERANCE='1%',
 CLS_PN='G155-133R0-01',
 SIGNAL_MODEL='DEFAULT_RESISTOR_33OHM_2_1',
 VALUE='33OHM',
 PRIM_FILE='./archive_libs/passive/resistor/chips/chips.prt';

PART_NAME
 R112 'RESISTOR-G155-133R0-01,33OHM,1%':
 SIGNAL_MODEL='DEFAULT_RESISTOR_33OHM_2_1';

SECTION_NUMBER 1
 '@TIMECARD_LIB.TIMECARD(SCH_1):PAGE11_I8@PASSIVE.RESISTOR(CHIPS)':
 C_PATH='@timecard_lib.timecard(sch_1):page11_i8@passive.resistor(chips)',
 P_PATH='@timecard_lib.timecard(sch_1):page22_i8@passive.resistor(chips)',
 PATH='I8',
 DRAWING='@TIMECARD_LIB.TIMECARD(SCH_1):PAGE11',
 PACKAGE='0402',
 PHYS_PAGE='22',
 XY='(-6300,5800)',
 ROT='0',
 VER='1',
 CDS_LIB='passive',
 CDS_PART_NAME='RESISTOR-G155-133R0-01,33OHM,1%',
 TOLERANCE='1%',
 CLS_PN='G155-133R0-01',
 SIGNAL_MODEL='DEFAULT_RESISTOR_33OHM_2_1',
 VALUE='33OHM',
 PRIM_FILE='./archive_libs/passive/resistor/chips/chips.prt';

PART_NAME
 R113 'RESISTOR-G155-133R0-01,33OHM,1%':
 SIGNAL_MODEL='DEFAULT_RESISTOR_33OHM_2_1';

SECTION_NUMBER 1
 '@TIMECARD_LIB.TIMECARD(SCH_1):PAGE11_I7@PASSIVE.RESISTOR(CHIPS)':
 C_PATH='@timecard_lib.timecard(sch_1):page11_i7@passive.resistor(chips)',
 P_PATH='@timecard_lib.timecard(sch_1):page22_i7@passive.resistor(chips)',
 PATH='I7',
 DRAWING='@TIMECARD_LIB.TIMECARD(SCH_1):PAGE11',
 PACKAGE='0402',
 PHYS_PAGE='22',
 XY='(-6300,5700)',
 ROT='0',
 VER='1',
 CDS_LIB='passive',
 CDS_PART_NAME='RESISTOR-G155-133R0-01,33OHM,1%',
 TOLERANCE='1%',
 CLS_PN='G155-133R0-01',
 SIGNAL_MODEL='DEFAULT_RESISTOR_33OHM_2_1',
 VALUE='33OHM',
 PRIM_FILE='./archive_libs/passive/resistor/chips/chips.prt';

PART_NAME
 R114 'RESISTOR-G155-14701-01,4.7KOHMA':;

SECTION_NUMBER 1
 '@TIMECARD_LIB.TIMECARD(SCH_1):PAGE11_I18@PASSIVE.RESISTOR(CHIPS)':
 C_PATH='@timecard_lib.timecard(sch_1):page11_i18@passive.resistor(chips)',
 P_PATH='@timecard_lib.timecard(sch_1):page22_i18@passive.resistor(chips)',
 PATH='I18',
 DRAWING='@TIMECARD_LIB.TIMECARD(SCH_1):PAGE11',
 PACKAGE='0402',
 PHYS_PAGE='22',
 XY='(-3450,5800)',
 ROT='0',
 VER='2',
 CDS_LIB='passive',
 CDS_PART_NAME='RESISTOR-G155-14701-01,4.7KOHMA',
 NO_ASSY='TRUE',
 TOLERANCE='1%',
 CLS_PN='G155-14701-01',
 VALUE='4.7KOHM',
 PRIM_FILE='./archive_libs/passive/resistor/chips/chips.prt';

PART_NAME
 R115 'RESISTOR-G155-14701-01,4.7KOHMA':;

SECTION_NUMBER 1
 '@TIMECARD_LIB.TIMECARD(SCH_1):PAGE11_I21@PASSIVE.RESISTOR(CHIPS)':
 C_PATH='@timecard_lib.timecard(sch_1):page11_i21@passive.resistor(chips)',
 P_PATH='@timecard_lib.timecard(sch_1):page22_i21@passive.resistor(chips)',
 PATH='I21',
 DRAWING='@TIMECARD_LIB.TIMECARD(SCH_1):PAGE11',
 PACKAGE='0402',
 PHYS_PAGE='22',
 XY='(-3400,6750)',
 ROT='0',
 VER='2',
 CDS_LIB='passive',
 CDS_PART_NAME='RESISTOR-G155-14701-01,4.7KOHMA',
 TOLERANCE='1%',
 CLS_PN='G155-14701-01',
 VALUE='4.7KOHM',
 PRIM_FILE='./archive_libs/passive/resistor/chips/chips.prt';

PART_NAME
 R116 'RESISTOR-G155-133R0-01,33OHM,1%':
 SIGNAL_MODEL='DEFAULT_RESISTOR_33OHM_2_1';

SECTION_NUMBER 1
 '@TIMECARD_LIB.TIMECARD(SCH_1):PAGE11_I25@PASSIVE.RESISTOR(CHIPS)':
 C_PATH='@timecard_lib.timecard(sch_1):page11_i25@passive.resistor(chips)',
 P_PATH='@timecard_lib.timecard(sch_1):page22_i25@passive.resistor(chips)',
 PATH='I25',
 DRAWING='@TIMECARD_LIB.TIMECARD(SCH_1):PAGE11',
 PACKAGE='0402',
 PHYS_PAGE='22',
 XY='(-2050,6150)',
 ROT='0',
 VER='1',
 CDS_LIB='passive',
 CDS_PART_NAME='RESISTOR-G155-133R0-01,33OHM,1%',
 TOLERANCE='1%',
 CLS_PN='G155-133R0-01',
 SIGNAL_MODEL='DEFAULT_RESISTOR_33OHM_2_1',
 VALUE='33OHM',
 PRIM_FILE='./archive_libs/passive/resistor/chips/chips.prt';

PART_NAME
 R117 'RESISTOR-G155-133R0-01,33OHM,1%':
 SIGNAL_MODEL='DEFAULT_RESISTOR_33OHM_2_1';

SECTION_NUMBER 1
 '@TIMECARD_LIB.TIMECARD(SCH_1):PAGE11_I20@PASSIVE.RESISTOR(CHIPS)':
 C_PATH='@timecard_lib.timecard(sch_1):page11_i20@passive.resistor(chips)',
 P_PATH='@timecard_lib.timecard(sch_1):page22_i20@passive.resistor(chips)',
 PATH='I20',
 DRAWING='@TIMECARD_LIB.TIMECARD(SCH_1):PAGE11',
 PACKAGE='0402',
 PHYS_PAGE='22',
 XY='(-2050,6050)',
 ROT='0',
 VER='1',
 CDS_LIB='passive',
 CDS_PART_NAME='RESISTOR-G155-133R0-01,33OHM,1%',
 TOLERANCE='1%',
 CLS_PN='G155-133R0-01',
 SIGNAL_MODEL='DEFAULT_RESISTOR_33OHM_2_1',
 VALUE='33OHM',
 PRIM_FILE='./archive_libs/passive/resistor/chips/chips.prt';

PART_NAME
 R118 'RESISTOR-G155-13300-01,330OHM,A':;

SECTION_NUMBER 1
 '@TIMECARD_LIB.TIMECARD(SCH_1):PAGE14_I190@PASSIVE.RESISTOR(CHIPS)':
 C_PATH='@timecard_lib.timecard(sch_1):page14_i190@passive.resistor(chips)',
 P_PATH='@timecard_lib.timecard(sch_1):page26_i190@passive.resistor(chips)',
 PATH='I190',
 DRAWING='@TIMECARD_LIB.TIMECARD(SCH_1):PAGE14',
 PACKAGE='0402',
 PHYS_PAGE='26',
 XY='(-9250,7750)',
 ROT='0',
 VER='1',
 CDS_LIB='passive',
 CDS_PART_NAME='RESISTOR-G155-13300-01,330OHM,A',
 TOLERANCE='1%',
 CLS_PN='G155-13300-01',
 VALUE='330OHM',
 PRIM_FILE='./archive_libs/passive/resistor/chips/chips.prt';

PART_NAME
 R119 'RESISTOR-G155-13300-01,330OHM,A':;

SECTION_NUMBER 1
 '@TIMECARD_LIB.TIMECARD(SCH_1):PAGE14_I192@PASSIVE.RESISTOR(CHIPS)':
 C_PATH='@timecard_lib.timecard(sch_1):page14_i192@passive.resistor(chips)',
 P_PATH='@timecard_lib.timecard(sch_1):page26_i192@passive.resistor(chips)',
 PATH='I192',
 DRAWING='@TIMECARD_LIB.TIMECARD(SCH_1):PAGE14',
 PACKAGE='0402',
 PHYS_PAGE='26',
 XY='(-9250,7400)',
 ROT='0',
 VER='1',
 CDS_LIB='passive',
 CDS_PART_NAME='RESISTOR-G155-13300-01,330OHM,A',
 TOLERANCE='1%',
 CLS_PN='G155-13300-01',
 VALUE='330OHM',
 PRIM_FILE='./archive_libs/passive/resistor/chips/chips.prt';

PART_NAME
 R120 'RESISTOR-G155-11000-01,100OHM,A':;

SECTION_NUMBER 1
 '@TIMECARD_LIB.TIMECARD(SCH_1):PAGE12_I265@PASSIVE.RESISTOR(CHIPS)':
 C_PATH='@timecard_lib.timecard(sch_1):page12_i265@passive.resistor(chips)',
 P_PATH='@timecard_lib.timecard(sch_1):page23_i265@passive.resistor(chips)',
 PATH='I265',
 DRAWING='@TIMECARD_LIB.TIMECARD(SCH_1):PAGE12',
 PACKAGE='0402',
 PHYS_PAGE='23',
 XY='(-10700,4750)',
 ROT='3',
 VER='2',
 LOCATION='R120',
 CDS_LIB='passive',
 CDS_PART_NAME='RESISTOR-G155-11000-01,100OHM,A',
 TOLERANCE='1%',
 CLS_PN='G155-11000-01',
 VALUE='100OHM',
 PRIM_FILE='./archive_libs/passive/resistor/chips/chips.prt';

PART_NAME
 R121 'RESISTOR-G155-11000-01,100OHM,A':;

SECTION_NUMBER 1
 '@TIMECARD_LIB.TIMECARD(SCH_1):PAGE12_I284@PASSIVE.RESISTOR(CHIPS)':
 C_PATH='@timecard_lib.timecard(sch_1):page12_i284@passive.resistor(chips)',
 P_PATH='@timecard_lib.timecard(sch_1):page23_i284@passive.resistor(chips)',
 PATH='I284',
 DRAWING='@TIMECARD_LIB.TIMECARD(SCH_1):PAGE12',
 PACKAGE='0402',
 PHYS_PAGE='23',
 XY='(-10650,2600)',
 ROT='3',
 VER='2',
 LOCATION='R121',
 CDS_LIB='passive',
 CDS_PART_NAME='RESISTOR-G155-11000-01,100OHM,A',
 TOLERANCE='1%',
 CLS_PN='G155-11000-01',
 VALUE='100OHM',
 PRIM_FILE='./archive_libs/passive/resistor/chips/chips.prt';

PART_NAME
 R122 'RESISTOR-G155-149R9-01,49.9OHMA':;

SECTION_NUMBER 1
 '@TIMECARD_LIB.TIMECARD(SCH_1):PAGE12_I197@PASSIVE.RESISTOR(CHIPS)':
 C_PATH='@timecard_lib.timecard(sch_1):page12_i197@passive.resistor(chips)',
 P_PATH='@timecard_lib.timecard(sch_1):page23_i197@passive.resistor(chips)',
 PATH='I197',
 DRAWING='@TIMECARD_LIB.TIMECARD(SCH_1):PAGE12',
 PACKAGE='0402',
 PHYS_PAGE='23',
 XY='(-6400,9050)',
 ROT='3',
 VER='2',
 LOCATION='R122',
 CDS_LIB='passive',
 CDS_PART_NAME='RESISTOR-G155-149R9-01,49.9OHMA',
 TOLERANCE='1%',
 CLS_PN='G155-149R9-01',
 VALUE='49.9OHM',
 PRIM_FILE='./archive_libs/passive/resistor/chips/chips.prt';

PART_NAME
 R123 'RESISTOR-G155-149R9-01,49.9OHMA':;

SECTION_NUMBER 1
 '@TIMECARD_LIB.TIMECARD(SCH_1):PAGE12_I228@PASSIVE.RESISTOR(CHIPS)':
 C_PATH='@timecard_lib.timecard(sch_1):page12_i228@passive.resistor(chips)',
 P_PATH='@timecard_lib.timecard(sch_1):page23_i228@passive.resistor(chips)',
 PATH='I228',
 DRAWING='@TIMECARD_LIB.TIMECARD(SCH_1):PAGE12',
 PACKAGE='0402',
 PHYS_PAGE='23',
 XY='(-6350,6900)',
 ROT='3',
 VER='2',
 LOCATION='R123',
 CDS_LIB='passive',
 CDS_PART_NAME='RESISTOR-G155-149R9-01,49.9OHMA',
 TOLERANCE='1%',
 CLS_PN='G155-149R9-01',
 VALUE='49.9OHM',
 PRIM_FILE='./archive_libs/passive/resistor/chips/chips.prt';

PART_NAME
 R124 'RESISTOR-G155-11000-01,100OHM,A':;

SECTION_NUMBER 1
 '@TIMECARD_LIB.TIMECARD(SCH_1):PAGE14_I160@PASSIVE.RESISTOR(CHIPS)':
 C_PATH='@timecard_lib.timecard(sch_1):page14_i160@passive.resistor(chips)',
 P_PATH='@timecard_lib.timecard(sch_1):page26_i160@passive.resistor(chips)',
 PATH='I160',
 DRAWING='@TIMECARD_LIB.TIMECARD(SCH_1):PAGE14',
 PACKAGE='0402',
 PHYS_PAGE='26',
 XY='(-2800,10600)',
 ROT='0',
 VER='1',
 CDS_LIB='passive',
 CDS_PART_NAME='RESISTOR-G155-11000-01,100OHM,A',
 NO_ASSY='TRUE',
 TOLERANCE='1%',
 CLS_PN='G155-11000-01',
 VALUE='100OHM',
 PRIM_FILE='./archive_libs/passive/resistor/chips/chips.prt';

PART_NAME
 R125 'RESISTOR-G155-11000-01,100OHM,A':;

SECTION_NUMBER 1
 '@TIMECARD_LIB.TIMECARD(SCH_1):PAGE14_I161@PASSIVE.RESISTOR(CHIPS)':
 C_PATH='@timecard_lib.timecard(sch_1):page14_i161@passive.resistor(chips)',
 P_PATH='@timecard_lib.timecard(sch_1):page26_i161@passive.resistor(chips)',
 PATH='I161',
 DRAWING='@TIMECARD_LIB.TIMECARD(SCH_1):PAGE14',
 PACKAGE='0402',
 PHYS_PAGE='26',
 XY='(-2800,11200)',
 ROT='0',
 VER='1',
 CDS_LIB='passive',
 CDS_PART_NAME='RESISTOR-G155-11000-01,100OHM,A',
 NO_ASSY='TRUE',
 TOLERANCE='1%',
 CLS_PN='G155-11000-01',
 VALUE='100OHM',
 PRIM_FILE='./archive_libs/passive/resistor/chips/chips.prt';

PART_NAME
 R126 'RESISTOR-G155-149R9-01,49.9OHMA':;

SECTION_NUMBER 1
 '@TIMECARD_LIB.TIMECARD(SCH_1):PAGE12_I276@PASSIVE.RESISTOR(CHIPS)':
 C_PATH='@timecard_lib.timecard(sch_1):page12_i276@passive.resistor(chips)',
 P_PATH='@timecard_lib.timecard(sch_1):page23_i276@passive.resistor(chips)',
 PATH='I276',
 DRAWING='@TIMECARD_LIB.TIMECARD(SCH_1):PAGE12',
 PACKAGE='0402',
 PHYS_PAGE='23',
 XY='(-6300,2600)',
 ROT='3',
 VER='2',
 LOCATION='R126',
 CDS_LIB='passive',
 CDS_PART_NAME='RESISTOR-G155-149R9-01,49.9OHMA',
 TOLERANCE='1%',
 CLS_PN='G155-149R9-01',
 VALUE='49.9OHM',
 PRIM_FILE='./archive_libs/passive/resistor/chips/chips.prt';

PART_NAME
 R127 'RESISTOR-G155-149R9-01,49.9OHMA':;

SECTION_NUMBER 1
 '@TIMECARD_LIB.TIMECARD(SCH_1):PAGE12_I257@PASSIVE.RESISTOR(CHIPS)':
 C_PATH='@timecard_lib.timecard(sch_1):page12_i257@passive.resistor(chips)',
 P_PATH='@timecard_lib.timecard(sch_1):page23_i257@passive.resistor(chips)',
 PATH='I257',
 DRAWING='@TIMECARD_LIB.TIMECARD(SCH_1):PAGE12',
 PACKAGE='0402',
 PHYS_PAGE='23',
 XY='(-6350,4750)',
 ROT='3',
 VER='2',
 LOCATION='R127',
 CDS_LIB='passive',
 CDS_PART_NAME='RESISTOR-G155-149R9-01,49.9OHMA',
 TOLERANCE='1%',
 CLS_PN='G155-149R9-01',
 VALUE='49.9OHM',
 PRIM_FILE='./archive_libs/passive/resistor/chips/chips.prt';

PART_NAME
 R128 'RESISTOR-G155-100R0-J0,0OHM,-':;

SECTION_NUMBER 1
 '@TIMECARD_LIB.TIMECARD(SCH_1):PAGE524_I28@PASSIVE.RESISTOR(CHIPS)':
 C_PATH='@timecard_lib.timecard(sch_1):page524_i28@passive.resistor(chips)',
 P_PATH='@timecard_lib.timecard(sch_1):page24_i28@passive.resistor(chips)',
 PATH='I28',
 DRAWING='@TIMECARD_LIB.TIMECARD(SCH_1):PAGE524',
 PACKAGE='0402',
 PHYS_PAGE='24',
 XY='(-9300,9850)',
 ROT='0',
 VER='1',
 CDS_LIB='passive',
 CDS_PART_NAME='RESISTOR-G155-100R0-J0,0OHM,-',
 TOLERANCE='-',
 CLS_PN='G155-100R0-J0',
 VALUE='0OHM',
 PRIM_FILE='./archive_libs/passive/resistor/chips/chips.prt';

PART_NAME
 R129 'RESISTOR-G155-100R0-J0,0OHM,-':;

SECTION_NUMBER 1
 '@TIMECARD_LIB.TIMECARD(SCH_1):PAGE524_I26@PASSIVE.RESISTOR(CHIPS)':
 C_PATH='@timecard_lib.timecard(sch_1):page524_i26@passive.resistor(chips)',
 P_PATH='@timecard_lib.timecard(sch_1):page24_i26@passive.resistor(chips)',
 PATH='I26',
 DRAWING='@TIMECARD_LIB.TIMECARD(SCH_1):PAGE524',
 PACKAGE='0402',
 PHYS_PAGE='24',
 XY='(-9300,9750)',
 ROT='0',
 VER='1',
 CDS_LIB='passive',
 CDS_PART_NAME='RESISTOR-G155-100R0-J0,0OHM,-',
 TOLERANCE='-',
 CLS_PN='G155-100R0-J0',
 VALUE='0OHM',
 PRIM_FILE='./archive_libs/passive/resistor/chips/chips.prt';

PART_NAME
 R130 'RESISTOR-G155-11002-01,10KOHM,A':;

SECTION_NUMBER 1
 '@TIMECARD_LIB.TIMECARD(SCH_1):PAGE524_I23@PASSIVE.RESISTOR(CHIPS)':
 C_PATH='@timecard_lib.timecard(sch_1):page524_i23@passive.resistor(chips)',
 P_PATH='@timecard_lib.timecard(sch_1):page24_i23@passive.resistor(chips)',
 PATH='I23',
 DRAWING='@TIMECARD_LIB.TIMECARD(SCH_1):PAGE524',
 PACKAGE='0402',
 PHYS_PAGE='24',
 XY='(-8950,8150)',
 ROT='0',
 VER='2',
 CDS_LIB='passive',
 CDS_PART_NAME='RESISTOR-G155-11002-01,10KOHM,A',
 TOLERANCE='1%',
 CLS_PN='G155-11002-01',
 VALUE='10KOHM',
 PRIM_FILE='./archive_libs/passive/resistor/chips/chips.prt';

PART_NAME
 R131 'RESISTOR-G155-11000-01,100OHM,A':;

SECTION_NUMBER 1
 '@TIMECARD_LIB.TIMECARD(SCH_1):PAGE524_I187@PASSIVE.RESISTOR(CHIPS)':
 C_PATH='@timecard_lib.timecard(sch_1):page524_i187@passive.resistor(chips)',
 P_PATH='@timecard_lib.timecard(sch_1):page24_i187@passive.resistor(chips)',
 PATH='I187',
 DRAWING='@TIMECARD_LIB.TIMECARD(SCH_1):PAGE524',
 PACKAGE='0402',
 PHYS_PAGE='24',
 XY='(-5300,8750)',
 ROT='0',
 VER='1',
 CDS_LIB='passive',
 CDS_PART_NAME='RESISTOR-G155-11000-01,100OHM,A',
 TOLERANCE='1%',
 CLS_PN='G155-11000-01',
 VALUE='100OHM',
 PRIM_FILE='./archive_libs/passive/resistor/chips/chips.prt';

PART_NAME
 R132 'RESISTOR-G155-11000-01,100OHM,A':;

SECTION_NUMBER 1
 '@TIMECARD_LIB.TIMECARD(SCH_1):PAGE524_I188@PASSIVE.RESISTOR(CHIPS)':
 C_PATH='@timecard_lib.timecard(sch_1):page524_i188@passive.resistor(chips)',
 P_PATH='@timecard_lib.timecard(sch_1):page24_i188@passive.resistor(chips)',
 PATH='I188',
 DRAWING='@TIMECARD_LIB.TIMECARD(SCH_1):PAGE524',
 PACKAGE='0402',
 PHYS_PAGE='24',
 XY='(-5300,8650)',
 ROT='0',
 VER='1',
 CDS_LIB='passive',
 CDS_PART_NAME='RESISTOR-G155-11000-01,100OHM,A',
 TOLERANCE='1%',
 CLS_PN='G155-11000-01',
 VALUE='100OHM',
 PRIM_FILE='./archive_libs/passive/resistor/chips/chips.prt';

PART_NAME
 R133 'RESISTOR-G155-133R0-01,33OHM,1%':
 SIGNAL_MODEL='DEFAULT_RESISTOR_33OHM_2_1';

SECTION_NUMBER 1
 '@TIMECARD_LIB.TIMECARD(SCH_1):PAGE127_I446@PASSIVE.RESISTOR(CHIPS)':
 C_PATH='@timecard_lib.timecard(sch_1):page127_i446@passive.resistor(chips)',
 P_PATH='@timecard_lib.timecard(sch_1):page10_i446@passive.resistor(chips)',
 PATH='I446',
 DRAWING='@TIMECARD_LIB.TIMECARD(SCH_1):PAGE127',
 PHYS_PAGE='10',
 XY='(-14300,350)',
 ROT='0',
 VER='1',
 CDS_LIB='passive',
 CDS_PART_NAME='RESISTOR-G155-133R0-01,33OHM,1%',
 TOLERANCE='1%',
 CLS_PN='G155-133R0-01',
 SIGNAL_MODEL='DEFAULT_RESISTOR_33OHM_2_1',
 VALUE='33OHM',
 PRIM_FILE='./archive_libs/passive/resistor/chips/chips.prt';

PART_NAME
 R134 'RESISTOR-G155-133R0-01,33OHM,1%':
 SIGNAL_MODEL='DEFAULT_RESISTOR_33OHM_2_1';

SECTION_NUMBER 1
 '@TIMECARD_LIB.TIMECARD(SCH_1):PAGE127_I436@PASSIVE.RESISTOR(CHIPS)':
 C_PATH='@timecard_lib.timecard(sch_1):page127_i436@passive.resistor(chips)',
 P_PATH='@timecard_lib.timecard(sch_1):page10_i436@passive.resistor(chips)',
 PATH='I436',
 DRAWING='@TIMECARD_LIB.TIMECARD(SCH_1):PAGE127',
 PACKAGE='0402',
 PHYS_PAGE='10',
 XY='(-11800,1600)',
 ROT='0',
 VER='1',
 CDS_LIB='passive',
 CDS_PART_NAME='RESISTOR-G155-133R0-01,33OHM,1%',
 TOLERANCE='1%',
 CLS_PN='G155-133R0-01',
 SIGNAL_MODEL='DEFAULT_RESISTOR_33OHM_2_1',
 VALUE='33OHM',
 PRIM_FILE='./archive_libs/passive/resistor/chips/chips.prt';

PART_NAME
 R135 'RESISTOR-G155-100R0-J0,0OHM,-':;

SECTION_NUMBER 1
 '@TIMECARD_LIB.TIMECARD(SCH_1):PAGE127_I438@PASSIVE.RESISTOR(CHIPS)':
 C_PATH='@timecard_lib.timecard(sch_1):page127_i438@passive.resistor(chips)',
 P_PATH='@timecard_lib.timecard(sch_1):page10_i438@passive.resistor(chips)',
 PATH='I438',
 DRAWING='@TIMECARD_LIB.TIMECARD(SCH_1):PAGE127',
 PACKAGE='0402',
 PHYS_PAGE='10',
 XY='(-11800,1400)',
 ROT='0',
 VER='1',
 CDS_LIB='passive',
 CDS_PART_NAME='RESISTOR-G155-100R0-J0,0OHM,-',
 TOLERANCE='-',
 CLS_PN='G155-100R0-J0',
 VALUE='0OHM',
 PRIM_FILE='./archive_libs/passive/resistor/chips/chips.prt';

PART_NAME
 R136 'RESISTOR-G155-133R0-01,33OHM,1%':;

SECTION_NUMBER 1
 '@TIMECARD_LIB.TIMECARD(SCH_1):PAGE127_I437@PASSIVE.RESISTOR(CHIPS)':
 C_PATH='@timecard_lib.timecard(sch_1):page127_i437@passive.resistor(chips)',
 P_PATH='@timecard_lib.timecard(sch_1):page10_i437@passive.resistor(chips)',
 PATH='I437',
 DRAWING='@TIMECARD_LIB.TIMECARD(SCH_1):PAGE127',
 PACKAGE='0402',
 PHYS_PAGE='10',
 XY='(-11800,1200)',
 ROT='0',
 VER='1',
 CDS_LIB='passive',
 CDS_PART_NAME='RESISTOR-G155-133R0-01,33OHM,1%',
 TOLERANCE='1%',
 CLS_PN='G155-133R0-01',
 VALUE='33OHM',
 PRIM_FILE='./archive_libs/passive/resistor/chips/chips.prt';

PART_NAME
 R137 'RESISTOR-G155-133R0-01,33OHM,1%':
 SIGNAL_MODEL='DEFAULT_RESISTOR_33OHM_2_1';

SECTION_NUMBER 1
 '@TIMECARD_LIB.TIMECARD(SCH_1):PAGE127_I439@PASSIVE.RESISTOR(CHIPS)':
 C_PATH='@timecard_lib.timecard(sch_1):page127_i439@passive.resistor(chips)',
 P_PATH='@timecard_lib.timecard(sch_1):page10_i439@passive.resistor(chips)',
 PATH='I439',
 DRAWING='@TIMECARD_LIB.TIMECARD(SCH_1):PAGE127',
 PACKAGE='0402',
 PHYS_PAGE='10',
 XY='(-11800,1050)',
 ROT='0',
 VER='1',
 CDS_LIB='passive',
 CDS_PART_NAME='RESISTOR-G155-133R0-01,33OHM,1%',
 TOLERANCE='1%',
 CLS_PN='G155-133R0-01',
 SIGNAL_MODEL='DEFAULT_RESISTOR_33OHM_2_1',
 VALUE='33OHM',
 PRIM_FILE='./archive_libs/passive/resistor/chips/chips.prt';

PART_NAME
 R138 'RESISTOR-G155-13300-01,330OHM,A':;

SECTION_NUMBER 1
 '@TIMECARD_LIB.TIMECARD(SCH_1):PAGE14_I63@PASSIVE.RESISTOR(CHIPS)':
 C_PATH='@timecard_lib.timecard(sch_1):page14_i63@passive.resistor(chips)',
 P_PATH='@timecard_lib.timecard(sch_1):page26_i63@passive.resistor(chips)',
 PATH='I63',
 DRAWING='@TIMECARD_LIB.TIMECARD(SCH_1):PAGE14',
 PACKAGE='0402',
 PHYS_PAGE='26',
 XY='(-9250,9200)',
 ROT='0',
 VER='1',
 CDS_LIB='passive',
 CDS_PART_NAME='RESISTOR-G155-13300-01,330OHM,A',
 TOLERANCE='1%',
 CLS_PN='G155-13300-01',
 VALUE='330OHM',
 PRIM_FILE='./archive_libs/passive/resistor/chips/chips.prt';

PART_NAME
 R139 'RESISTOR-G155-133R0-01,33OHM,1%':;

SECTION_NUMBER 1
 '@TIMECARD_LIB.TIMECARD(SCH_1):PAGE14_I60@PASSIVE.RESISTOR(CHIPS)':
 C_PATH='@timecard_lib.timecard(sch_1):page14_i60@passive.resistor(chips)',
 P_PATH='@timecard_lib.timecard(sch_1):page26_i60@passive.resistor(chips)',
 PATH='I60',
 DRAWING='@TIMECARD_LIB.TIMECARD(SCH_1):PAGE14',
 PACKAGE='0402',
 PHYS_PAGE='26',
 XY='(-8650,8850)',
 ROT='0',
 VER='1',
 CDS_LIB='passive',
 CDS_PART_NAME='RESISTOR-G155-133R0-01,33OHM,1%',
 TOLERANCE='1%',
 CLS_PN='G155-133R0-01',
 VALUE='33OHM',
 PRIM_FILE='./archive_libs/passive/resistor/chips/chips.prt';

PART_NAME
 R140 'RESISTOR-G155-100R0-J0,0OHM,-':;

SECTION_NUMBER 1
 '@TIMECARD_LIB.TIMECARD(SCH_1):PAGE68_I18@PASSIVE.RESISTOR(CHIPS)':
 C_PATH='@timecard_lib.timecard(sch_1):page68_i18@passive.resistor(chips)',
 P_PATH='@timecard_lib.timecard(sch_1):page30_i18@passive.resistor(chips)',
 PATH='I18',
 DRAWING='@TIMECARD_LIB.TIMECARD(SCH_1):PAGE68',
 PACKAGE='0402',
 PHYS_PAGE='30',
 XY='(-12450,7750)',
 ROT='0',
 VER='1',
 CDS_LIB='passive',
 CDS_PART_NAME='RESISTOR-G155-100R0-J0,0OHM,-',
 TOLERANCE='-',
 CLS_PN='G155-100R0-J0',
 VALUE='0OHM',
 PRIM_FILE='./archive_libs/passive/resistor/chips/chips.prt';

PART_NAME
 R141 'RESISTOR-G155-100R0-J0,0OHM,-':;

SECTION_NUMBER 1
 '@TIMECARD_LIB.TIMECARD(SCH_1):PAGE68_I42@PASSIVE.RESISTOR(CHIPS)':
 C_PATH='@timecard_lib.timecard(sch_1):page68_i42@passive.resistor(chips)',
 P_PATH='@timecard_lib.timecard(sch_1):page30_i42@passive.resistor(chips)',
 PATH='I42',
 DRAWING='@TIMECARD_LIB.TIMECARD(SCH_1):PAGE68',
 PACKAGE='0402',
 PHYS_PAGE='30',
 XY='(-12200,2850)',
 ROT='0',
 VER='1',
 CDS_LIB='passive',
 CDS_PART_NAME='RESISTOR-G155-100R0-J0,0OHM,-',
 TOLERANCE='-',
 CLS_PN='G155-100R0-J0',
 VALUE='0OHM',
 PRIM_FILE='./archive_libs/passive/resistor/chips/chips.prt';

PART_NAME
 R142 'RESISTOR-G155-11000-01,100OHM,A':;

SECTION_NUMBER 1
 '@TIMECARD_LIB.TIMECARD(SCH_1):PAGE516_I44@PASSIVE.RESISTOR(CHIPS)':
 C_PATH='@timecard_lib.timecard(sch_1):page516_i44@passive.resistor(chips)',
 P_PATH='@timecard_lib.timecard(sch_1):page32_i44@passive.resistor(chips)',
 PATH='I44',
 DRAWING='@TIMECARD_LIB.TIMECARD(SCH_1):PAGE516',
 PACKAGE='0402',
 PHYS_PAGE='32',
 XY='(-13400,7000)',
 ROT='0',
 VER='1',
 CDS_LIB='passive',
 CDS_PART_NAME='RESISTOR-G155-11000-01,100OHM,A',
 TOLERANCE='1%',
 CLS_PN='G155-11000-01',
 VALUE='100OHM',
 PRIM_FILE='./archive_libs/passive/resistor/chips/chips.prt';

PART_NAME
 R143 'RESISTOR-G155-133R0-01,33OHM,1%':
 SIGNAL_MODEL='DEFAULT_RESISTOR_33OHM_2_1';

SECTION_NUMBER 1
 '@TIMECARD_LIB.TIMECARD(SCH_1):PAGE515_I167@PASSIVE.RESISTOR(CHIPS)':
 C_PATH='@timecard_lib.timecard(sch_1):page515_i167@passive.resistor(chips)',
 P_PATH='@timecard_lib.timecard(sch_1):page31_i167@passive.resistor(chips)',
 PATH='I167',
 DRAWING='@TIMECARD_LIB.TIMECARD(SCH_1):PAGE515',
 PACKAGE='0402',
 PHYS_PAGE='31',
 XY='(-6650,6400)',
 ROT='0',
 VER='1',
 CDS_LIB='passive',
 CDS_PART_NAME='RESISTOR-G155-133R0-01,33OHM,1%',
 TOLERANCE='1%',
 CLS_PN='G155-133R0-01',
 SIGNAL_MODEL='DEFAULT_RESISTOR_33OHM_2_1',
 VALUE='33OHM',
 PRIM_FILE='./archive_libs/passive/resistor/chips/chips.prt';

PART_NAME
 R144 'RESISTOR-G155-133R0-01,33OHM,1%':
 SIGNAL_MODEL='DEFAULT_RESISTOR_33OHM_2_1';

SECTION_NUMBER 1
 '@TIMECARD_LIB.TIMECARD(SCH_1):PAGE5_I68@PASSIVE.RESISTOR(CHIPS)':
 C_PATH='@timecard_lib.timecard(sch_1):page5_i68@passive.resistor(chips)',
 P_PATH='@timecard_lib.timecard(sch_1):page16_i68@passive.resistor(chips)',
 PATH='I68',
 DRAWING='@TIMECARD_LIB.TIMECARD(SCH_1):PAGE5',
 PACKAGE='0402',
 PHYS_PAGE='16',
 XY='(-9750,10500)',
 ROT='0',
 VER='1',
 CDS_LIB='passive',
 CDS_PART_NAME='RESISTOR-G155-133R0-01,33OHM,1%',
 TOLERANCE='1%',
 CLS_PN='G155-133R0-01',
 SIGNAL_MODEL='DEFAULT_RESISTOR_33OHM_2_1',
 VALUE='33OHM',
 PRIM_FILE='./archive_libs/passive/resistor/chips/chips.prt';

PART_NAME
 R145 'RESISTOR-G155-133R0-01,33OHM,1%':
 SIGNAL_MODEL='DEFAULT_RESISTOR_33OHM_2_1';

SECTION_NUMBER 1
 '@TIMECARD_LIB.TIMECARD(SCH_1):PAGE5_I67@PASSIVE.RESISTOR(CHIPS)':
 C_PATH='@timecard_lib.timecard(sch_1):page5_i67@passive.resistor(chips)',
 P_PATH='@timecard_lib.timecard(sch_1):page16_i67@passive.resistor(chips)',
 PATH='I67',
 DRAWING='@TIMECARD_LIB.TIMECARD(SCH_1):PAGE5',
 PACKAGE='0402',
 PHYS_PAGE='16',
 XY='(-9750,10400)',
 ROT='0',
 VER='1',
 CDS_LIB='passive',
 CDS_PART_NAME='RESISTOR-G155-133R0-01,33OHM,1%',
 TOLERANCE='1%',
 CLS_PN='G155-133R0-01',
 SIGNAL_MODEL='DEFAULT_RESISTOR_33OHM_2_1',
 VALUE='33OHM',
 PRIM_FILE='./archive_libs/passive/resistor/chips/chips.prt';

PART_NAME
 R146 'RESISTOR-G155-11002-01,10KOHM,A':;

SECTION_NUMBER 1
 '@TIMECARD_LIB.TIMECARD(SCH_1):PAGE5_I60@PASSIVE.RESISTOR(CHIPS)':
 C_PATH='@timecard_lib.timecard(sch_1):page5_i60@passive.resistor(chips)',
 P_PATH='@timecard_lib.timecard(sch_1):page16_i60@passive.resistor(chips)',
 PATH='I60',
 DRAWING='@TIMECARD_LIB.TIMECARD(SCH_1):PAGE5',
 PACKAGE='0402',
 PHYS_PAGE='16',
 XY='(-8100,11150)',
 ROT='1',
 VER='2',
 CDS_LIB='passive',
 CDS_PART_NAME='RESISTOR-G155-11002-01,10KOHM,A',
 TOLERANCE='1%',
 CLS_PN='G155-11002-01',
 VALUE='10KOHM',
 PRIM_FILE='./archive_libs/passive/resistor/chips/chips.prt';

PART_NAME
 R147 'RESISTOR-G155-11002-01,10KOHM,A':;

SECTION_NUMBER 1
 '@TIMECARD_LIB.TIMECARD(SCH_1):PAGE5_I80@PASSIVE.RESISTOR(CHIPS)':
 C_PATH='@timecard_lib.timecard(sch_1):page5_i80@passive.resistor(chips)',
 P_PATH='@timecard_lib.timecard(sch_1):page16_i80@passive.resistor(chips)',
 PATH='I80',
 DRAWING='@TIMECARD_LIB.TIMECARD(SCH_1):PAGE5',
 PACKAGE='0402',
 PHYS_PAGE='16',
 XY='(-8100,11050)',
 ROT='1',
 VER='2',
 LOCATION='R147',
 CDS_LIB='passive',
 CDS_PART_NAME='RESISTOR-G155-11002-01,10KOHM,A',
 TOLERANCE='1%',
 CLS_PN='G155-11002-01',
 VALUE='10KOHM',
 PRIM_FILE='./archive_libs/passive/resistor/chips/chips.prt';

PART_NAME
 R148 'RESISTOR-G155-11002-01,10KOHM,A':;

SECTION_NUMBER 1
 '@TIMECARD_LIB.TIMECARD(SCH_1):PAGE5_I81@PASSIVE.RESISTOR(CHIPS)':
 C_PATH='@timecard_lib.timecard(sch_1):page5_i81@passive.resistor(chips)',
 P_PATH='@timecard_lib.timecard(sch_1):page16_i81@passive.resistor(chips)',
 PATH='I81',
 DRAWING='@TIMECARD_LIB.TIMECARD(SCH_1):PAGE5',
 PACKAGE='0402',
 PHYS_PAGE='16',
 XY='(-8100,10950)',
 ROT='1',
 VER='2',
 LOCATION='R148',
 CDS_LIB='passive',
 CDS_PART_NAME='RESISTOR-G155-11002-01,10KOHM,A',
 TOLERANCE='1%',
 CLS_PN='G155-11002-01',
 VALUE='10KOHM',
 PRIM_FILE='./archive_libs/passive/resistor/chips/chips.prt';

PART_NAME
 R149 'RESISTOR-G155-14701-01,4.7KOHMA':;

SECTION_NUMBER 1
 '@TIMECARD_LIB.TIMECARD(SCH_1):PAGE5_I82@PASSIVE.RESISTOR(CHIPS)':
 C_PATH='@timecard_lib.timecard(sch_1):page5_i82@passive.resistor(chips)',
 P_PATH='@timecard_lib.timecard(sch_1):page16_i82@passive.resistor(chips)',
 PATH='I82',
 DRAWING='@TIMECARD_LIB.TIMECARD(SCH_1):PAGE5',
 PACKAGE='0402',
 PHYS_PAGE='16',
 XY='(-8100,10100)',
 ROT='1',
 VER='2',
 LOCATION='R149',
 CDS_LIB='passive',
 CDS_PART_NAME='RESISTOR-G155-14701-01,4.7KOHMA',
 NO_ASSY='TRUE',
 TOLERANCE='1%',
 CLS_PN='G155-14701-01',
 VALUE='4.7KOHM',
 PRIM_FILE='./archive_libs/passive/resistor/chips/chips.prt';

PART_NAME
 R150 'RESISTOR-G155-14701-01,4.7KOHMA':;

SECTION_NUMBER 1
 '@TIMECARD_LIB.TIMECARD(SCH_1):PAGE5_I83@PASSIVE.RESISTOR(CHIPS)':
 C_PATH='@timecard_lib.timecard(sch_1):page5_i83@passive.resistor(chips)',
 P_PATH='@timecard_lib.timecard(sch_1):page16_i83@passive.resistor(chips)',
 PATH='I83',
 DRAWING='@TIMECARD_LIB.TIMECARD(SCH_1):PAGE5',
 PACKAGE='0402',
 PHYS_PAGE='16',
 XY='(-8100,10000)',
 ROT='1',
 VER='2',
 LOCATION='R150',
 CDS_LIB='passive',
 CDS_PART_NAME='RESISTOR-G155-14701-01,4.7KOHMA',
 NO_ASSY='TRUE',
 TOLERANCE='1%',
 CLS_PN='G155-14701-01',
 VALUE='4.7KOHM',
 PRIM_FILE='./archive_libs/passive/resistor/chips/chips.prt';

PART_NAME
 R151 'RESISTOR-G155-14701-01,4.7KOHMA':;

SECTION_NUMBER 1
 '@TIMECARD_LIB.TIMECARD(SCH_1):PAGE5_I84@PASSIVE.RESISTOR(CHIPS)':
 C_PATH='@timecard_lib.timecard(sch_1):page5_i84@passive.resistor(chips)',
 P_PATH='@timecard_lib.timecard(sch_1):page16_i84@passive.resistor(chips)',
 PATH='I84',
 DRAWING='@TIMECARD_LIB.TIMECARD(SCH_1):PAGE5',
 PACKAGE='0402',
 PHYS_PAGE='16',
 XY='(-8100,9900)',
 ROT='1',
 VER='2',
 LOCATION='R151',
 CDS_LIB='passive',
 CDS_PART_NAME='RESISTOR-G155-14701-01,4.7KOHMA',
 NO_ASSY='TRUE',
 TOLERANCE='1%',
 CLS_PN='G155-14701-01',
 VALUE='4.7KOHM',
 PRIM_FILE='./archive_libs/passive/resistor/chips/chips.prt';

PART_NAME
 R152 'RESISTOR-G155-14701-01,4.7KOHMA':;

SECTION_NUMBER 1
 '@TIMECARD_LIB.TIMECARD(SCH_1):PAGE5_I85@PASSIVE.RESISTOR(CHIPS)':
 C_PATH='@timecard_lib.timecard(sch_1):page5_i85@passive.resistor(chips)',
 P_PATH='@timecard_lib.timecard(sch_1):page16_i85@passive.resistor(chips)',
 PATH='I85',
 DRAWING='@TIMECARD_LIB.TIMECARD(SCH_1):PAGE5',
 PACKAGE='0402',
 PHYS_PAGE='16',
 XY='(-8100,9700)',
 ROT='1',
 VER='2',
 LOCATION='R152',
 CDS_LIB='passive',
 CDS_PART_NAME='RESISTOR-G155-14701-01,4.7KOHMA',
 TOLERANCE='1%',
 CLS_PN='G155-14701-01',
 VALUE='4.7KOHM',
 PRIM_FILE='./archive_libs/passive/resistor/chips/chips.prt';

PART_NAME
 R153 'RESISTOR-G155-14701-01,4.7KOHMA':;

SECTION_NUMBER 1
 '@TIMECARD_LIB.TIMECARD(SCH_1):PAGE5_I86@PASSIVE.RESISTOR(CHIPS)':
 C_PATH='@timecard_lib.timecard(sch_1):page5_i86@passive.resistor(chips)',
 P_PATH='@timecard_lib.timecard(sch_1):page16_i86@passive.resistor(chips)',
 PATH='I86',
 DRAWING='@TIMECARD_LIB.TIMECARD(SCH_1):PAGE5',
 PACKAGE='0402',
 PHYS_PAGE='16',
 XY='(-8100,9600)',
 ROT='1',
 VER='2',
 LOCATION='R153',
 CDS_LIB='passive',
 CDS_PART_NAME='RESISTOR-G155-14701-01,4.7KOHMA',
 TOLERANCE='1%',
 CLS_PN='G155-14701-01',
 VALUE='4.7KOHM',
 PRIM_FILE='./archive_libs/passive/resistor/chips/chips.prt';

PART_NAME
 R154 'RESISTOR-G155-14701-01,4.7KOHMA':;

SECTION_NUMBER 1
 '@TIMECARD_LIB.TIMECARD(SCH_1):PAGE5_I87@PASSIVE.RESISTOR(CHIPS)':
 C_PATH='@timecard_lib.timecard(sch_1):page5_i87@passive.resistor(chips)',
 P_PATH='@timecard_lib.timecard(sch_1):page16_i87@passive.resistor(chips)',
 PATH='I87',
 DRAWING='@TIMECARD_LIB.TIMECARD(SCH_1):PAGE5',
 PACKAGE='0402',
 PHYS_PAGE='16',
 XY='(-8100,9500)',
 ROT='1',
 VER='2',
 LOCATION='R154',
 CDS_LIB='passive',
 CDS_PART_NAME='RESISTOR-G155-14701-01,4.7KOHMA',
 TOLERANCE='1%',
 CLS_PN='G155-14701-01',
 VALUE='4.7KOHM',
 PRIM_FILE='./archive_libs/passive/resistor/chips/chips.prt';

PART_NAME
 R155 'RESISTOR-G155-14701-01,4.7KOHMA':;

SECTION_NUMBER 1
 '@TIMECARD_LIB.TIMECARD(SCH_1):PAGE5_I66@PASSIVE.RESISTOR(CHIPS)':
 C_PATH='@timecard_lib.timecard(sch_1):page5_i66@passive.resistor(chips)',
 P_PATH='@timecard_lib.timecard(sch_1):page16_i66@passive.resistor(chips)',
 PATH='I66',
 DRAWING='@TIMECARD_LIB.TIMECARD(SCH_1):PAGE5',
 PACKAGE='0402',
 PHYS_PAGE='16',
 XY='(-8100,9350)',
 ROT='1',
 VER='2',
 CDS_LIB='passive',
 CDS_PART_NAME='RESISTOR-G155-14701-01,4.7KOHMA',
 NO_ASSY='TRUE',
 TOLERANCE='1%',
 CLS_PN='G155-14701-01',
 VALUE='4.7KOHM',
 PRIM_FILE='./archive_libs/passive/resistor/chips/chips.prt';

PART_NAME
 R156 'RESISTOR-G155-11000-01,100OHM,A':;

SECTION_NUMBER 1
 '@TIMECARD_LIB.TIMECARD(SCH_1):PAGE12_I63@PASSIVE.RESISTOR(CHIPS)':
 C_PATH='@timecard_lib.timecard(sch_1):page12_i63@passive.resistor(chips)',
 P_PATH='@timecard_lib.timecard(sch_1):page23_i63@passive.resistor(chips)',
 PATH='I63',
 DRAWING='@TIMECARD_LIB.TIMECARD(SCH_1):PAGE12',
 PACKAGE='0402',
 PHYS_PAGE='23',
 XY='(-10750,9050)',
 ROT='3',
 VER='2',
 CDS_LIB='passive',
 CDS_PART_NAME='RESISTOR-G155-11000-01,100OHM,A',
 TOLERANCE='1%',
 CLS_PN='G155-11000-01',
 VALUE='100OHM',
 PRIM_FILE='./archive_libs/passive/resistor/chips/chips.prt';

PART_NAME
 R157 'RESISTOR-G155-11000-01,100OHM,A':;

SECTION_NUMBER 1
 '@TIMECARD_LIB.TIMECARD(SCH_1):PAGE12_I237@PASSIVE.RESISTOR(CHIPS)':
 C_PATH='@timecard_lib.timecard(sch_1):page12_i237@passive.resistor(chips)',
 P_PATH='@timecard_lib.timecard(sch_1):page23_i237@passive.resistor(chips)',
 PATH='I237',
 DRAWING='@TIMECARD_LIB.TIMECARD(SCH_1):PAGE12',
 PACKAGE='0402',
 PHYS_PAGE='23',
 XY='(-10700,6900)',
 ROT='3',
 VER='2',
 LOCATION='R157',
 CDS_LIB='passive',
 CDS_PART_NAME='RESISTOR-G155-11000-01,100OHM,A',
 TOLERANCE='1%',
 CLS_PN='G155-11000-01',
 VALUE='100OHM',
 PRIM_FILE='./archive_libs/passive/resistor/chips/chips.prt';

PART_NAME
 R158 'RESISTOR-G155-14701-01,4.7KOHMA':;

SECTION_NUMBER 1
 '@TIMECARD_LIB.TIMECARD(SCH_1):PAGE5_I153@PASSIVE.RESISTOR(CHIPS)':
 C_PATH='@timecard_lib.timecard(sch_1):page5_i153@passive.resistor(chips)',
 P_PATH='@timecard_lib.timecard(sch_1):page16_i153@passive.resistor(chips)',
 PATH='I153',
 DRAWING='@TIMECARD_LIB.TIMECARD(SCH_1):PAGE5',
 PACKAGE='0402',
 PHYS_PAGE='16',
 XY='(-5100,4800)',
 ROT='0',
 VER='2',
 CDS_LIB='passive',
 CDS_PART_NAME='RESISTOR-G155-14701-01,4.7KOHMA',
 TOLERANCE='1%',
 CLS_PN='G155-14701-01',
 VALUE='4.7KOHM',
 PRIM_FILE='./archive_libs/passive/resistor/chips/chips.prt';

PART_NAME
 R159 'RESISTOR-G155-14701-01,4.7KOHMA':;

SECTION_NUMBER 1
 '@TIMECARD_LIB.TIMECARD(SCH_1):PAGE5_I156@PASSIVE.RESISTOR(CHIPS)':
 C_PATH='@timecard_lib.timecard(sch_1):page5_i156@passive.resistor(chips)',
 P_PATH='@timecard_lib.timecard(sch_1):page16_i156@passive.resistor(chips)',
 PATH='I156',
 DRAWING='@TIMECARD_LIB.TIMECARD(SCH_1):PAGE5',
 PACKAGE='0402',
 PHYS_PAGE='16',
 XY='(-5100,4200)',
 ROT='0',
 VER='2',
 CDS_LIB='passive',
 CDS_PART_NAME='RESISTOR-G155-14701-01,4.7KOHMA',
 NO_ASSY='TRUE',
 TOLERANCE='1%',
 CLS_PN='G155-14701-01',
 VALUE='4.7KOHM',
 PRIM_FILE='./archive_libs/passive/resistor/chips/chips.prt';

PART_NAME
 R160 'RESISTOR-G155-14701-01,4.7KOHMA':;

SECTION_NUMBER 1
 '@TIMECARD_LIB.TIMECARD(SCH_1):PAGE5_I160@PASSIVE.RESISTOR(CHIPS)':
 C_PATH='@timecard_lib.timecard(sch_1):page5_i160@passive.resistor(chips)',
 P_PATH='@timecard_lib.timecard(sch_1):page16_i160@passive.resistor(chips)',
 PATH='I160',
 DRAWING='@TIMECARD_LIB.TIMECARD(SCH_1):PAGE5',
 PACKAGE='0402',
 PHYS_PAGE='16',
 XY='(-4650,4800)',
 ROT='0',
 VER='2',
 CDS_LIB='passive',
 CDS_PART_NAME='RESISTOR-G155-14701-01,4.7KOHMA',
 NO_ASSY='TRUE',
 TOLERANCE='1%',
 CLS_PN='G155-14701-01',
 VALUE='4.7KOHM',
 PRIM_FILE='./archive_libs/passive/resistor/chips/chips.prt';

PART_NAME
 R161 'RESISTOR-G155-14701-01,4.7KOHMA':;

SECTION_NUMBER 1
 '@TIMECARD_LIB.TIMECARD(SCH_1):PAGE5_I165@PASSIVE.RESISTOR(CHIPS)':
 C_PATH='@timecard_lib.timecard(sch_1):page5_i165@passive.resistor(chips)',
 P_PATH='@timecard_lib.timecard(sch_1):page16_i165@passive.resistor(chips)',
 PATH='I165',
 DRAWING='@TIMECARD_LIB.TIMECARD(SCH_1):PAGE5',
 PACKAGE='0402',
 PHYS_PAGE='16',
 XY='(-4650,4200)',
 ROT='0',
 VER='2',
 CDS_LIB='passive',
 CDS_PART_NAME='RESISTOR-G155-14701-01,4.7KOHMA',
 TOLERANCE='1%',
 CLS_PN='G155-14701-01',
 VALUE='4.7KOHM',
 PRIM_FILE='./archive_libs/passive/resistor/chips/chips.prt';

PART_NAME
 R162 'RESISTOR-G155-14701-01,4.7KOHMA':;

SECTION_NUMBER 1
 '@TIMECARD_LIB.TIMECARD(SCH_1):PAGE5_I161@PASSIVE.RESISTOR(CHIPS)':
 C_PATH='@timecard_lib.timecard(sch_1):page5_i161@passive.resistor(chips)',
 P_PATH='@timecard_lib.timecard(sch_1):page16_i161@passive.resistor(chips)',
 PATH='I161',
 DRAWING='@TIMECARD_LIB.TIMECARD(SCH_1):PAGE5',
 PACKAGE='0402',
 PHYS_PAGE='16',
 XY='(-4200,4800)',
 ROT='0',
 VER='2',
 CDS_LIB='passive',
 CDS_PART_NAME='RESISTOR-G155-14701-01,4.7KOHMA',
 NO_ASSY='TRUE',
 TOLERANCE='1%',
 CLS_PN='G155-14701-01',
 VALUE='4.7KOHM',
 PRIM_FILE='./archive_libs/passive/resistor/chips/chips.prt';

PART_NAME
 R163 'RESISTOR-G155-14701-01,4.7KOHMA':;

SECTION_NUMBER 1
 '@TIMECARD_LIB.TIMECARD(SCH_1):PAGE5_I166@PASSIVE.RESISTOR(CHIPS)':
 C_PATH='@timecard_lib.timecard(sch_1):page5_i166@passive.resistor(chips)',
 P_PATH='@timecard_lib.timecard(sch_1):page16_i166@passive.resistor(chips)',
 PATH='I166',
 DRAWING='@TIMECARD_LIB.TIMECARD(SCH_1):PAGE5',
 PACKAGE='0402',
 PHYS_PAGE='16',
 XY='(-4200,4200)',
 ROT='0',
 VER='2',
 CDS_LIB='passive',
 CDS_PART_NAME='RESISTOR-G155-14701-01,4.7KOHMA',
 TOLERANCE='1%',
 CLS_PN='G155-14701-01',
 VALUE='4.7KOHM',
 PRIM_FILE='./archive_libs/passive/resistor/chips/chips.prt';

PART_NAME
 R164 'RESISTOR-G155-11003-01,100KOHMA':;

SECTION_NUMBER 1
 '@TIMECARD_LIB.TIMECARD(SCH_1):PAGE3_I151@PASSIVE.RESISTOR(CHIPS)':
 C_PATH='@timecard_lib.timecard(sch_1):page3_i151@passive.resistor(chips)',
 P_PATH='@timecard_lib.timecard(sch_1):page9_i151@passive.resistor(chips)',
 PATH='I151',
 DRAWING='@TIMECARD_LIB.TIMECARD(SCH_1):PAGE3',
 PACKAGE='0402',
 PHYS_PAGE='9',
 XY='(450,4000)',
 ROT='0',
 VER='2',
 CDS_LIB='passive',
 CDS_PART_NAME='RESISTOR-G155-11003-01,100KOHMA',
 NO_ASSY='TRUE',
 TOLERANCE='1%',
 CLS_PN='G155-11003-01',
 VALUE='100KOHM',
 PRIM_FILE='./archive_libs/passive/resistor/chips/chips.prt';

PART_NAME
 R165 'RESISTOR-G155-11002-01,10KOHM,A':;

SECTION_NUMBER 1
 '@TIMECARD_LIB.TIMECARD(SCH_1):PAGE68_I2@PASSIVE.RESISTOR(CHIPS)':
 C_PATH='@timecard_lib.timecard(sch_1):page68_i2@passive.resistor(chips)',
 P_PATH='@timecard_lib.timecard(sch_1):page30_i2@passive.resistor(chips)',
 PATH='I2',
 DRAWING='@TIMECARD_LIB.TIMECARD(SCH_1):PAGE68',
 PACKAGE='0402',
 PHYS_PAGE='30',
 XY='(-11850,7550)',
 ROT='0',
 VER='2',
 CDS_LIB='passive',
 CDS_PART_NAME='RESISTOR-G155-11002-01,10KOHM,A',
 NO_ASSY='TRUE',
 TOLERANCE='1%',
 CLS_PN='G155-11002-01',
 VALUE='10KOHM',
 PRIM_FILE='./archive_libs/passive/resistor/chips/chips.prt';

PART_NAME
 R166 'RESISTOR-G152-00055-01,1.13KOHA':;

SECTION_NUMBER 1
 '@TIMECARD_LIB.TIMECARD(SCH_1):PAGE68_I45@PASSIVE.RESISTOR(CHIPS)':
 C_PATH='@timecard_lib.timecard(sch_1):page68_i45@passive.resistor(chips)',
 P_PATH='@timecard_lib.timecard(sch_1):page30_i45@passive.resistor(chips)',
 PATH='I45',
 DRAWING='@TIMECARD_LIB.TIMECARD(SCH_1):PAGE68',
 PACKAGE='402',
 PHYS_PAGE='30',
 XY='(-11850,3400)',
 ROT='0',
 VER='2',
 CDS_LIB='passive',
 CDS_PART_NAME='RESISTOR-G152-00055-01,1.13KOHA',
 NO_ASSY='TRUE',
 TOLERANCE='1%',
 CLS_PN='G152-00055-01',
 VALUE='1.13KOHM',
 PRIM_FILE='./archive_libs/passive/resistor/chips/chips.prt';

PART_NAME
 R167 'RESISTOR-G155-11002-01,10KOHM,A':;

SECTION_NUMBER 1
 '@TIMECARD_LIB.TIMECARD(SCH_1):PAGE3_I148@PASSIVE.RESISTOR(CHIPS)':
 C_PATH='@timecard_lib.timecard(sch_1):page3_i148@passive.resistor(chips)',
 P_PATH='@timecard_lib.timecard(sch_1):page9_i148@passive.resistor(chips)',
 PATH='I148',
 DRAWING='@TIMECARD_LIB.TIMECARD(SCH_1):PAGE3',
 PACKAGE='0402',
 PHYS_PAGE='9',
 XY='(850,4000)',
 ROT='0',
 VER='2',
 CDS_LIB='passive',
 CDS_PART_NAME='RESISTOR-G155-11002-01,10KOHM,A',
 TOLERANCE='1%',
 CLS_PN='G155-11002-01',
 VALUE='10KOHM',
 PRIM_FILE='./archive_libs/passive/resistor/chips/chips.prt';

PART_NAME
 R168 'RESISTOR-G155-11004-01,1MOHM,1%':;

SECTION_NUMBER 1
 '@TIMECARD_LIB.TIMECARD(SCH_1):PAGE9_I70@PASSIVE.RESISTOR(CHIPS)':
 C_PATH='@timecard_lib.timecard(sch_1):page9_i70@passive.resistor(chips)',
 P_PATH='@timecard_lib.timecard(sch_1):page20_i70@passive.resistor(chips)',
 PATH='I70',
 DRAWING='@TIMECARD_LIB.TIMECARD(SCH_1):PAGE9',
 PACKAGE='0402',
 PHYS_PAGE='20',
 XY='(-5150,10200)',
 ROT='0',
 VER='2',
 CDS_LIB='passive',
 CDS_PART_NAME='RESISTOR-G155-11004-01,1MOHM,1%',
 NO_ASSY='TRUE',
 TOLERANCE='1%',
 CLS_PN='G155-11004-01',
 VALUE='1MOHM',
 PRIM_FILE='./archive_libs/passive/resistor/chips/chips.prt';

PART_NAME
 R169 'RESISTOR-G155-13300-01,330OHM,A':;

SECTION_NUMBER 1
 '@TIMECARD_LIB.TIMECARD(SCH_1):PAGE14_I288@PASSIVE.RESISTOR(CHIPS)':
 C_PATH='@timecard_lib.timecard(sch_1):page14_i288@passive.resistor(chips)',
 P_PATH='@timecard_lib.timecard(sch_1):page26_i288@passive.resistor(chips)',
 PATH='I288',
 DRAWING='@TIMECARD_LIB.TIMECARD(SCH_1):PAGE14',
 PACKAGE='0402',
 PHYS_PAGE='26',
 XY='(-9250,7050)',
 ROT='0',
 VER='1',
 CDS_LIB='passive',
 CDS_PART_NAME='RESISTOR-G155-13300-01,330OHM,A',
 TOLERANCE='1%',
 CLS_PN='G155-13300-01',
 VALUE='330OHM',
 PRIM_FILE='./archive_libs/passive/resistor/chips/chips.prt';

PART_NAME
 R170 'RESISTOR-G155-11002-01,10KOHM,A':;

SECTION_NUMBER 1
 '@TIMECARD_LIB.TIMECARD(SCH_1):PAGE16_I1608@PASSIVE.RESISTOR(CHIPS)':
 C_PATH='@timecard_lib.timecard(sch_1):page16_i1608@passive.resistor(chips)',
 P_PATH='@timecard_lib.timecard(sch_1):page25_i1608@passive.resistor(chips)',
 PATH='I1608',
 DRAWING='@TIMECARD_LIB.TIMECARD(SCH_1):PAGE16',
 PACKAGE='0402',
 PHYS_PAGE='25',
 XY='(-12350,4100)',
 ROT='0',
 VER='1',
 CDS_LIB='passive',
 CDS_PART_NAME='RESISTOR-G155-11002-01,10KOHM,A',
 TOLERANCE='1%',
 CLS_PN='G155-11002-01',
 VALUE='10KOHM',
 PRIM_FILE='./archive_libs/passive/resistor/chips/chips.prt';

PART_NAME
 R171 'RESISTOR-G155-14701-01,4.7KOHMA':;

SECTION_NUMBER 1
 '@TIMECARD_LIB.TIMECARD(SCH_1):PAGE16_I1542@PASSIVE.RESISTOR(CHIPS)':
 C_PATH='@timecard_lib.timecard(sch_1):page16_i1542@passive.resistor(chips)',
 P_PATH='@timecard_lib.timecard(sch_1):page25_i1542@passive.resistor(chips)',
 PATH='I1542',
 DRAWING='@TIMECARD_LIB.TIMECARD(SCH_1):PAGE16',
 PACKAGE='0402',
 PHYS_PAGE='25',
 XY='(-12350,4000)',
 ROT='1',
 VER='2',
 CDS_LIB='passive',
 CDS_PART_NAME='RESISTOR-G155-14701-01,4.7KOHMA',
 NO_ASSY='TRUE',
 TOLERANCE='1%',
 CLS_PN='G155-14701-01',
 VALUE='4.7KOHM',
 PRIM_FILE='./archive_libs/passive/resistor/chips/chips.prt';

PART_NAME
 R172 'RESISTOR-G155-11002-01,10KOHM,A':;

SECTION_NUMBER 1
 '@TIMECARD_LIB.TIMECARD(SCH_1):PAGE16_I1607@PASSIVE.RESISTOR(CHIPS)':
 C_PATH='@timecard_lib.timecard(sch_1):page16_i1607@passive.resistor(chips)',
 P_PATH='@timecard_lib.timecard(sch_1):page25_i1607@passive.resistor(chips)',
 PATH='I1607',
 DRAWING='@TIMECARD_LIB.TIMECARD(SCH_1):PAGE16',
 PACKAGE='0402',
 PHYS_PAGE='25',
 XY='(-12350,3800)',
 ROT='0',
 VER='1',
 CDS_LIB='passive',
 CDS_PART_NAME='RESISTOR-G155-11002-01,10KOHM,A',
 TOLERANCE='1%',
 CLS_PN='G155-11002-01',
 VALUE='10KOHM',
 PRIM_FILE='./archive_libs/passive/resistor/chips/chips.prt';

PART_NAME
 R173 'RESISTOR-G155-14701-01,4.7KOHMA':;

SECTION_NUMBER 1
 '@TIMECARD_LIB.TIMECARD(SCH_1):PAGE16_I1544@PASSIVE.RESISTOR(CHIPS)':
 C_PATH='@timecard_lib.timecard(sch_1):page16_i1544@passive.resistor(chips)',
 P_PATH='@timecard_lib.timecard(sch_1):page25_i1544@passive.resistor(chips)',
 PATH='I1544',
 DRAWING='@TIMECARD_LIB.TIMECARD(SCH_1):PAGE16',
 PACKAGE='0402',
 PHYS_PAGE='25',
 XY='(-12350,3700)',
 ROT='1',
 VER='2',
 CDS_LIB='passive',
 CDS_PART_NAME='RESISTOR-G155-14701-01,4.7KOHMA',
 NO_ASSY='TRUE',
 TOLERANCE='1%',
 CLS_PN='G155-14701-01',
 VALUE='4.7KOHM',
 PRIM_FILE='./archive_libs/passive/resistor/chips/chips.prt';

PART_NAME
 R174 'RESISTOR-G155-11002-01,10KOHM,A':;

SECTION_NUMBER 1
 '@TIMECARD_LIB.TIMECARD(SCH_1):PAGE68_I44@PASSIVE.RESISTOR(CHIPS)':
 C_PATH='@timecard_lib.timecard(sch_1):page68_i44@passive.resistor(chips)',
 P_PATH='@timecard_lib.timecard(sch_1):page30_i44@passive.resistor(chips)',
 PATH='I44',
 DRAWING='@TIMECARD_LIB.TIMECARD(SCH_1):PAGE68',
 PACKAGE='0402',
 PHYS_PAGE='30',
 XY='(-11800,2550)',
 ROT='0',
 VER='2',
 CDS_LIB='passive',
 CDS_PART_NAME='RESISTOR-G155-11002-01,10KOHM,A',
 NO_ASSY='TRUE',
 TOLERANCE='1%',
 CLS_PN='G155-11002-01',
 VALUE='10KOHM',
 PRIM_FILE='./archive_libs/passive/resistor/chips/chips.prt';

PART_NAME
 R175 'RESISTOR-G155-133R0-01,33OHM,1%':;

SECTION_NUMBER 1
 '@TIMECARD_LIB.TIMECARD(SCH_1):PAGE5_I100@PASSIVE.RESISTOR(CHIPS)':
 C_PATH='@timecard_lib.timecard(sch_1):page5_i100@passive.resistor(chips)',
 P_PATH='@timecard_lib.timecard(sch_1):page16_i100@passive.resistor(chips)',
 PATH='I100',
 DRAWING='@TIMECARD_LIB.TIMECARD(SCH_1):PAGE5',
 PACKAGE='0402',
 PHYS_PAGE='16',
 XY='(-11000,6100)',
 ROT='0',
 VER='1',
 CDS_LIB='passive',
 CDS_PART_NAME='RESISTOR-G155-133R0-01,33OHM,1%',
 NO_ASSY='TRUE',
 TOLERANCE='1%',
 CLS_PN='G155-133R0-01',
 VALUE='33OHM',
 PRIM_FILE='./archive_libs/passive/resistor/chips/chips.prt';

PART_NAME
 R176 'RESISTOR-G155-133R0-01,33OHM,1%':;

SECTION_NUMBER 1
 '@TIMECARD_LIB.TIMECARD(SCH_1):PAGE5_I102@PASSIVE.RESISTOR(CHIPS)':
 C_PATH='@timecard_lib.timecard(sch_1):page5_i102@passive.resistor(chips)',
 P_PATH='@timecard_lib.timecard(sch_1):page16_i102@passive.resistor(chips)',
 PATH='I102',
 DRAWING='@TIMECARD_LIB.TIMECARD(SCH_1):PAGE5',
 PACKAGE='0402',
 PHYS_PAGE='16',
 XY='(-11000,6000)',
 ROT='0',
 VER='1',
 CDS_LIB='passive',
 CDS_PART_NAME='RESISTOR-G155-133R0-01,33OHM,1%',
 NO_ASSY='TRUE',
 TOLERANCE='1%',
 CLS_PN='G155-133R0-01',
 VALUE='33OHM',
 PRIM_FILE='./archive_libs/passive/resistor/chips/chips.prt';

PART_NAME
 R177 'RESISTOR-G152-00055-01,1.13KOHA':;

SECTION_NUMBER 1
 '@TIMECARD_LIB.TIMECARD(SCH_1):PAGE68_I26@PASSIVE.RESISTOR(CHIPS)':
 C_PATH='@timecard_lib.timecard(sch_1):page68_i26@passive.resistor(chips)',
 P_PATH='@timecard_lib.timecard(sch_1):page30_i26@passive.resistor(chips)',
 PATH='I26',
 DRAWING='@TIMECARD_LIB.TIMECARD(SCH_1):PAGE68',
 PACKAGE='0402',
 PHYS_PAGE='30',
 XY='(-11700,8300)',
 ROT='0',
 VER='2',
 CDS_LIB='passive',
 CDS_PART_NAME='RESISTOR-G152-00055-01,1.13KOHA',
 NO_ASSY='TRUE',
 TOLERANCE='1%',
 CLS_PN='G152-00055-01',
 VALUE='1.13KOHM',
 PRIM_FILE='./archive_libs/passive/resistor/chips/chips.prt';

PART_NAME
 R178 'RESISTOR-G155-14701-01,4.7KOHMA':;

SECTION_NUMBER 1
 '@TIMECARD_LIB.TIMECARD(SCH_1):PAGE68_I11@PASSIVE.RESISTOR(CHIPS)':
 C_PATH='@timecard_lib.timecard(sch_1):page68_i11@passive.resistor(chips)',
 P_PATH='@timecard_lib.timecard(sch_1):page30_i11@passive.resistor(chips)',
 PATH='I11',
 DRAWING='@TIMECARD_LIB.TIMECARD(SCH_1):PAGE68',
 PACKAGE='0402',
 PHYS_PAGE='30',
 XY='(-7600,7300)',
 ROT='0',
 VER='2',
 CDS_LIB='passive',
 CDS_PART_NAME='RESISTOR-G155-14701-01,4.7KOHMA',
 TOLERANCE='1%',
 CLS_PN='G155-14701-01',
 VALUE='4.7KOHM',
 PRIM_FILE='./archive_libs/passive/resistor/chips/chips.prt';

PART_NAME
 R179 'RESISTOR-G155-14701-01,4.7KOHMA':;

SECTION_NUMBER 1
 '@TIMECARD_LIB.TIMECARD(SCH_1):PAGE68_I73@PASSIVE.RESISTOR(CHIPS)':
 C_PATH='@timecard_lib.timecard(sch_1):page68_i73@passive.resistor(chips)',
 P_PATH='@timecard_lib.timecard(sch_1):page30_i73@passive.resistor(chips)',
 PATH='I73',
 DRAWING='@TIMECARD_LIB.TIMECARD(SCH_1):PAGE68',
 PACKAGE='0402',
 PHYS_PAGE='30',
 XY='(-7600,2400)',
 ROT='0',
 VER='2',
 CDS_LIB='passive',
 CDS_PART_NAME='RESISTOR-G155-14701-01,4.7KOHMA',
 TOLERANCE='1%',
 CLS_PN='G155-14701-01',
 VALUE='4.7KOHM',
 PRIM_FILE='./archive_libs/passive/resistor/chips/chips.prt';

PART_NAME
 R180 'RESISTOR-G155-11001-01,1KOHM,1%':;

SECTION_NUMBER 1
 '@TIMECARD_LIB.TIMECARD(SCH_1):PAGE14_I44@PASSIVE.RESISTOR(CHIPS)':
 C_PATH='@timecard_lib.timecard(sch_1):page14_i44@passive.resistor(chips)',
 P_PATH='@timecard_lib.timecard(sch_1):page26_i44@passive.resistor(chips)',
 PATH='I44',
 DRAWING='@TIMECARD_LIB.TIMECARD(SCH_1):PAGE14',
 PACKAGE='0402',
 PHYS_PAGE='26',
 XY='(-9150,8500)',
 ROT='0',
 VER='1',
 CDS_LIB='passive',
 CDS_PART_NAME='RESISTOR-G155-11001-01,1KOHM,1%',
 TOLERANCE='1%',
 CLS_PN='G155-11001-01',
 VALUE='1KOHM',
 PRIM_FILE='./archive_libs/passive/resistor/chips/chips.prt';

PART_NAME
 R181 'RESISTOR-G155-100R0-J0,0OHM,-':;

SECTION_NUMBER 1
 '@TIMECARD_LIB.TIMECARD(SCH_1):PAGE68_I10@PASSIVE.RESISTOR(CHIPS)':
 C_PATH='@timecard_lib.timecard(sch_1):page68_i10@passive.resistor(chips)',
 P_PATH='@timecard_lib.timecard(sch_1):page30_i10@passive.resistor(chips)',
 PATH='I10',
 DRAWING='@TIMECARD_LIB.TIMECARD(SCH_1):PAGE68',
 PACKAGE='0402',
 PHYS_PAGE='30',
 XY='(-6950,7000)',
 ROT='0',
 VER='1',
 CDS_LIB='passive',
 CDS_PART_NAME='RESISTOR-G155-100R0-J0,0OHM,-',
 TOLERANCE='-',
 CLS_PN='G155-100R0-J0',
 VALUE='0OHM',
 PRIM_FILE='./archive_libs/passive/resistor/chips/chips.prt';

PART_NAME
 R182 'RESISTOR-G155-100R0-J0,0OHM,-':;

SECTION_NUMBER 1
 '@TIMECARD_LIB.TIMECARD(SCH_1):PAGE68_I74@PASSIVE.RESISTOR(CHIPS)':
 C_PATH='@timecard_lib.timecard(sch_1):page68_i74@passive.resistor(chips)',
 P_PATH='@timecard_lib.timecard(sch_1):page30_i74@passive.resistor(chips)',
 PATH='I74',
 DRAWING='@TIMECARD_LIB.TIMECARD(SCH_1):PAGE68',
 PACKAGE='0402',
 PHYS_PAGE='30',
 XY='(-7000,2100)',
 ROT='0',
 VER='1',
 CDS_LIB='passive',
 CDS_PART_NAME='RESISTOR-G155-100R0-J0,0OHM,-',
 TOLERANCE='-',
 CLS_PN='G155-100R0-J0',
 VALUE='0OHM',
 PRIM_FILE='./archive_libs/passive/resistor/chips/chips.prt';

PART_NAME
 R183 'RESISTOR-G155-133R0-01,33OHM,1%':;

SECTION_NUMBER 1
 '@TIMECARD_LIB.TIMECARD(SCH_1):PAGE5_I101@PASSIVE.RESISTOR(CHIPS)':
 C_PATH='@timecard_lib.timecard(sch_1):page5_i101@passive.resistor(chips)',
 P_PATH='@timecard_lib.timecard(sch_1):page16_i101@passive.resistor(chips)',
 PATH='I101',
 DRAWING='@TIMECARD_LIB.TIMECARD(SCH_1):PAGE5',
 PACKAGE='0402',
 PHYS_PAGE='16',
 XY='(-11000,5850)',
 ROT='0',
 VER='1',
 CDS_LIB='passive',
 CDS_PART_NAME='RESISTOR-G155-133R0-01,33OHM,1%',
 NO_ASSY='TRUE',
 TOLERANCE='1%',
 CLS_PN='G155-133R0-01',
 VALUE='33OHM',
 PRIM_FILE='./archive_libs/passive/resistor/chips/chips.prt';

PART_NAME
 R184 'RESISTOR-G155-133R0-01,33OHM,1%':;

SECTION_NUMBER 1
 '@TIMECARD_LIB.TIMECARD(SCH_1):PAGE5_I103@PASSIVE.RESISTOR(CHIPS)':
 C_PATH='@timecard_lib.timecard(sch_1):page5_i103@passive.resistor(chips)',
 P_PATH='@timecard_lib.timecard(sch_1):page16_i103@passive.resistor(chips)',
 PATH='I103',
 DRAWING='@TIMECARD_LIB.TIMECARD(SCH_1):PAGE5',
 PACKAGE='0402',
 PHYS_PAGE='16',
 XY='(-11000,5750)',
 ROT='0',
 VER='1',
 CDS_LIB='passive',
 CDS_PART_NAME='RESISTOR-G155-133R0-01,33OHM,1%',
 NO_ASSY='TRUE',
 TOLERANCE='1%',
 CLS_PN='G155-133R0-01',
 VALUE='33OHM',
 PRIM_FILE='./archive_libs/passive/resistor/chips/chips.prt';

PART_NAME
 R185 'RESISTOR-G155-04221-01,4.22KOHA':;

SECTION_NUMBER 1
 '@TIMECARD_LIB.TIMECARD(SCH_1):PAGE68_I59@PASSIVE.RESISTOR(CHIPS)':
 C_PATH='@timecard_lib.timecard(sch_1):page68_i59@passive.resistor(chips)',
 P_PATH='@timecard_lib.timecard(sch_1):page30_i59@passive.resistor(chips)',
 PATH='I59',
 DRAWING='@TIMECARD_LIB.TIMECARD(SCH_1):PAGE68',
 PACKAGE='0402',
 PHYS_PAGE='30',
 XY='(-6400,8350)',
 ROT='0',
 VER='2',
 CDS_LIB='passive',
 CDS_PART_NAME='RESISTOR-G155-04221-01,4.22KOHA',
 TOLERANCE='1%',
 CLS_PN='G155-04221-01',
 VALUE='4.22KOHM',
 PRIM_FILE='./archive_libs/passive/resistor/chips/chips.prt';

PART_NAME
 R186 'RESISTOR-G155-03001-01,3KOHM,1%':;

SECTION_NUMBER 1
 '@TIMECARD_LIB.TIMECARD(SCH_1):PAGE68_I14@PASSIVE.RESISTOR(CHIPS)':
 C_PATH='@timecard_lib.timecard(sch_1):page68_i14@passive.resistor(chips)',
 P_PATH='@timecard_lib.timecard(sch_1):page30_i14@passive.resistor(chips)',
 PATH='I14',
 DRAWING='@TIMECARD_LIB.TIMECARD(SCH_1):PAGE68',
 PACKAGE='0402',
 PHYS_PAGE='30',
 XY='(-6350,7650)',
 ROT='1',
 VER='1',
 CDS_LIB='passive',
 CDS_PART_NAME='RESISTOR-G155-03001-01,3KOHM,1%',
 TOLERANCE='1%',
 CLS_PN='G155-03001-01',
 VALUE='3KOHM',
 PRIM_FILE='./archive_libs/passive/resistor/chips/chips.prt';

PART_NAME
 R187 'RESISTOR-G155-04221-01,4.22KOHA':;

SECTION_NUMBER 1
 '@TIMECARD_LIB.TIMECARD(SCH_1):PAGE68_I78@PASSIVE.RESISTOR(CHIPS)':
 C_PATH='@timecard_lib.timecard(sch_1):page68_i78@passive.resistor(chips)',
 P_PATH='@timecard_lib.timecard(sch_1):page30_i78@passive.resistor(chips)',
 PATH='I78',
 DRAWING='@TIMECARD_LIB.TIMECARD(SCH_1):PAGE68',
 PACKAGE='0402',
 PHYS_PAGE='30',
 XY='(-6350,3450)',
 ROT='0',
 VER='2',
 CDS_LIB='passive',
 CDS_PART_NAME='RESISTOR-G155-04221-01,4.22KOHA',
 TOLERANCE='1%',
 CLS_PN='G155-04221-01',
 VALUE='4.22KOHM',
 PRIM_FILE='./archive_libs/passive/resistor/chips/chips.prt';

PART_NAME
 R188 'RESISTOR-G155-03241-01,3.24KOHA':;

SECTION_NUMBER 1
 '@TIMECARD_LIB.TIMECARD(SCH_1):PAGE68_I79@PASSIVE.RESISTOR(CHIPS)':
 C_PATH='@timecard_lib.timecard(sch_1):page68_i79@passive.resistor(chips)',
 P_PATH='@timecard_lib.timecard(sch_1):page30_i79@passive.resistor(chips)',
 PATH='I79',
 DRAWING='@TIMECARD_LIB.TIMECARD(SCH_1):PAGE68',
 PACKAGE='0402',
 PHYS_PAGE='30',
 XY='(-6300,2750)',
 ROT='1',
 VER='1',
 CDS_LIB='passive',
 CDS_PART_NAME='RESISTOR-G155-03241-01,3.24KOHA',
 TOLERANCE='1%',
 CLS_PN='G155-03241-01',
 VALUE='3.24KOHM',
 PRIM_FILE='./archive_libs/passive/resistor/chips/chips.prt';

PART_NAME
 R189 'RESISTOR-G155-03241-01,3.24KOHA':;

SECTION_NUMBER 1
 '@TIMECARD_LIB.TIMECARD(SCH_1):PAGE68_I16@PASSIVE.RESISTOR(CHIPS)':
 C_PATH='@timecard_lib.timecard(sch_1):page68_i16@passive.resistor(chips)',
 P_PATH='@timecard_lib.timecard(sch_1):page30_i16@passive.resistor(chips)',
 PATH='I16',
 DRAWING='@TIMECARD_LIB.TIMECARD(SCH_1):PAGE68',
 PACKAGE='0402',
 PHYS_PAGE='30',
 XY='(-6100,7650)',
 ROT='1',
 VER='1',
 CDS_LIB='passive',
 CDS_PART_NAME='RESISTOR-G155-03241-01,3.24KOHA',
 NO_ASSY='TRUE',
 TOLERANCE='1%',
 CLS_PN='G155-03241-01',
 VALUE='3.24KOHM',
 PRIM_FILE='./archive_libs/passive/resistor/chips/chips.prt';

PART_NAME
 R190 'RESISTOR-G155-03241-01,3.24KOHA':;

SECTION_NUMBER 1
 '@TIMECARD_LIB.TIMECARD(SCH_1):PAGE68_I80@PASSIVE.RESISTOR(CHIPS)':
 C_PATH='@timecard_lib.timecard(sch_1):page68_i80@passive.resistor(chips)',
 P_PATH='@timecard_lib.timecard(sch_1):page30_i80@passive.resistor(chips)',
 PATH='I80',
 DRAWING='@TIMECARD_LIB.TIMECARD(SCH_1):PAGE68',
 PACKAGE='0402',
 PHYS_PAGE='30',
 XY='(-6050,2750)',
 ROT='1',
 VER='1',
 CDS_LIB='passive',
 CDS_PART_NAME='RESISTOR-G155-03241-01,3.24KOHA',
 TOLERANCE='1%',
 CLS_PN='G155-03241-01',
 VALUE='3.24KOHM',
 PRIM_FILE='./archive_libs/passive/resistor/chips/chips.prt';

PART_NAME
 R191 'RESISTOR-G155-14701-01,4.7KOHMA':;

SECTION_NUMBER 1
 '@TIMECARD_LIB.TIMECARD(SCH_1):PAGE127_I471@PASSIVE.RESISTOR(CHIPS)':
 C_PATH='@timecard_lib.timecard(sch_1):page127_i471@passive.resistor(chips)',
 P_PATH='@timecard_lib.timecard(sch_1):page10_i471@passive.resistor(chips)',
 PATH='I471',
 DRAWING='@TIMECARD_LIB.TIMECARD(SCH_1):PAGE127',
 PACKAGE='0402',
 PHYS_PAGE='10',
 XY='(-6500,500)',
 ROT='2',
 VER='2',
 CDS_LIB='passive',
 CDS_PART_NAME='RESISTOR-G155-14701-01,4.7KOHMA',
 TOLERANCE='1%',
 CLS_PN='G155-14701-01',
 VALUE='4.7KOHM',
 PRIM_FILE='./archive_libs/passive/resistor/chips/chips.prt';

PART_NAME
 R192 'RESISTOR-G155-14701-01,4.7KOHMA':;

SECTION_NUMBER 1
 '@TIMECARD_LIB.TIMECARD(SCH_1):PAGE127_I470@PASSIVE.RESISTOR(CHIPS)':
 C_PATH='@timecard_lib.timecard(sch_1):page127_i470@passive.resistor(chips)',
 P_PATH='@timecard_lib.timecard(sch_1):page10_i470@passive.resistor(chips)',
 PATH='I470',
 DRAWING='@TIMECARD_LIB.TIMECARD(SCH_1):PAGE127',
 PACKAGE='0402',
 PHYS_PAGE='10',
 XY='(-6400,-200)',
 ROT='0',
 VER='2',
 CDS_LIB='passive',
 CDS_PART_NAME='RESISTOR-G155-14701-01,4.7KOHMA',
 TOLERANCE='1%',
 CLS_PN='G155-14701-01',
 VALUE='4.7KOHM',
 PRIM_FILE='./archive_libs/passive/resistor/chips/chips.prt';

PART_NAME
 R193 'RESISTOR-G155-14701-01,4.7KOHMA':;

SECTION_NUMBER 1
 '@TIMECARD_LIB.TIMECARD(SCH_1):PAGE127_I330@PASSIVE.RESISTOR(CHIPS)':
 C_PATH='@timecard_lib.timecard(sch_1):page127_i330@passive.resistor(chips)',
 P_PATH='@timecard_lib.timecard(sch_1):page10_i330@passive.resistor(chips)',
 PATH='I330',
 DRAWING='@TIMECARD_LIB.TIMECARD(SCH_1):PAGE127',
 PACKAGE='0402',
 PHYS_PAGE='10',
 XY='(-10350,4750)',
 ROT='0',
 VER='1',
 CDS_LIB='passive',
 CDS_PART_NAME='RESISTOR-G155-14701-01,4.7KOHMA',
 TOLERANCE='1%',
 CLS_PN='G155-14701-01',
 VALUE='4.7KOHM',
 PRIM_FILE='./archive_libs/passive/resistor/chips/chips.prt';

PART_NAME
 R194 'RESISTOR-G155-14701-01,4.7KOHMA':;

SECTION_NUMBER 1
 '@TIMECARD_LIB.TIMECARD(SCH_1):PAGE127_I329@PASSIVE.RESISTOR(CHIPS)':
 C_PATH='@timecard_lib.timecard(sch_1):page127_i329@passive.resistor(chips)',
 P_PATH='@timecard_lib.timecard(sch_1):page10_i329@passive.resistor(chips)',
 PATH='I329',
 DRAWING='@TIMECARD_LIB.TIMECARD(SCH_1):PAGE127',
 PACKAGE='0402',
 PHYS_PAGE='10',
 XY='(-10350,4650)',
 ROT='0',
 VER='1',
 CDS_LIB='passive',
 CDS_PART_NAME='RESISTOR-G155-14701-01,4.7KOHMA',
 TOLERANCE='1%',
 CLS_PN='G155-14701-01',
 VALUE='4.7KOHM',
 PRIM_FILE='./archive_libs/passive/resistor/chips/chips.prt';

PART_NAME
 R195 'RESISTOR-G155-133R0-01,33OHM,1%':;

SECTION_NUMBER 1
 '@TIMECARD_LIB.TIMECARD(SCH_1):PAGE127_I331@PASSIVE.RESISTOR(CHIPS)':
 C_PATH='@timecard_lib.timecard(sch_1):page127_i331@passive.resistor(chips)',
 P_PATH='@timecard_lib.timecard(sch_1):page10_i331@passive.resistor(chips)',
 PATH='I331',
 DRAWING='@TIMECARD_LIB.TIMECARD(SCH_1):PAGE127',
 PACKAGE='0402',
 PHYS_PAGE='10',
 XY='(-9950,5150)',
 ROT='0',
 VER='1',
 CDS_LIB='passive',
 CDS_PART_NAME='RESISTOR-G155-133R0-01,33OHM,1%',
 TOLERANCE='1%',
 CLS_PN='G155-133R0-01',
 VALUE='33OHM',
 PRIM_FILE='./archive_libs/passive/resistor/chips/chips.prt';

PART_NAME
 R196 'RESISTOR-G155-11000-01,100OHM,A':;

SECTION_NUMBER 1
 '@TIMECARD_LIB.TIMECARD(SCH_1):PAGE127_I332@PASSIVE.RESISTOR(CHIPS)':
 C_PATH='@timecard_lib.timecard(sch_1):page127_i332@passive.resistor(chips)',
 P_PATH='@timecard_lib.timecard(sch_1):page10_i332@passive.resistor(chips)',
 PATH='I332',
 DRAWING='@TIMECARD_LIB.TIMECARD(SCH_1):PAGE127',
 PACKAGE='0402',
 PHYS_PAGE='10',
 XY='(-10150,5800)',
 ROT='0',
 VER='1',
 CDS_LIB='passive',
 CDS_PART_NAME='RESISTOR-G155-11000-01,100OHM,A',
 TOLERANCE='1%',
 CLS_PN='G155-11000-01',
 VALUE='100OHM',
 PRIM_FILE='./archive_libs/passive/resistor/chips/chips.prt';

PART_NAME
 R197 'RESISTOR-G155-11000-01,100OHM,A':;

SECTION_NUMBER 1
 '@TIMECARD_LIB.TIMECARD(SCH_1):PAGE127_I333@PASSIVE.RESISTOR(CHIPS)':
 C_PATH='@timecard_lib.timecard(sch_1):page127_i333@passive.resistor(chips)',
 P_PATH='@timecard_lib.timecard(sch_1):page10_i333@passive.resistor(chips)',
 PATH='I333',
 DRAWING='@TIMECARD_LIB.TIMECARD(SCH_1):PAGE127',
 PACKAGE='0402',
 PHYS_PAGE='10',
 XY='(-9500,6450)',
 ROT='0',
 VER='1',
 CDS_LIB='passive',
 CDS_PART_NAME='RESISTOR-G155-11000-01,100OHM,A',
 NO_ASSY='TRUE',
 TOLERANCE='1%',
 CLS_PN='G155-11000-01',
 VALUE='100OHM',
 PRIM_FILE='./archive_libs/passive/resistor/chips/chips.prt';

PART_NAME
 R198 'RESISTOR-G155-11000-01,100OHM,A':;

SECTION_NUMBER 1
 '@TIMECARD_LIB.TIMECARD(SCH_1):PAGE127_I334@PASSIVE.RESISTOR(CHIPS)':
 C_PATH='@timecard_lib.timecard(sch_1):page127_i334@passive.resistor(chips)',
 P_PATH='@timecard_lib.timecard(sch_1):page10_i334@passive.resistor(chips)',
 PATH='I334',
 DRAWING='@TIMECARD_LIB.TIMECARD(SCH_1):PAGE127',
 PACKAGE='0402',
 PHYS_PAGE='10',
 XY='(-9500,6150)',
 ROT='0',
 VER='1',
 CDS_LIB='passive',
 CDS_PART_NAME='RESISTOR-G155-11000-01,100OHM,A',
 NO_ASSY='TRUE',
 TOLERANCE='1%',
 CLS_PN='G155-11000-01',
 VALUE='100OHM',
 PRIM_FILE='./archive_libs/passive/resistor/chips/chips.prt';

PART_NAME
 R199 'RESISTOR-G155-14701-01,4.7KOHMA':;

SECTION_NUMBER 1
 '@TIMECARD_LIB.TIMECARD(SCH_1):PAGE127_I462@PASSIVE.RESISTOR(CHIPS)':
 C_PATH='@timecard_lib.timecard(sch_1):page127_i462@passive.resistor(chips)',
 P_PATH='@timecard_lib.timecard(sch_1):page10_i462@passive.resistor(chips)',
 PATH='I462',
 DRAWING='@TIMECARD_LIB.TIMECARD(SCH_1):PAGE127',
 PACKAGE='0402',
 PHYS_PAGE='10',
 XY='(-4500,700)',
 ROT='0',
 VER='1',
 CDS_LIB='passive',
 CDS_PART_NAME='RESISTOR-G155-14701-01,4.7KOHMA',
 TOLERANCE='1%',
 CLS_PN='G155-14701-01',
 VALUE='4.7KOHM',
 PRIM_FILE='./archive_libs/passive/resistor/chips/chips.prt';

PART_NAME
 R200 'RESISTOR-G155-14701-01,4.7KOHMA':;

SECTION_NUMBER 1
 '@TIMECARD_LIB.TIMECARD(SCH_1):PAGE127_I465@PASSIVE.RESISTOR(CHIPS)':
 C_PATH='@timecard_lib.timecard(sch_1):page127_i465@passive.resistor(chips)',
 P_PATH='@timecard_lib.timecard(sch_1):page10_i465@passive.resistor(chips)',
 PATH='I465',
 DRAWING='@TIMECARD_LIB.TIMECARD(SCH_1):PAGE127',
 PACKAGE='0402',
 PHYS_PAGE='10',
 XY='(-4500,600)',
 ROT='0',
 VER='1',
 LOCATION='R200',
 CDS_LIB='passive',
 CDS_PART_NAME='RESISTOR-G155-14701-01,4.7KOHMA',
 TOLERANCE='1%',
 CLS_PN='G155-14701-01',
 VALUE='4.7KOHM',
 PRIM_FILE='./archive_libs/passive/resistor/chips/chips.prt';

PART_NAME
 R201 'RESISTOR-G155-14701-01,4.7KOHMA':;

SECTION_NUMBER 1
 '@TIMECARD_LIB.TIMECARD(SCH_1):PAGE127_I463@PASSIVE.RESISTOR(CHIPS)':
 C_PATH='@timecard_lib.timecard(sch_1):page127_i463@passive.resistor(chips)',
 P_PATH='@timecard_lib.timecard(sch_1):page10_i463@passive.resistor(chips)',
 PATH='I463',
 DRAWING='@TIMECARD_LIB.TIMECARD(SCH_1):PAGE127',
 PACKAGE='0402',
 PHYS_PAGE='10',
 XY='(-4500,500)',
 ROT='0',
 VER='1',
 LOCATION='R201',
 CDS_LIB='passive',
 CDS_PART_NAME='RESISTOR-G155-14701-01,4.7KOHMA',
 TOLERANCE='1%',
 CLS_PN='G155-14701-01',
 VALUE='4.7KOHM',
 PRIM_FILE='./archive_libs/passive/resistor/chips/chips.prt';

PART_NAME
 R202 'RESISTOR-G155-14701-01,4.7KOHMA':;

SECTION_NUMBER 1
 '@TIMECARD_LIB.TIMECARD(SCH_1):PAGE127_I464@PASSIVE.RESISTOR(CHIPS)':
 C_PATH='@timecard_lib.timecard(sch_1):page127_i464@passive.resistor(chips)',
 P_PATH='@timecard_lib.timecard(sch_1):page10_i464@passive.resistor(chips)',
 PATH='I464',
 DRAWING='@TIMECARD_LIB.TIMECARD(SCH_1):PAGE127',
 PACKAGE='0402',
 PHYS_PAGE='10',
 XY='(-4500,400)',
 ROT='0',
 VER='1',
 LOCATION='R202',
 CDS_LIB='passive',
 CDS_PART_NAME='RESISTOR-G155-14701-01,4.7KOHMA',
 TOLERANCE='1%',
 CLS_PN='G155-14701-01',
 VALUE='4.7KOHM',
 PRIM_FILE='./archive_libs/passive/resistor/chips/chips.prt';

PART_NAME
 R203 'RESISTOR-G155-133R0-01,33OHM,1%':;

SECTION_NUMBER 1
 '@TIMECARD_LIB.TIMECARD(SCH_1):PAGE127_I467@PASSIVE.RESISTOR(CHIPS)':
 C_PATH='@timecard_lib.timecard(sch_1):page127_i467@passive.resistor(chips)',
 P_PATH='@timecard_lib.timecard(sch_1):page10_i467@passive.resistor(chips)',
 PATH='I467',
 DRAWING='@TIMECARD_LIB.TIMECARD(SCH_1):PAGE127',
 PACKAGE='0402',
 PHYS_PAGE='10',
 XY='(-4500,250)',
 ROT='0',
 VER='1',
 CDS_LIB='passive',
 CDS_PART_NAME='RESISTOR-G155-133R0-01,33OHM,1%',
 TOLERANCE='1%',
 CLS_PN='G155-133R0-01',
 VALUE='33OHM',
 PRIM_FILE='./archive_libs/passive/resistor/chips/chips.prt';

PART_NAME
 R204 'RESISTOR-G155-133R0-01,33OHM,1%':;

SECTION_NUMBER 1
 '@TIMECARD_LIB.TIMECARD(SCH_1):PAGE127_I466@PASSIVE.RESISTOR(CHIPS)':
 C_PATH='@timecard_lib.timecard(sch_1):page127_i466@passive.resistor(chips)',
 P_PATH='@timecard_lib.timecard(sch_1):page10_i466@passive.resistor(chips)',
 PATH='I466',
 DRAWING='@TIMECARD_LIB.TIMECARD(SCH_1):PAGE127',
 PACKAGE='0402',
 PHYS_PAGE='10',
 XY='(-4500,150)',
 ROT='0',
 VER='1',
 LOCATION='R204',
 CDS_LIB='passive',
 CDS_PART_NAME='RESISTOR-G155-133R0-01,33OHM,1%',
 TOLERANCE='1%',
 CLS_PN='G155-133R0-01',
 VALUE='33OHM',
 PRIM_FILE='./archive_libs/passive/resistor/chips/chips.prt';

PART_NAME
 R205 'RESISTOR-G155-133R0-01,33OHM,1%':;

SECTION_NUMBER 1
 '@TIMECARD_LIB.TIMECARD(SCH_1):PAGE127_I468@PASSIVE.RESISTOR(CHIPS)':
 C_PATH='@timecard_lib.timecard(sch_1):page127_i468@passive.resistor(chips)',
 P_PATH='@timecard_lib.timecard(sch_1):page10_i468@passive.resistor(chips)',
 PATH='I468',
 DRAWING='@TIMECARD_LIB.TIMECARD(SCH_1):PAGE127',
 PACKAGE='0402',
 PHYS_PAGE='10',
 XY='(-4500,50)',
 ROT='0',
 VER='1',
 LOCATION='R205',
 CDS_LIB='passive',
 CDS_PART_NAME='RESISTOR-G155-133R0-01,33OHM,1%',
 TOLERANCE='1%',
 CLS_PN='G155-133R0-01',
 VALUE='33OHM',
 PRIM_FILE='./archive_libs/passive/resistor/chips/chips.prt';

PART_NAME
 R206 'RESISTOR-G155-133R0-01,33OHM,1%':;

SECTION_NUMBER 1
 '@TIMECARD_LIB.TIMECARD(SCH_1):PAGE127_I469@PASSIVE.RESISTOR(CHIPS)':
 C_PATH='@timecard_lib.timecard(sch_1):page127_i469@passive.resistor(chips)',
 P_PATH='@timecard_lib.timecard(sch_1):page10_i469@passive.resistor(chips)',
 PATH='I469',
 DRAWING='@TIMECARD_LIB.TIMECARD(SCH_1):PAGE127',
 PACKAGE='0402',
 PHYS_PAGE='10',
 XY='(-4500,-50)',
 ROT='0',
 VER='1',
 LOCATION='R206',
 CDS_LIB='passive',
 CDS_PART_NAME='RESISTOR-G155-133R0-01,33OHM,1%',
 TOLERANCE='1%',
 CLS_PN='G155-133R0-01',
 VALUE='33OHM',
 PRIM_FILE='./archive_libs/passive/resistor/chips/chips.prt';

PART_NAME
 R207 'RESISTOR-G155-100R0-J0,0OHM,-':;

SECTION_NUMBER 1
 '@TIMECARD_LIB.TIMECARD(SCH_1):PAGE127_I337@PASSIVE.RESISTOR(CHIPS)':
 C_PATH='@timecard_lib.timecard(sch_1):page127_i337@passive.resistor(chips)',
 P_PATH='@timecard_lib.timecard(sch_1):page10_i337@passive.resistor(chips)',
 PATH='I337',
 DRAWING='@TIMECARD_LIB.TIMECARD(SCH_1):PAGE127',
 PHYS_PAGE='10',
 XY='(-5750,5150)',
 ROT='0',
 VER='1',
 CDS_LIB='passive',
 CDS_PART_NAME='RESISTOR-G155-100R0-J0,0OHM,-',
 TOLERANCE='-',
 CLS_PN='G155-100R0-J0',
 VALUE='0OHM',
 PRIM_FILE='./archive_libs/passive/resistor/chips/chips.prt';

PART_NAME
 R208 'RESISTOR-G155-13300-01,330OHM,A':;

SECTION_NUMBER 1
 '@TIMECARD_LIB.TIMECARD(SCH_1):PAGE14_I293@PASSIVE.RESISTOR(CHIPS)':
 C_PATH='@timecard_lib.timecard(sch_1):page14_i293@passive.resistor(chips)',
 P_PATH='@timecard_lib.timecard(sch_1):page26_i293@passive.resistor(chips)',
 PATH='I293',
 DRAWING='@TIMECARD_LIB.TIMECARD(SCH_1):PAGE14',
 PHYS_PAGE='26',
 XY='(-10150,10200)',
 ROT='0',
 VER='1',
 CDS_LIB='passive',
 CDS_PART_NAME='RESISTOR-G155-13300-01,330OHM,A',
 TOLERANCE='1%',
 CLS_PN='G155-13300-01',
 VALUE='330OHM',
 PRIM_FILE='./archive_libs/passive/resistor/chips/chips.prt';

PART_NAME
 R209 'RESISTOR-G155-14701-01,4.7KOHMA':;

SECTION_NUMBER 1
 '@TIMECARD_LIB.TIMECARD(SCH_1):PAGE127_I339@PASSIVE.RESISTOR(CHIPS)':
 C_PATH='@timecard_lib.timecard(sch_1):page127_i339@passive.resistor(chips)',
 P_PATH='@timecard_lib.timecard(sch_1):page10_i339@passive.resistor(chips)',
 PATH='I339',
 DRAWING='@TIMECARD_LIB.TIMECARD(SCH_1):PAGE127',
 PHYS_PAGE='10',
 XY='(-3600,4750)',
 ROT='0',
 VER='1',
 CDS_LIB='passive',
 CDS_PART_NAME='RESISTOR-G155-14701-01,4.7KOHMA',
 TOLERANCE='1%',
 CLS_PN='G155-14701-01',
 VALUE='4.7KOHM',
 PRIM_FILE='./archive_libs/passive/resistor/chips/chips.prt';

PART_NAME
 R210 'RESISTOR-G155-13300-01,330OHM,A':;

SECTION_NUMBER 1
 '@TIMECARD_LIB.TIMECARD(SCH_1):PAGE127_I338@PASSIVE.RESISTOR(CHIPS)':
 C_PATH='@timecard_lib.timecard(sch_1):page127_i338@passive.resistor(chips)',
 P_PATH='@timecard_lib.timecard(sch_1):page10_i338@passive.resistor(chips)',
 PATH='I338',
 DRAWING='@TIMECARD_LIB.TIMECARD(SCH_1):PAGE127',
 PHYS_PAGE='10',
 XY='(-3600,4650)',
 ROT='0',
 VER='1',
 CDS_LIB='passive',
 CDS_PART_NAME='RESISTOR-G155-13300-01,330OHM,A',
 TOLERANCE='1%',
 CLS_PN='G155-13300-01',
 VALUE='330OHM',
 PRIM_FILE='./archive_libs/passive/resistor/chips/chips.prt';

PART_NAME
 R211 'RESISTOR-G155-11000-01,100OHM,A':;

SECTION_NUMBER 1
 '@TIMECARD_LIB.TIMECARD(SCH_1):PAGE127_I404@PASSIVE.RESISTOR(CHIPS)':
 C_PATH='@timecard_lib.timecard(sch_1):page127_i404@passive.resistor(chips)',
 P_PATH='@timecard_lib.timecard(sch_1):page10_i404@passive.resistor(chips)',
 PATH='I404',
 DRAWING='@TIMECARD_LIB.TIMECARD(SCH_1):PAGE127',
 PACKAGE='0402',
 PHYS_PAGE='10',
 XY='(-2000,3250)',
 ROT='5',
 VER='1',
 CDS_LIB='passive',
 CDS_PART_NAME='RESISTOR-G155-11000-01,100OHM,A',
 TOLERANCE='1%',
 CLS_PN='G155-11000-01',
 VALUE='100OHM',
 PRIM_FILE='./archive_libs/passive/resistor/chips/chips.prt';

PART_NAME
 R212 'RESISTOR-G155-11000-01,100OHM,A':;

SECTION_NUMBER 1
 '@TIMECARD_LIB.TIMECARD(SCH_1):PAGE127_I407@PASSIVE.RESISTOR(CHIPS)':
 C_PATH='@timecard_lib.timecard(sch_1):page127_i407@passive.resistor(chips)',
 P_PATH='@timecard_lib.timecard(sch_1):page10_i407@passive.resistor(chips)',
 PATH='I407',
 DRAWING='@TIMECARD_LIB.TIMECARD(SCH_1):PAGE127',
 PACKAGE='0402',
 PHYS_PAGE='10',
 XY='(-2000,2600)',
 ROT='5',
 VER='1',
 CDS_LIB='passive',
 CDS_PART_NAME='RESISTOR-G155-11000-01,100OHM,A',
 NO_ASSY='TRUE',
 TOLERANCE='1%',
 CLS_PN='G155-11000-01',
 VALUE='100OHM',
 PRIM_FILE='./archive_libs/passive/resistor/chips/chips.prt';

PART_NAME
 R213 'RESISTOR-G155-11002-01,10KOHM,A':;

SECTION_NUMBER 1
 '@TIMECARD_LIB.TIMECARD(SCH_1):PAGE127_I396@PASSIVE.RESISTOR(CHIPS)':
 C_PATH='@timecard_lib.timecard(sch_1):page127_i396@passive.resistor(chips)',
 P_PATH='@timecard_lib.timecard(sch_1):page10_i396@passive.resistor(chips)',
 PATH='I396',
 DRAWING='@TIMECARD_LIB.TIMECARD(SCH_1):PAGE127',
 PACKAGE='0402',
 PHYS_PAGE='10',
 XY='(-5500,3250)',
 ROT='0',
 VER='2',
 CDS_LIB='passive',
 CDS_PART_NAME='RESISTOR-G155-11002-01,10KOHM,A',
 NO_ASSY='TRUE',
 TOLERANCE='1%',
 CLS_PN='G155-11002-01',
 VALUE='10KOHM',
 PRIM_FILE='./archive_libs/passive/resistor/chips/chips.prt';

PART_NAME
 R214 'RESISTOR-G155-11001-01,1KOHM,1%':;

SECTION_NUMBER 1
 '@TIMECARD_LIB.TIMECARD(SCH_1):PAGE127_I397@PASSIVE.RESISTOR(CHIPS)':
 C_PATH='@timecard_lib.timecard(sch_1):page127_i397@passive.resistor(chips)',
 P_PATH='@timecard_lib.timecard(sch_1):page10_i397@passive.resistor(chips)',
 PATH='I397',
 DRAWING='@TIMECARD_LIB.TIMECARD(SCH_1):PAGE127',
 PACKAGE='0402',
 PHYS_PAGE='10',
 XY='(-5500,2600)',
 ROT='0',
 VER='2',
 CDS_LIB='passive',
 CDS_PART_NAME='RESISTOR-G155-11001-01,1KOHM,1%',
 TOLERANCE='1%',
 CLS_PN='G155-11001-01',
 VALUE='1KOHM',
 PRIM_FILE='./archive_libs/passive/resistor/chips/chips.prt';

PART_NAME
 R215 'RESISTOR-G155-11002-01,10KOHM,A':;

SECTION_NUMBER 1
 '@TIMECARD_LIB.TIMECARD(SCH_1):PAGE127_I394@PASSIVE.RESISTOR(CHIPS)':
 C_PATH='@timecard_lib.timecard(sch_1):page127_i394@passive.resistor(chips)',
 P_PATH='@timecard_lib.timecard(sch_1):page10_i394@passive.resistor(chips)',
 PATH='I394',
 DRAWING='@TIMECARD_LIB.TIMECARD(SCH_1):PAGE127',
 PACKAGE='0402',
 PHYS_PAGE='10',
 XY='(-5000,3250)',
 ROT='0',
 VER='2',
 CDS_LIB='passive',
 CDS_PART_NAME='RESISTOR-G155-11002-01,10KOHM,A',
 NO_ASSY='TRUE',
 TOLERANCE='1%',
 CLS_PN='G155-11002-01',
 VALUE='10KOHM',
 PRIM_FILE='./archive_libs/passive/resistor/chips/chips.prt';

PART_NAME
 R216 'RESISTOR-G155-11001-01,1KOHM,1%':;

SECTION_NUMBER 1
 '@TIMECARD_LIB.TIMECARD(SCH_1):PAGE127_I391@PASSIVE.RESISTOR(CHIPS)':
 C_PATH='@timecard_lib.timecard(sch_1):page127_i391@passive.resistor(chips)',
 P_PATH='@timecard_lib.timecard(sch_1):page10_i391@passive.resistor(chips)',
 PATH='I391',
 DRAWING='@TIMECARD_LIB.TIMECARD(SCH_1):PAGE127',
 PACKAGE='0402',
 PHYS_PAGE='10',
 XY='(-5000,2600)',
 ROT='0',
 VER='2',
 CDS_LIB='passive',
 CDS_PART_NAME='RESISTOR-G155-11001-01,1KOHM,1%',
 TOLERANCE='1%',
 CLS_PN='G155-11001-01',
 VALUE='1KOHM',
 PRIM_FILE='./archive_libs/passive/resistor/chips/chips.prt';

PART_NAME
 R217 'RESISTOR-G155-11000-01,100OHM,A':;

SECTION_NUMBER 1
 '@TIMECARD_LIB.TIMECARD(SCH_1):PAGE127_I402@PASSIVE.RESISTOR(CHIPS)':
 C_PATH='@timecard_lib.timecard(sch_1):page127_i402@passive.resistor(chips)',
 P_PATH='@timecard_lib.timecard(sch_1):page10_i402@passive.resistor(chips)',
 PATH='I402',
 DRAWING='@TIMECARD_LIB.TIMECARD(SCH_1):PAGE127',
 PACKAGE='0402',
 PHYS_PAGE='10',
 XY='(-1500,3250)',
 ROT='5',
 VER='1',
 CDS_LIB='passive',
 CDS_PART_NAME='RESISTOR-G155-11000-01,100OHM,A',
 NO_ASSY='TRUE',
 TOLERANCE='1%',
 CLS_PN='G155-11000-01',
 VALUE='100OHM',
 PRIM_FILE='./archive_libs/passive/resistor/chips/chips.prt';

PART_NAME
 R218 'RESISTOR-G155-11000-01,100OHM,A':;

SECTION_NUMBER 1
 '@TIMECARD_LIB.TIMECARD(SCH_1):PAGE127_I406@PASSIVE.RESISTOR(CHIPS)':
 C_PATH='@timecard_lib.timecard(sch_1):page127_i406@passive.resistor(chips)',
 P_PATH='@timecard_lib.timecard(sch_1):page10_i406@passive.resistor(chips)',
 PATH='I406',
 DRAWING='@TIMECARD_LIB.TIMECARD(SCH_1):PAGE127',
 PACKAGE='0402',
 PHYS_PAGE='10',
 XY='(-1500,2600)',
 ROT='5',
 VER='1',
 CDS_LIB='passive',
 CDS_PART_NAME='RESISTOR-G155-11000-01,100OHM,A',
 TOLERANCE='1%',
 CLS_PN='G155-11000-01',
 VALUE='100OHM',
 PRIM_FILE='./archive_libs/passive/resistor/chips/chips.prt';

PART_NAME
 R219 'RESISTOR-G155-11002-01,10KOHM,A':;

SECTION_NUMBER 1
 '@TIMECARD_LIB.TIMECARD(SCH_1):PAGE127_I392@PASSIVE.RESISTOR(CHIPS)':
 C_PATH='@timecard_lib.timecard(sch_1):page127_i392@passive.resistor(chips)',
 P_PATH='@timecard_lib.timecard(sch_1):page10_i392@passive.resistor(chips)',
 PATH='I392',
 DRAWING='@TIMECARD_LIB.TIMECARD(SCH_1):PAGE127',
 PACKAGE='0402',
 PHYS_PAGE='10',
 XY='(-4550,3250)',
 ROT='0',
 VER='2',
 CDS_LIB='passive',
 CDS_PART_NAME='RESISTOR-G155-11002-01,10KOHM,A',
 TOLERANCE='1%',
 CLS_PN='G155-11002-01',
 VALUE='10KOHM',
 PRIM_FILE='./archive_libs/passive/resistor/chips/chips.prt';

PART_NAME
 R220 'RESISTOR-G155-11001-01,1KOHM,1%':;

SECTION_NUMBER 1
 '@TIMECARD_LIB.TIMECARD(SCH_1):PAGE127_I393@PASSIVE.RESISTOR(CHIPS)':
 C_PATH='@timecard_lib.timecard(sch_1):page127_i393@passive.resistor(chips)',
 P_PATH='@timecard_lib.timecard(sch_1):page10_i393@passive.resistor(chips)',
 PATH='I393',
 DRAWING='@TIMECARD_LIB.TIMECARD(SCH_1):PAGE127',
 PACKAGE='0402',
 PHYS_PAGE='10',
 XY='(-4550,2600)',
 ROT='0',
 VER='2',
 CDS_LIB='passive',
 CDS_PART_NAME='RESISTOR-G155-11001-01,1KOHM,1%',
 NO_ASSY='TRUE',
 TOLERANCE='1%',
 CLS_PN='G155-11001-01',
 VALUE='1KOHM',
 PRIM_FILE='./archive_libs/passive/resistor/chips/chips.prt';

PART_NAME
 R221 'RESISTOR-G155-11000-01,100OHM,A':;

SECTION_NUMBER 1
 '@TIMECARD_LIB.TIMECARD(SCH_1):PAGE127_I403@PASSIVE.RESISTOR(CHIPS)':
 C_PATH='@timecard_lib.timecard(sch_1):page127_i403@passive.resistor(chips)',
 P_PATH='@timecard_lib.timecard(sch_1):page10_i403@passive.resistor(chips)',
 PATH='I403',
 DRAWING='@TIMECARD_LIB.TIMECARD(SCH_1):PAGE127',
 PACKAGE='0402',
 PHYS_PAGE='10',
 XY='(-1000,3250)',
 ROT='5',
 VER='1',
 CDS_LIB='passive',
 CDS_PART_NAME='RESISTOR-G155-11000-01,100OHM,A',
 NO_ASSY='TRUE',
 TOLERANCE='1%',
 CLS_PN='G155-11000-01',
 VALUE='100OHM',
 PRIM_FILE='./archive_libs/passive/resistor/chips/chips.prt';

PART_NAME
 R222 'RESISTOR-G155-11000-01,100OHM,A':;

SECTION_NUMBER 1
 '@TIMECARD_LIB.TIMECARD(SCH_1):PAGE127_I405@PASSIVE.RESISTOR(CHIPS)':
 C_PATH='@timecard_lib.timecard(sch_1):page127_i405@passive.resistor(chips)',
 P_PATH='@timecard_lib.timecard(sch_1):page10_i405@passive.resistor(chips)',
 PATH='I405',
 DRAWING='@TIMECARD_LIB.TIMECARD(SCH_1):PAGE127',
 PACKAGE='0402',
 PHYS_PAGE='10',
 XY='(-1000,2600)',
 ROT='5',
 VER='1',
 CDS_LIB='passive',
 CDS_PART_NAME='RESISTOR-G155-11000-01,100OHM,A',
 TOLERANCE='1%',
 CLS_PN='G155-11000-01',
 VALUE='100OHM',
 PRIM_FILE='./archive_libs/passive/resistor/chips/chips.prt';

PART_NAME
 R223 'RESISTOR-G155-11001-01,1KOHM,1%':;

SECTION_NUMBER 1
 '@TIMECARD_LIB.TIMECARD(SCH_1):PAGE161_I252@PASSIVE.RESISTOR(CHIPS)':
 C_PATH='@timecard_lib.timecard(sch_1):page161_i252@passive.resistor(chips)',
 P_PATH='@timecard_lib.timecard(sch_1):page11_i252@passive.resistor(chips)',
 PATH='I252',
 DRAWING='@TIMECARD_LIB.TIMECARD(SCH_1):PAGE161',
 PACKAGE='0402',
 PHYS_PAGE='11',
 XY='(-2800,7750)',
 ROT='0',
 VER='1',
 CDS_LIB='passive',
 CDS_PART_NAME='RESISTOR-G155-11001-01,1KOHM,1%',
 TOLERANCE='1%',
 CLS_PN='G155-11001-01',
 VALUE='1KOHM',
 PRIM_FILE='./archive_libs/passive/resistor/chips/chips.prt';

PART_NAME
 R224 'RESISTOR-G155-11001-01,1KOHM,1%':;

SECTION_NUMBER 1
 '@TIMECARD_LIB.TIMECARD(SCH_1):PAGE161_I253@PASSIVE.RESISTOR(CHIPS)':
 C_PATH='@timecard_lib.timecard(sch_1):page161_i253@passive.resistor(chips)',
 P_PATH='@timecard_lib.timecard(sch_1):page11_i253@passive.resistor(chips)',
 PATH='I253',
 DRAWING='@TIMECARD_LIB.TIMECARD(SCH_1):PAGE161',
 PACKAGE='0402',
 PHYS_PAGE='11',
 XY='(-2750,7650)',
 ROT='4',
 VER='1',
 CDS_LIB='passive',
 CDS_PART_NAME='RESISTOR-G155-11001-01,1KOHM,1%',
 NO_ASSY='TRUE',
 TOLERANCE='1%',
 CLS_PN='G155-11001-01',
 VALUE='1KOHM',
 PRIM_FILE='./archive_libs/passive/resistor/chips/chips.prt';

PART_NAME
 R225 'RESISTOR-G155-13300-01,330OHM,A':;

SECTION_NUMBER 1
 '@TIMECARD_LIB.TIMECARD(SCH_1):PAGE515_I152@PASSIVE.RESISTOR(CHIPS)':
 C_PATH='@timecard_lib.timecard(sch_1):page515_i152@passive.resistor(chips)',
 P_PATH='@timecard_lib.timecard(sch_1):page31_i152@passive.resistor(chips)',
 PATH='I152',
 DRAWING='@TIMECARD_LIB.TIMECARD(SCH_1):PAGE515',
 PACKAGE='0402',
 PHYS_PAGE='31',
 XY='(-10900,1150)',
 ROT='0',
 VER='1',
 CDS_LIB='passive',
 CDS_PART_NAME='RESISTOR-G155-13300-01,330OHM,A',
 TOLERANCE='1%',
 CLS_PN='G155-13300-01',
 VALUE='330OHM',
 PRIM_FILE='./archive_libs/passive/resistor/chips/chips.prt';

PART_NAME
 R226 'RESISTOR-G155-13300-01,330OHM,A':;

SECTION_NUMBER 1
 '@TIMECARD_LIB.TIMECARD(SCH_1):PAGE515_I122@PASSIVE.RESISTOR(CHIPS)':
 C_PATH='@timecard_lib.timecard(sch_1):page515_i122@passive.resistor(chips)',
 P_PATH='@timecard_lib.timecard(sch_1):page31_i122@passive.resistor(chips)',
 PATH='I122',
 DRAWING='@TIMECARD_LIB.TIMECARD(SCH_1):PAGE515',
 PACKAGE='0402',
 PHYS_PAGE='31',
 XY='(-10700,6600)',
 ROT='0',
 VER='1',
 CDS_LIB='passive',
 CDS_PART_NAME='RESISTOR-G155-13300-01,330OHM,A',
 TOLERANCE='1%',
 CLS_PN='G155-13300-01',
 VALUE='330OHM',
 PRIM_FILE='./archive_libs/passive/resistor/chips/chips.prt';

PART_NAME
 R227 'RESISTOR-G155-11002-01,10KOHM,A':;

SECTION_NUMBER 1
 '@TIMECARD_LIB.TIMECARD(SCH_1):PAGE515_I127@PASSIVE.RESISTOR(CHIPS)':
 C_PATH='@timecard_lib.timecard(sch_1):page515_i127@passive.resistor(chips)',
 P_PATH='@timecard_lib.timecard(sch_1):page31_i127@passive.resistor(chips)',
 PATH='I127',
 DRAWING='@TIMECARD_LIB.TIMECARD(SCH_1):PAGE515',
 PACKAGE='0402',
 PHYS_PAGE='31',
 XY='(-9800,850)',
 ROT='0',
 VER='2',
 CDS_LIB='passive',
 CDS_PART_NAME='RESISTOR-G155-11002-01,10KOHM,A',
 NO_ASSY='TRUE',
 TOLERANCE='1%',
 CLS_PN='G155-11002-01',
 VALUE='10KOHM',
 PRIM_FILE='./archive_libs/passive/resistor/chips/chips.prt';

PART_NAME
 R228 'RESISTOR-G152-00055-01,1.13KOHA':;

SECTION_NUMBER 1
 '@TIMECARD_LIB.TIMECARD(SCH_1):PAGE515_I129@PASSIVE.RESISTOR(CHIPS)':
 C_PATH='@timecard_lib.timecard(sch_1):page515_i129@passive.resistor(chips)',
 P_PATH='@timecard_lib.timecard(sch_1):page31_i129@passive.resistor(chips)',
 PATH='I129',
 DRAWING='@TIMECARD_LIB.TIMECARD(SCH_1):PAGE515',
 PACKAGE='0402',
 PHYS_PAGE='31',
 XY='(-9750,1700)',
 ROT='0',
 VER='2',
 CDS_LIB='passive',
 CDS_PART_NAME='RESISTOR-G152-00055-01,1.13KOHA',
 NO_ASSY='TRUE',
 TOLERANCE='1%',
 CLS_PN='G152-00055-01',
 VALUE='1.13KOHM',
 PRIM_FILE='./archive_libs/passive/resistor/chips/chips.prt';

PART_NAME
 R229 'RESISTOR-G155-14701-01,4.7KOHMA':;

SECTION_NUMBER 1
 '@TIMECARD_LIB.TIMECARD(SCH_1):PAGE515_I139@PASSIVE.RESISTOR(CHIPS)':
 C_PATH='@timecard_lib.timecard(sch_1):page515_i139@passive.resistor(chips)',
 P_PATH='@timecard_lib.timecard(sch_1):page31_i139@passive.resistor(chips)',
 PATH='I139',
 DRAWING='@TIMECARD_LIB.TIMECARD(SCH_1):PAGE515',
 PACKAGE='0402',
 PHYS_PAGE='31',
 XY='(-5750,550)',
 ROT='0',
 VER='2',
 CDS_LIB='passive',
 CDS_PART_NAME='RESISTOR-G155-14701-01,4.7KOHMA',
 NO_ASSY='TRUE',
 TOLERANCE='1%',
 CLS_PN='G155-14701-01',
 VALUE='4.7KOHM',
 PRIM_FILE='./archive_libs/passive/resistor/chips/chips.prt';

PART_NAME
 R230 'RESISTOR-G155-100R0-J0,0OHM,-':;

SECTION_NUMBER 1
 '@TIMECARD_LIB.TIMECARD(SCH_1):PAGE515_I140@PASSIVE.RESISTOR(CHIPS)':
 C_PATH='@timecard_lib.timecard(sch_1):page515_i140@passive.resistor(chips)',
 P_PATH='@timecard_lib.timecard(sch_1):page31_i140@passive.resistor(chips)',
 PATH='I140',
 DRAWING='@TIMECARD_LIB.TIMECARD(SCH_1):PAGE515',
 PHYS_PAGE='31',
 XY='(-5050,250)',
 ROT='0',
 VER='1',
 CDS_LIB='passive',
 CDS_PART_NAME='RESISTOR-G155-100R0-J0,0OHM,-',
 TOLERANCE='-',
 CLS_PN='G155-100R0-J0',
 VALUE='0OHM',
 PRIM_FILE='./archive_libs/passive/resistor/chips/chips.prt';

PART_NAME
 R231 'RESISTOR-G155-04221-01,4.22KOHA':;

SECTION_NUMBER 1
 '@TIMECARD_LIB.TIMECARD(SCH_1):PAGE515_I146@PASSIVE.RESISTOR(CHIPS)':
 C_PATH='@timecard_lib.timecard(sch_1):page515_i146@passive.resistor(chips)',
 P_PATH='@timecard_lib.timecard(sch_1):page31_i146@passive.resistor(chips)',
 PATH='I146',
 DRAWING='@TIMECARD_LIB.TIMECARD(SCH_1):PAGE515',
 PACKAGE='0402',
 PHYS_PAGE='31',
 XY='(-4450,1750)',
 ROT='0',
 VER='2',
 CDS_LIB='passive',
 CDS_PART_NAME='RESISTOR-G155-04221-01,4.22KOHA',
 TOLERANCE='1%',
 CLS_PN='G155-04221-01',
 VALUE='4.22KOHM',
 PRIM_FILE='./archive_libs/passive/resistor/chips/chips.prt';

PART_NAME
 R232 'RESISTOR-G155-02101-01,2.1KOHMA':;

SECTION_NUMBER 1
 '@TIMECARD_LIB.TIMECARD(SCH_1):PAGE515_I143@PASSIVE.RESISTOR(CHIPS)':
 C_PATH='@timecard_lib.timecard(sch_1):page515_i143@passive.resistor(chips)',
 P_PATH='@timecard_lib.timecard(sch_1):page31_i143@passive.resistor(chips)',
 PATH='I143',
 DRAWING='@TIMECARD_LIB.TIMECARD(SCH_1):PAGE515',
 PACKAGE='0402',
 PHYS_PAGE='31',
 XY='(-4400,1050)',
 ROT='1',
 VER='1',
 CDS_LIB='passive',
 CDS_PART_NAME='RESISTOR-G155-02101-01,2.1KOHMA',
 TOLERANCE='1%',
 CLS_PN='G155-02101-01',
 VALUE='2.1KOHM',
 PRIM_FILE='./archive_libs/passive/resistor/chips/chips.prt';

PART_NAME
 R233 'RESISTOR-G155-02101-01,2.1KOHMA':;

SECTION_NUMBER 1
 '@TIMECARD_LIB.TIMECARD(SCH_1):PAGE515_I145@PASSIVE.RESISTOR(CHIPS)':
 C_PATH='@timecard_lib.timecard(sch_1):page515_i145@passive.resistor(chips)',
 P_PATH='@timecard_lib.timecard(sch_1):page31_i145@passive.resistor(chips)',
 PATH='I145',
 DRAWING='@TIMECARD_LIB.TIMECARD(SCH_1):PAGE515',
 PACKAGE='0402',
 PHYS_PAGE='31',
 XY='(-4150,1050)',
 ROT='1',
 VER='1',
 CDS_LIB='passive',
 CDS_PART_NAME='RESISTOR-G155-02101-01,2.1KOHMA',
 TOLERANCE='1%',
 CLS_PN='G155-02101-01',
 VALUE='2.1KOHM',
 PRIM_FILE='./archive_libs/passive/resistor/chips/chips.prt';

PART_NAME
 R234 'RESISTOR-G155-133R0-01,33OHM,1%':;

SECTION_NUMBER 1
 '@TIMECARD_LIB.TIMECARD(SCH_1):PAGE161_I258@PASSIVE.RESISTOR(CHIPS)':
 C_PATH='@timecard_lib.timecard(sch_1):page161_i258@passive.resistor(chips)',
 P_PATH='@timecard_lib.timecard(sch_1):page11_i258@passive.resistor(chips)',
 PATH='I258',
 DRAWING='@TIMECARD_LIB.TIMECARD(SCH_1):PAGE161',
 PACKAGE='0402',
 PHYS_PAGE='11',
 XY='(-5350,8150)',
 ROT='0',
 VER='1',
 CDS_LIB='passive',
 CDS_PART_NAME='RESISTOR-G155-133R0-01,33OHM,1%',
 TOLERANCE='1%',
 CLS_PN='G155-133R0-01',
 VALUE='33OHM',
 PRIM_FILE='./archive_libs/passive/resistor/chips/chips.prt';

PART_NAME
 R235 'RESISTOR-G155-14701-01,4.7KOHMA':;

SECTION_NUMBER 1
 '@TIMECARD_LIB.TIMECARD(SCH_1):PAGE522_I149@PASSIVE.RESISTOR(CHIPS)':
 C_PATH='@timecard_lib.timecard(sch_1):page522_i149@passive.resistor(chips)',
 P_PATH='@timecard_lib.timecard(sch_1):page15_i149@passive.resistor(chips)',
 PATH='I149',
 DRAWING='@TIMECARD_LIB.TIMECARD(SCH_1):PAGE522',
 PACKAGE='0402',
 PHYS_PAGE='15',
 XY='(-9400,6450)',
 ROT='0',
 VER='1',
 CDS_LIB='passive',
 CDS_PART_NAME='RESISTOR-G155-14701-01,4.7KOHMA',
 TOLERANCE='1%',
 CLS_PN='G155-14701-01',
 VALUE='4.7KOHM',
 PRIM_FILE='./archive_libs/passive/resistor/chips/chips.prt';

PART_NAME
 R236 'RESISTOR-G155-14701-01,4.7KOHMA':;

SECTION_NUMBER 1
 '@TIMECARD_LIB.TIMECARD(SCH_1):PAGE522_I156@PASSIVE.RESISTOR(CHIPS)':
 C_PATH='@timecard_lib.timecard(sch_1):page522_i156@passive.resistor(chips)',
 P_PATH='@timecard_lib.timecard(sch_1):page15_i156@passive.resistor(chips)',
 PATH='I156',
 DRAWING='@TIMECARD_LIB.TIMECARD(SCH_1):PAGE522',
 PACKAGE='0402',
 PHYS_PAGE='15',
 XY='(-9350,2900)',
 ROT='0',
 VER='1',
 CDS_LIB='passive',
 CDS_PART_NAME='RESISTOR-G155-14701-01,4.7KOHMA',
 TOLERANCE='1%',
 CLS_PN='G155-14701-01',
 VALUE='4.7KOHM',
 PRIM_FILE='./archive_libs/passive/resistor/chips/chips.prt';

PART_NAME
 R237 'RESISTOR-G155-11002-01,10KOHM,A':;

SECTION_NUMBER 1
 '@TIMECARD_LIB.TIMECARD(SCH_1):PAGE515_I56@PASSIVE.RESISTOR(CHIPS)':
 C_PATH='@timecard_lib.timecard(sch_1):page515_i56@passive.resistor(chips)',
 P_PATH='@timecard_lib.timecard(sch_1):page31_i56@passive.resistor(chips)',
 PATH='I56',
 DRAWING='@TIMECARD_LIB.TIMECARD(SCH_1):PAGE515',
 PACKAGE='0402',
 PHYS_PAGE='31',
 XY='(-9650,6250)',
 ROT='0',
 VER='2',
 CDS_LIB='passive',
 CDS_PART_NAME='RESISTOR-G155-11002-01,10KOHM,A',
 NO_ASSY='TRUE',
 TOLERANCE='1%',
 CLS_PN='G155-11002-01',
 VALUE='10KOHM',
 PRIM_FILE='./archive_libs/passive/resistor/chips/chips.prt';

PART_NAME
 R238 'RESISTOR-G155-133R0-01,33OHM,1%':;

SECTION_NUMBER 1
 '@TIMECARD_LIB.TIMECARD(SCH_1):PAGE161_I259@PASSIVE.RESISTOR(CHIPS)':
 C_PATH='@timecard_lib.timecard(sch_1):page161_i259@passive.resistor(chips)',
 P_PATH='@timecard_lib.timecard(sch_1):page11_i259@passive.resistor(chips)',
 PATH='I259',
 DRAWING='@TIMECARD_LIB.TIMECARD(SCH_1):PAGE161',
 PACKAGE='0402',
 PHYS_PAGE='11',
 XY='(-5350,8050)',
 ROT='0',
 VER='1',
 CDS_LIB='passive',
 CDS_PART_NAME='RESISTOR-G155-133R0-01,33OHM,1%',
 TOLERANCE='1%',
 CLS_PN='G155-133R0-01',
 VALUE='33OHM',
 PRIM_FILE='./archive_libs/passive/resistor/chips/chips.prt';

PART_NAME
 R239 'RESISTOR-G155-11500-01,150OHM,A':;

SECTION_NUMBER 1
 '@TIMECARD_LIB.TIMECARD(SCH_1):PAGE522_I169@PASSIVE.RESISTOR(CHIPS)':
 C_PATH='@timecard_lib.timecard(sch_1):page522_i169@passive.resistor(chips)',
 P_PATH='@timecard_lib.timecard(sch_1):page15_i169@passive.resistor(chips)',
 PATH='I169',
 DRAWING='@TIMECARD_LIB.TIMECARD(SCH_1):PAGE522',
 PACKAGE='0402',
 PHYS_PAGE='15',
 XY='(-7000,6150)',
 ROT='5',
 VER='1',
 CDS_LIB='passive',
 CDS_PART_NAME='RESISTOR-G155-11500-01,150OHM,A',
 NO_ASSY='TRUE',
 TOLERANCE='1%',
 CLS_PN='G155-11500-01',
 VALUE='150OHM',
 PRIM_FILE='./archive_libs/passive/resistor/chips/chips.prt';

PART_NAME
 R240 'RESISTOR-G155-11500-01,150OHM,A':;

SECTION_NUMBER 1
 '@TIMECARD_LIB.TIMECARD(SCH_1):PAGE522_I172@PASSIVE.RESISTOR(CHIPS)':
 C_PATH='@timecard_lib.timecard(sch_1):page522_i172@passive.resistor(chips)',
 P_PATH='@timecard_lib.timecard(sch_1):page15_i172@passive.resistor(chips)',
 PATH='I172',
 DRAWING='@TIMECARD_LIB.TIMECARD(SCH_1):PAGE522',
 PACKAGE='0402',
 PHYS_PAGE='15',
 XY='(-7000,2600)',
 ROT='5',
 VER='1',
 CDS_LIB='passive',
 CDS_PART_NAME='RESISTOR-G155-11500-01,150OHM,A',
 NO_ASSY='TRUE',
 TOLERANCE='1%',
 CLS_PN='G155-11500-01',
 VALUE='150OHM',
 PRIM_FILE='./archive_libs/passive/resistor/chips/chips.prt';

PART_NAME
 R241 'RESISTOR-G155-11500-01,150OHM,A':;

SECTION_NUMBER 1
 '@TIMECARD_LIB.TIMECARD(SCH_1):PAGE522_I170@PASSIVE.RESISTOR(CHIPS)':
 C_PATH='@timecard_lib.timecard(sch_1):page522_i170@passive.resistor(chips)',
 P_PATH='@timecard_lib.timecard(sch_1):page15_i170@passive.resistor(chips)',
 PATH='I170',
 DRAWING='@TIMECARD_LIB.TIMECARD(SCH_1):PAGE522',
 PACKAGE='0402',
 PHYS_PAGE='15',
 XY='(-6650,6150)',
 ROT='5',
 VER='1',
 CDS_LIB='passive',
 CDS_PART_NAME='RESISTOR-G155-11500-01,150OHM,A',
 NO_ASSY='TRUE',
 TOLERANCE='1%',
 CLS_PN='G155-11500-01',
 VALUE='150OHM',
 PRIM_FILE='./archive_libs/passive/resistor/chips/chips.prt';

PART_NAME
 R242 'RESISTOR-G155-11500-01,150OHM,A':;

SECTION_NUMBER 1
 '@TIMECARD_LIB.TIMECARD(SCH_1):PAGE522_I174@PASSIVE.RESISTOR(CHIPS)':
 C_PATH='@timecard_lib.timecard(sch_1):page522_i174@passive.resistor(chips)',
 P_PATH='@timecard_lib.timecard(sch_1):page15_i174@passive.resistor(chips)',
 PATH='I174',
 DRAWING='@TIMECARD_LIB.TIMECARD(SCH_1):PAGE522',
 PACKAGE='0402',
 PHYS_PAGE='15',
 XY='(-6650,2600)',
 ROT='5',
 VER='1',
 CDS_LIB='passive',
 CDS_PART_NAME='RESISTOR-G155-11500-01,150OHM,A',
 NO_ASSY='TRUE',
 TOLERANCE='1%',
 CLS_PN='G155-11500-01',
 VALUE='150OHM',
 PRIM_FILE='./archive_libs/passive/resistor/chips/chips.prt';

PART_NAME
 R243 'RESISTOR-G155-14701-01,4.7KOHMA':;

SECTION_NUMBER 1
 '@TIMECARD_LIB.TIMECARD(SCH_1):PAGE523_I44@PASSIVE.RESISTOR(CHIPS)':
 C_PATH='@timecard_lib.timecard(sch_1):page523_i44@passive.resistor(chips)',
 P_PATH='@timecard_lib.timecard(sch_1):page29_i44@passive.resistor(chips)',
 PATH='I44',
 DRAWING='@TIMECARD_LIB.TIMECARD(SCH_1):PAGE523',
 PACKAGE='0402',
 PHYS_PAGE='29',
 XY='(-13200,3350)',
 ROT='0',
 VER='2',
 CDS_LIB='passive',
 CDS_PART_NAME='RESISTOR-G155-14701-01,4.7KOHMA',
 TOLERANCE='1%',
 CLS_PN='G155-14701-01',
 VALUE='4.7KOHM',
 PRIM_FILE='./archive_libs/passive/resistor/chips/chips.prt';

PART_NAME
 R244 'RESISTOR-G155-100R0-J0,0OHM,-':;

SECTION_NUMBER 1
 '@TIMECARD_LIB.TIMECARD(SCH_1):PAGE523_I109@PASSIVE.RESISTOR(CHIPS)':
 C_PATH='@timecard_lib.timecard(sch_1):page523_i109@passive.resistor(chips)',
 P_PATH='@timecard_lib.timecard(sch_1):page29_i109@passive.resistor(chips)',
 PATH='I109',
 DRAWING='@TIMECARD_LIB.TIMECARD(SCH_1):PAGE523',
 PACKAGE='0402',
 PHYS_PAGE='29',
 XY='(-12600,4250)',
 ROT='0',
 VER='1',
 CDS_LIB='passive',
 CDS_PART_NAME='RESISTOR-G155-100R0-J0,0OHM,-',
 TOLERANCE='-',
 CLS_PN='G155-100R0-J0',
 VALUE='0OHM',
 PRIM_FILE='./archive_libs/passive/resistor/chips/chips.prt';

PART_NAME
 R245 'RESISTOR-G155-100R0-J0,0OHM,-':;

SECTION_NUMBER 1
 '@TIMECARD_LIB.TIMECARD(SCH_1):PAGE523_I104@PASSIVE.RESISTOR(CHIPS)':
 C_PATH='@timecard_lib.timecard(sch_1):page523_i104@passive.resistor(chips)',
 P_PATH='@timecard_lib.timecard(sch_1):page29_i104@passive.resistor(chips)',
 PATH='I104',
 DRAWING='@TIMECARD_LIB.TIMECARD(SCH_1):PAGE523',
 PACKAGE='0402',
 PHYS_PAGE='29',
 XY='(-12300,2500)',
 ROT='0',
 VER='1',
 CDS_LIB='passive',
 CDS_PART_NAME='RESISTOR-G155-100R0-J0,0OHM,-',
 TOLERANCE='-',
 CLS_PN='G155-100R0-J0',
 VALUE='0OHM',
 PRIM_FILE='./archive_libs/passive/resistor/chips/chips.prt';

PART_NAME
 R246 'RESISTOR-A155-05101-DL,5.1KOHMA':;

SECTION_NUMBER 1
 '@TIMECARD_LIB.TIMECARD(SCH_1):PAGE523_I51@PASSIVE.RESISTOR(CHIPS)':
 C_PATH='@timecard_lib.timecard(sch_1):page523_i51@passive.resistor(chips)',
 P_PATH='@timecard_lib.timecard(sch_1):page29_i51@passive.resistor(chips)',
 PATH='I51',
 DRAWING='@TIMECARD_LIB.TIMECARD(SCH_1):PAGE523',
 PACKAGE='0402',
 PHYS_PAGE='29',
 XY='(-12150,3850)',
 ROT='0',
 VER='2',
 CDS_LIB='passive',
 CDS_PART_NAME='RESISTOR-A155-05101-DL,5.1KOHMA',
 NO_ASSY='TRUE',
 TOLERANCE='1%',
 CLS_PN='A155-05101-DL',
 VALUE='5.1KOHM',
 PRIM_FILE='./archive_libs/passive/resistor/chips/chips.prt';

PART_NAME
 R247 'RESISTOR-G155-11002-01,10KOHM,A':;

SECTION_NUMBER 1
 '@TIMECARD_LIB.TIMECARD(SCH_1):PAGE523_I54@PASSIVE.RESISTOR(CHIPS)':
 C_PATH='@timecard_lib.timecard(sch_1):page523_i54@passive.resistor(chips)',
 P_PATH='@timecard_lib.timecard(sch_1):page29_i54@passive.resistor(chips)',
 PATH='I54',
 DRAWING='@TIMECARD_LIB.TIMECARD(SCH_1):PAGE523',
 PACKAGE='0402',
 PHYS_PAGE='29',
 XY='(-12000,4950)',
 ROT='0',
 VER='2',
 CDS_LIB='passive',
 CDS_PART_NAME='RESISTOR-G155-11002-01,10KOHM,A',
 NO_ASSY='TRUE',
 TOLERANCE='1%',
 CLS_PN='G155-11002-01',
 VALUE='10KOHM',
 PRIM_FILE='./archive_libs/passive/resistor/chips/chips.prt';

PART_NAME
 R248 'RESISTOR-G155-11003-01,100KOHMA':;

SECTION_NUMBER 1
 '@TIMECARD_LIB.TIMECARD(SCH_1):PAGE523_I15@PASSIVE.RESISTOR(CHIPS)':
 C_PATH='@timecard_lib.timecard(sch_1):page523_i15@passive.resistor(chips)',
 P_PATH='@timecard_lib.timecard(sch_1):page29_i15@passive.resistor(chips)',
 PATH='I15',
 DRAWING='@TIMECARD_LIB.TIMECARD(SCH_1):PAGE523',
 PACKAGE='0402',
 PHYS_PAGE='29',
 XY='(-10500,3350)',
 ROT='0',
 VER='2',
 CDS_LIB='passive',
 CDS_PART_NAME='RESISTOR-G155-11003-01,100KOHMA',
 TOLERANCE='1%',
 CLS_PN='G155-11003-01',
 VALUE='100KOHM',
 PRIM_FILE='./archive_libs/passive/resistor/chips/chips.prt';

PART_NAME
 R249 'RESISTOR-G155-14701-01,4.7KOHMA':;

SECTION_NUMBER 1
 '@TIMECARD_LIB.TIMECARD(SCH_1):PAGE523_I16@PASSIVE.RESISTOR(CHIPS)':
 C_PATH='@timecard_lib.timecard(sch_1):page523_i16@passive.resistor(chips)',
 P_PATH='@timecard_lib.timecard(sch_1):page29_i16@passive.resistor(chips)',
 PATH='I16',
 DRAWING='@TIMECARD_LIB.TIMECARD(SCH_1):PAGE523',
 PACKAGE='0402',
 PHYS_PAGE='29',
 XY='(-9850,3250)',
 ROT='0',
 VER='2',
 CDS_LIB='passive',
 CDS_PART_NAME='RESISTOR-G155-14701-01,4.7KOHMA',
 TOLERANCE='1%',
 CLS_PN='G155-14701-01',
 VALUE='4.7KOHM',
 PRIM_FILE='./archive_libs/passive/resistor/chips/chips.prt';

PART_NAME
 R250 'RESISTOR-G155-100R0-J0,0OHM,-':;

SECTION_NUMBER 1
 '@TIMECARD_LIB.TIMECARD(SCH_1):PAGE523_I23@PASSIVE.RESISTOR(CHIPS)':
 C_PATH='@timecard_lib.timecard(sch_1):page523_i23@passive.resistor(chips)',
 P_PATH='@timecard_lib.timecard(sch_1):page29_i23@passive.resistor(chips)',
 PATH='I23',
 DRAWING='@TIMECARD_LIB.TIMECARD(SCH_1):PAGE523',
 PACKAGE='0402',
 PHYS_PAGE='29',
 XY='(-6300,4550)',
 ROT='0',
 VER='1',
 CDS_LIB='passive',
 CDS_PART_NAME='RESISTOR-G155-100R0-J0,0OHM,-',
 TOLERANCE='-',
 CLS_PN='G155-100R0-J0',
 VALUE='0OHM',
 PRIM_FILE='./archive_libs/passive/resistor/chips/chips.prt';

PART_NAME
 R251 'RESISTOR-G155-03322-01,33.2KOHA':;

SECTION_NUMBER 1
 '@TIMECARD_LIB.TIMECARD(SCH_1):PAGE523_I56@PASSIVE.RESISTOR(CHIPS)':
 C_PATH='@timecard_lib.timecard(sch_1):page523_i56@passive.resistor(chips)',
 P_PATH='@timecard_lib.timecard(sch_1):page29_i56@passive.resistor(chips)',
 PATH='I56',
 DRAWING='@TIMECARD_LIB.TIMECARD(SCH_1):PAGE523',
 PACKAGE='0402',
 PHYS_PAGE='29',
 XY='(-4600,2900)',
 ROT='1',
 VER='1',
 CDS_LIB='passive',
 CDS_PART_NAME='RESISTOR-G155-03322-01,33.2KOHA',
 TOLERANCE='1%',
 CLS_PN='G155-03322-01',
 VALUE='33.2KOHM',
 PRIM_FILE='./archive_libs/passive/resistor/chips/chips.prt';

PART_NAME
 R252 'RESISTOR-G156-100R0-J0,0OHM,-':;

SECTION_NUMBER 1
 '@TIMECARD_LIB.TIMECARD(SCH_1):PAGE523_I57@PASSIVE.RESISTOR(CHIPS)':
 C_PATH='@timecard_lib.timecard(sch_1):page523_i57@passive.resistor(chips)',
 P_PATH='@timecard_lib.timecard(sch_1):page29_i57@passive.resistor(chips)',
 PATH='I57',
 DRAWING='@TIMECARD_LIB.TIMECARD(SCH_1):PAGE523',
 PACKAGE='0603',
 PHYS_PAGE='29',
 XY='(-4250,2900)',
 ROT='1',
 VER='1',
 CDS_LIB='passive',
 CDS_PART_NAME='RESISTOR-G156-100R0-J0,0OHM,-',
 NO_ASSY='TRUE',
 TOLERANCE='-',
 CLS_PN='G156-100R0-J0',
 VALUE='0OHM',
 PRIM_FILE='./archive_libs/passive/resistor/chips/chips.prt';

PART_NAME
 R253 'RESISTOR-G157-12R20-01,2.2OHM,A':;

SECTION_NUMBER 1
 '@TIMECARD_LIB.TIMECARD(SCH_1):PAGE523_I26@PASSIVE.RESISTOR(CHIPS)':
 C_PATH='@timecard_lib.timecard(sch_1):page523_i26@passive.resistor(chips)',
 P_PATH='@timecard_lib.timecard(sch_1):page29_i26@passive.resistor(chips)',
 PATH='I26',
 DRAWING='@TIMECARD_LIB.TIMECARD(SCH_1):PAGE523',
 PACKAGE='0805',
 PHYS_PAGE='29',
 XY='(-3150,4700)',
 ROT='0',
 VER='1',
 CDS_LIB='passive',
 CDS_PART_NAME='RESISTOR-G157-12R20-01,2.2OHM,A',
 NO_ASSY='TRUE',
 TOLERANCE='1%',
 CLS_PN='G157-12R20-01',
 VALUE='2.2OHM',
 PRIM_FILE='./archive_libs/passive/resistor/chips/chips.prt';

PART_NAME
 R254 'RESISTOR-G155-120R0-01,20OHM,1%':;

SECTION_NUMBER 1
 '@TIMECARD_LIB.TIMECARD(SCH_1):PAGE523_I30@PASSIVE.RESISTOR(CHIPS)':
 C_PATH='@timecard_lib.timecard(sch_1):page523_i30@passive.resistor(chips)',
 P_PATH='@timecard_lib.timecard(sch_1):page29_i30@passive.resistor(chips)',
 PATH='I30',
 DRAWING='@TIMECARD_LIB.TIMECARD(SCH_1):PAGE523',
 PACKAGE='0402',
 PHYS_PAGE='29',
 XY='(-2550,4050)',
 ROT='0',
 VER='2',
 CDS_LIB='passive',
 CDS_PART_NAME='RESISTOR-G155-120R0-01,20OHM,1%',
 TOLERANCE='1%',
 CLS_PN='G155-120R0-01',
 VALUE='20OHM',
 PRIM_FILE='./archive_libs/passive/resistor/chips/chips.prt';

PART_NAME
 R255 'RESISTOR-G155-02262-01,22.6K,1%':;

SECTION_NUMBER 1
 '@TIMECARD_LIB.TIMECARD(SCH_1):PAGE523_I29@PASSIVE.RESISTOR(CHIPS)':
 C_PATH='@timecard_lib.timecard(sch_1):page523_i29@passive.resistor(chips)',
 P_PATH='@timecard_lib.timecard(sch_1):page29_i29@passive.resistor(chips)',
 PATH='I29',
 DRAWING='@TIMECARD_LIB.TIMECARD(SCH_1):PAGE523',
 PACKAGE='0402',
 PHYS_PAGE='29',
 XY='(-2550,3600)',
 ROT='0',
 VER='2',
 CDS_LIB='passive',
 CDS_PART_NAME='RESISTOR-G155-02262-01,22.6K,1%',
 TOLERANCE='1%',
 CLS_PN='G155-02262-01',
 VALUE='22.6K',
 PRIM_FILE='./archive_libs/passive/resistor/chips/chips.prt';

PART_NAME
 R256 'RESISTOR-G155-11001-01,1KOHM,1%':;

SECTION_NUMBER 1
 '@TIMECARD_LIB.TIMECARD(SCH_1):PAGE14_I65@PASSIVE.RESISTOR(CHIPS)':
 C_PATH='@timecard_lib.timecard(sch_1):page14_i65@passive.resistor(chips)',
 P_PATH='@timecard_lib.timecard(sch_1):page26_i65@passive.resistor(chips)',
 PATH='I65',
 DRAWING='@TIMECARD_LIB.TIMECARD(SCH_1):PAGE14',
 PACKAGE='0402',
 PHYS_PAGE='26',
 XY='(-9650,8100)',
 ROT='0',
 VER='1',
 CDS_LIB='passive',
 CDS_PART_NAME='RESISTOR-G155-11001-01,1KOHM,1%',
 TOLERANCE='1%',
 CLS_PN='G155-11001-01',
 VALUE='1KOHM',
 PRIM_FILE='./archive_libs/passive/resistor/chips/chips.prt';

PART_NAME
 R257 'RESISTOR-G155-13300-01,330OHM,A':;

SECTION_NUMBER 1
 '@TIMECARD_LIB.TIMECARD(SCH_1):PAGE14_I67@PASSIVE.RESISTOR(CHIPS)':
 C_PATH='@timecard_lib.timecard(sch_1):page14_i67@passive.resistor(chips)',
 P_PATH='@timecard_lib.timecard(sch_1):page26_i67@passive.resistor(chips)',
 PATH='I67',
 DRAWING='@TIMECARD_LIB.TIMECARD(SCH_1):PAGE14',
 PACKAGE='0402',
 PHYS_PAGE='26',
 XY='(-8900,12400)',
 ROT='0',
 VER='1',
 CDS_LIB='passive',
 CDS_PART_NAME='RESISTOR-G155-13300-01,330OHM,A',
 TOLERANCE='1%',
 CLS_PN='G155-13300-01',
 VALUE='330OHM',
 PRIM_FILE='./archive_libs/passive/resistor/chips/chips.prt';

PART_NAME
 R258 'RESISTOR-G155-13300-01,330OHM,A':;

SECTION_NUMBER 1
 '@TIMECARD_LIB.TIMECARD(SCH_1):PAGE14_I68@PASSIVE.RESISTOR(CHIPS)':
 C_PATH='@timecard_lib.timecard(sch_1):page14_i68@passive.resistor(chips)',
 P_PATH='@timecard_lib.timecard(sch_1):page26_i68@passive.resistor(chips)',
 PATH='I68',
 DRAWING='@TIMECARD_LIB.TIMECARD(SCH_1):PAGE14',
 PACKAGE='0402',
 PHYS_PAGE='26',
 XY='(-8900,12050)',
 ROT='0',
 VER='1',
 CDS_LIB='passive',
 CDS_PART_NAME='RESISTOR-G155-13300-01,330OHM,A',
 TOLERANCE='1%',
 CLS_PN='G155-13300-01',
 VALUE='330OHM',
 PRIM_FILE='./archive_libs/passive/resistor/chips/chips.prt';

PART_NAME
 R259 'RESISTOR-G155-13300-01,330OHM,A':;

SECTION_NUMBER 1
 '@TIMECARD_LIB.TIMECARD(SCH_1):PAGE14_I69@PASSIVE.RESISTOR(CHIPS)':
 C_PATH='@timecard_lib.timecard(sch_1):page14_i69@passive.resistor(chips)',
 P_PATH='@timecard_lib.timecard(sch_1):page26_i69@passive.resistor(chips)',
 PATH='I69',
 DRAWING='@TIMECARD_LIB.TIMECARD(SCH_1):PAGE14',
 PACKAGE='0402',
 PHYS_PAGE='26',
 XY='(-8900,11700)',
 ROT='0',
 VER='1',
 CDS_LIB='passive',
 CDS_PART_NAME='RESISTOR-G155-13300-01,330OHM,A',
 TOLERANCE='1%',
 CLS_PN='G155-13300-01',
 VALUE='330OHM',
 PRIM_FILE='./archive_libs/passive/resistor/chips/chips.prt';

PART_NAME
 R260 'RESISTOR-G155-11001-01,1KOHM,1%':;

SECTION_NUMBER 1
 '@TIMECARD_LIB.TIMECARD(SCH_1):PAGE515_I67@PASSIVE.RESISTOR(CHIPS)':
 C_PATH='@timecard_lib.timecard(sch_1):page515_i67@passive.resistor(chips)',
 P_PATH='@timecard_lib.timecard(sch_1):page31_i67@passive.resistor(chips)',
 PATH='I67',
 DRAWING='@TIMECARD_LIB.TIMECARD(SCH_1):PAGE515',
 PACKAGE='0402',
 PHYS_PAGE='31',
 XY='(-8600,7150)',
 ROT='0',
 VER='2',
 CDS_LIB='passive',
 CDS_PART_NAME='RESISTOR-G155-11001-01,1KOHM,1%',
 NO_ASSY='TRUE',
 TOLERANCE='1%',
 CLS_PN='G155-11001-01',
 VALUE='1KOHM',
 PRIM_FILE='./archive_libs/passive/resistor/chips/chips.prt';

PART_NAME
 R261 'RESISTOR-G155-13300-01,330OHM,A':;

SECTION_NUMBER 1
 '@TIMECARD_LIB.TIMECARD(SCH_1):PAGE14_I70@PASSIVE.RESISTOR(CHIPS)':
 C_PATH='@timecard_lib.timecard(sch_1):page14_i70@passive.resistor(chips)',
 P_PATH='@timecard_lib.timecard(sch_1):page26_i70@passive.resistor(chips)',
 PATH='I70',
 DRAWING='@TIMECARD_LIB.TIMECARD(SCH_1):PAGE14',
 PACKAGE='0402',
 PHYS_PAGE='26',
 XY='(-8900,11350)',
 ROT='0',
 VER='1',
 CDS_LIB='passive',
 CDS_PART_NAME='RESISTOR-G155-13300-01,330OHM,A',
 TOLERANCE='1%',
 CLS_PN='G155-13300-01',
 VALUE='330OHM',
 PRIM_FILE='./archive_libs/passive/resistor/chips/chips.prt';

PART_NAME
 R262 'RESISTOR-G155-11001-01,1KOHM,1%':;

SECTION_NUMBER 1
 '@TIMECARD_LIB.TIMECARD(SCH_1):PAGE14_I66@PASSIVE.RESISTOR(CHIPS)':
 C_PATH='@timecard_lib.timecard(sch_1):page14_i66@passive.resistor(chips)',
 P_PATH='@timecard_lib.timecard(sch_1):page26_i66@passive.resistor(chips)',
 PATH='I66',
 DRAWING='@TIMECARD_LIB.TIMECARD(SCH_1):PAGE14',
 PACKAGE='0402',
 PHYS_PAGE='26',
 XY='(-8750,8100)',
 ROT='0',
 VER='1',
 CDS_LIB='passive',
 CDS_PART_NAME='RESISTOR-G155-11001-01,1KOHM,1%',
 TOLERANCE='1%',
 CLS_PN='G155-11001-01',
 VALUE='1KOHM',
 PRIM_FILE='./archive_libs/passive/resistor/chips/chips.prt';

PART_NAME
 R263 'RESISTOR-G155-100R0-J0,0OHM,-':;

SECTION_NUMBER 1
 '@TIMECARD_LIB.TIMECARD(SCH_1):PAGE517_I47@PASSIVE.RESISTOR(CHIPS)':
 C_PATH='@timecard_lib.timecard(sch_1):page517_i47@passive.resistor(chips)',
 P_PATH='@timecard_lib.timecard(sch_1):page28_i47@passive.resistor(chips)',
 PATH='I47',
 DRAWING='@TIMECARD_LIB.TIMECARD(SCH_1):PAGE517',
 PACKAGE='0402',
 PHYS_PAGE='28',
 XY='(-11350,4100)',
 ROT='0',
 VER='1',
 CDS_LIB='passive',
 CDS_PART_NAME='RESISTOR-G155-100R0-J0,0OHM,-',
 TOLERANCE='-',
 CLS_PN='G155-100R0-J0',
 VALUE='0OHM',
 PRIM_FILE='./archive_libs/passive/resistor/chips/chips.prt';

PART_NAME
 R264 'RESISTOR-G155-11003-01,100KOHMA':;

SECTION_NUMBER 1
 '@TIMECARD_LIB.TIMECARD(SCH_1):PAGE527_I222@PASSIVE.RESISTOR(CHIPS)':
 C_PATH='@timecard_lib.timecard(sch_1):page527_i222@passive.resistor(chips)',
 P_PATH='@timecard_lib.timecard(sch_1):page21_i222@passive.resistor(chips)',
 PATH='I222',
 DRAWING='@TIMECARD_LIB.TIMECARD(SCH_1):PAGE527',
 PACKAGE='0402',
 PHYS_PAGE='21',
 XY='(-9100,2500)',
 ROT='1',
 VER='2',
 CDS_LIB='passive',
 CDS_PART_NAME='RESISTOR-G155-11003-01,100KOHMA',
 TOLERANCE='1%',
 CLS_PN='G155-11003-01',
 VALUE='100KOHM',
 PRIM_FILE='./archive_libs/passive/resistor/chips/chips.prt';

PART_NAME
 R265 'RESISTOR-G155-11003-01,100KOHMA':;

SECTION_NUMBER 1
 '@TIMECARD_LIB.TIMECARD(SCH_1):PAGE527_I221@PASSIVE.RESISTOR(CHIPS)':
 C_PATH='@timecard_lib.timecard(sch_1):page527_i221@passive.resistor(chips)',
 P_PATH='@timecard_lib.timecard(sch_1):page21_i221@passive.resistor(chips)',
 PATH='I221',
 DRAWING='@TIMECARD_LIB.TIMECARD(SCH_1):PAGE527',
 PACKAGE='0402',
 PHYS_PAGE='21',
 XY='(-9100,2400)',
 ROT='1',
 VER='2',
 CDS_LIB='passive',
 CDS_PART_NAME='RESISTOR-G155-11003-01,100KOHMA',
 TOLERANCE='1%',
 CLS_PN='G155-11003-01',
 VALUE='100KOHM',
 PRIM_FILE='./archive_libs/passive/resistor/chips/chips.prt';

PART_NAME
 R266 'RESISTOR-G155-133R0-01,33OHM,1%':
 SIGNAL_MODEL='DEFAULT_RESISTOR_33OHM_2_1';

SECTION_NUMBER 1
 '@TIMECARD_LIB.TIMECARD(SCH_1):PAGE527_I204@PASSIVE.RESISTOR(CHIPS)':
 C_PATH='@timecard_lib.timecard(sch_1):page527_i204@passive.resistor(chips)',
 P_PATH='@timecard_lib.timecard(sch_1):page21_i204@passive.resistor(chips)',
 PATH='I204',
 DRAWING='@TIMECARD_LIB.TIMECARD(SCH_1):PAGE527',
 PACKAGE='0402',
 PHYS_PAGE='21',
 XY='(-4150,100)',
 ROT='0',
 VER='1',
 CDS_LIB='passive',
 CDS_PART_NAME='RESISTOR-G155-133R0-01,33OHM,1%',
 NO_ASSY='TRUE',
 TOLERANCE='1%',
 CLS_PN='G155-133R0-01',
 SIGNAL_MODEL='DEFAULT_RESISTOR_33OHM_2_1',
 VALUE='33OHM',
 PRIM_FILE='./archive_libs/passive/resistor/chips/chips.prt';

PART_NAME
 R267 'RESISTOR-G155-133R0-01,33OHM,1%':
 SIGNAL_MODEL='DEFAULT_RESISTOR_33OHM_2_1';

SECTION_NUMBER 1
 '@TIMECARD_LIB.TIMECARD(SCH_1):PAGE527_I206@PASSIVE.RESISTOR(CHIPS)':
 C_PATH='@timecard_lib.timecard(sch_1):page527_i206@passive.resistor(chips)',
 P_PATH='@timecard_lib.timecard(sch_1):page21_i206@passive.resistor(chips)',
 PATH='I206',
 DRAWING='@TIMECARD_LIB.TIMECARD(SCH_1):PAGE527',
 PACKAGE='0402',
 PHYS_PAGE='21',
 XY='(1300,3800)',
 ROT='0',
 VER='1',
 CDS_LIB='passive',
 CDS_PART_NAME='RESISTOR-G155-133R0-01,33OHM,1%',
 TOLERANCE='1%',
 CLS_PN='G155-133R0-01',
 SIGNAL_MODEL='DEFAULT_RESISTOR_33OHM_2_1',
 VALUE='33OHM',
 PRIM_FILE='./archive_libs/passive/resistor/chips/chips.prt';

PART_NAME
 R268 'RESISTOR-G155-11003-01,100KOHMA':;

SECTION_NUMBER 1
 '@TIMECARD_LIB.TIMECARD(SCH_1):PAGE11_I38@PASSIVE.RESISTOR(CHIPS)':
 C_PATH='@timecard_lib.timecard(sch_1):page11_i38@passive.resistor(chips)',
 P_PATH='@timecard_lib.timecard(sch_1):page22_i38@passive.resistor(chips)',
 PATH='I38',
 DRAWING='@TIMECARD_LIB.TIMECARD(SCH_1):PAGE11',
 PACKAGE='0402',
 PHYS_PAGE='22',
 XY='(-7350,6400)',
 ROT='1',
 VER='2',
 CDS_LIB='passive',
 CDS_PART_NAME='RESISTOR-G155-11003-01,100KOHMA',
 TOLERANCE='1%',
 CLS_PN='G155-11003-01',
 VALUE='100KOHM',
 PRIM_FILE='./archive_libs/passive/resistor/chips/chips.prt';

PART_NAME
 R269 'RESISTOR-G155-11003-01,100KOHMA':;

SECTION_NUMBER 1
 '@TIMECARD_LIB.TIMECARD(SCH_1):PAGE11_I40@PASSIVE.RESISTOR(CHIPS)':
 C_PATH='@timecard_lib.timecard(sch_1):page11_i40@passive.resistor(chips)',
 P_PATH='@timecard_lib.timecard(sch_1):page22_i40@passive.resistor(chips)',
 PATH='I40',
 DRAWING='@TIMECARD_LIB.TIMECARD(SCH_1):PAGE11',
 PACKAGE='0402',
 PHYS_PAGE='22',
 XY='(-7350,6300)',
 ROT='1',
 VER='2',
 CDS_LIB='passive',
 CDS_PART_NAME='RESISTOR-G155-11003-01,100KOHMA',
 TOLERANCE='1%',
 CLS_PN='G155-11003-01',
 VALUE='100KOHM',
 PRIM_FILE='./archive_libs/passive/resistor/chips/chips.prt';

PART_NAME
 R270 'RESISTOR-G155-14701-01,4.7KOHMA':;

SECTION_NUMBER 1
 '@TIMECARD_LIB.TIMECARD(SCH_1):PAGE161_I140@PASSIVE.RESISTOR(CHIPS)':
 C_PATH='@timecard_lib.timecard(sch_1):page161_i140@passive.resistor(chips)',
 P_PATH='@timecard_lib.timecard(sch_1):page11_i140@passive.resistor(chips)',
 PATH='I140',
 DRAWING='@TIMECARD_LIB.TIMECARD(SCH_1):PAGE161',
 PACKAGE='0402',
 PHYS_PAGE='11',
 XY='(-12600,7300)',
 ROT='1',
 VER='2',
 CDS_LIB='passive',
 CDS_PART_NAME='RESISTOR-G155-14701-01,4.7KOHMA',
 TOLERANCE='1%',
 CLS_PN='G155-14701-01',
 VALUE='4.7KOHM',
 PRIM_FILE='./archive_libs/passive/resistor/chips/chips.prt';

PART_NAME
 R271 'RESISTOR-G155-14701-01,4.7KOHMA':;

SECTION_NUMBER 1
 '@TIMECARD_LIB.TIMECARD(SCH_1):PAGE161_I200@PASSIVE.RESISTOR(CHIPS)':
 C_PATH='@timecard_lib.timecard(sch_1):page161_i200@passive.resistor(chips)',
 P_PATH='@timecard_lib.timecard(sch_1):page11_i200@passive.resistor(chips)',
 PATH='I200',
 DRAWING='@TIMECARD_LIB.TIMECARD(SCH_1):PAGE161',
 PACKAGE='0402',
 PHYS_PAGE='11',
 XY='(-12600,7200)',
 ROT='1',
 VER='2',
 LOCATION='R271',
 CDS_LIB='passive',
 CDS_PART_NAME='RESISTOR-G155-14701-01,4.7KOHMA',
 NO_ASSY='TRUE',
 TOLERANCE='1%',
 CLS_PN='G155-14701-01',
 VALUE='4.7KOHM',
 PRIM_FILE='./archive_libs/passive/resistor/chips/chips.prt';

PART_NAME
 R272 'RESISTOR-G155-11000-01,100OHM,A':;

SECTION_NUMBER 1
 '@TIMECARD_LIB.TIMECARD(SCH_1):PAGE14_I163@PASSIVE.RESISTOR(CHIPS)':
 C_PATH='@timecard_lib.timecard(sch_1):page14_i163@passive.resistor(chips)',
 P_PATH='@timecard_lib.timecard(sch_1):page26_i163@passive.resistor(chips)',
 PATH='I163',
 DRAWING='@TIMECARD_LIB.TIMECARD(SCH_1):PAGE14',
 PACKAGE='0402',
 PHYS_PAGE='26',
 XY='(-2800,10900)',
 ROT='0',
 VER='1',
 CDS_LIB='passive',
 CDS_PART_NAME='RESISTOR-G155-11000-01,100OHM,A',
 NO_ASSY='TRUE',
 TOLERANCE='1%',
 CLS_PN='G155-11000-01',
 VALUE='100OHM',
 PRIM_FILE='./archive_libs/passive/resistor/chips/chips.prt';

PART_NAME
 R273 'RESISTOR-G155-11000-01,100OHM,A':;

SECTION_NUMBER 1
 '@TIMECARD_LIB.TIMECARD(SCH_1):PAGE14_I165@PASSIVE.RESISTOR(CHIPS)':
 C_PATH='@timecard_lib.timecard(sch_1):page14_i165@passive.resistor(chips)',
 P_PATH='@timecard_lib.timecard(sch_1):page26_i165@passive.resistor(chips)',
 PATH='I165',
 DRAWING='@TIMECARD_LIB.TIMECARD(SCH_1):PAGE14',
 PACKAGE='0402',
 PHYS_PAGE='26',
 XY='(-2800,9100)',
 ROT='0',
 VER='1',
 CDS_LIB='passive',
 CDS_PART_NAME='RESISTOR-G155-11000-01,100OHM,A',
 NO_ASSY='TRUE',
 TOLERANCE='1%',
 CLS_PN='G155-11000-01',
 VALUE='100OHM',
 PRIM_FILE='./archive_libs/passive/resistor/chips/chips.prt';

PART_NAME
 R274 'RESISTOR-G155-11000-01,100OHM,A':;

SECTION_NUMBER 1
 '@TIMECARD_LIB.TIMECARD(SCH_1):PAGE14_I171@PASSIVE.RESISTOR(CHIPS)':
 C_PATH='@timecard_lib.timecard(sch_1):page14_i171@passive.resistor(chips)',
 P_PATH='@timecard_lib.timecard(sch_1):page26_i171@passive.resistor(chips)',
 PATH='I171',
 DRAWING='@TIMECARD_LIB.TIMECARD(SCH_1):PAGE14',
 PACKAGE='0402',
 PHYS_PAGE='26',
 XY='(-2800,9700)',
 ROT='0',
 VER='1',
 CDS_LIB='passive',
 CDS_PART_NAME='RESISTOR-G155-11000-01,100OHM,A',
 NO_ASSY='TRUE',
 TOLERANCE='1%',
 CLS_PN='G155-11000-01',
 VALUE='100OHM',
 PRIM_FILE='./archive_libs/passive/resistor/chips/chips.prt';

PART_NAME
 R275 'RESISTOR-G155-11000-01,100OHM,A':;

SECTION_NUMBER 1
 '@TIMECARD_LIB.TIMECARD(SCH_1):PAGE163_I39@PASSIVE.RESISTOR(CHIPS)':
 C_PATH='@timecard_lib.timecard(sch_1):page163_i39@passive.resistor(chips)',
 P_PATH='@timecard_lib.timecard(sch_1):page13_i39@passive.resistor(chips)',
 PATH='I39',
 DRAWING='@TIMECARD_LIB.TIMECARD(SCH_1):PAGE163',
 PACKAGE='0402',
 PHYS_PAGE='13',
 XY='(-5550,6850)',
 ROT='0',
 VER='1',
 CDS_LIB='passive',
 CDS_PART_NAME='RESISTOR-G155-11000-01,100OHM,A',
 NO_ASSY='TRUE',
 TOLERANCE='1%',
 CLS_PN='G155-11000-01',
 VALUE='100OHM',
 PRIM_FILE='./archive_libs/passive/resistor/chips/chips.prt';

PART_NAME
 R276 'RESISTOR-G155-11000-01,100OHM,A':;

SECTION_NUMBER 1
 '@TIMECARD_LIB.TIMECARD(SCH_1):PAGE163_I38@PASSIVE.RESISTOR(CHIPS)':
 C_PATH='@timecard_lib.timecard(sch_1):page163_i38@passive.resistor(chips)',
 P_PATH='@timecard_lib.timecard(sch_1):page13_i38@passive.resistor(chips)',
 PATH='I38',
 DRAWING='@TIMECARD_LIB.TIMECARD(SCH_1):PAGE163',
 PACKAGE='0402',
 PHYS_PAGE='13',
 XY='(-5450,6250)',
 ROT='0',
 VER='1',
 CDS_LIB='passive',
 CDS_PART_NAME='RESISTOR-G155-11000-01,100OHM,A',
 NO_ASSY='TRUE',
 TOLERANCE='1%',
 CLS_PN='G155-11000-01',
 VALUE='100OHM',
 PRIM_FILE='./archive_libs/passive/resistor/chips/chips.prt';

PART_NAME
 R277 'RESISTOR-G155-11000-01,100OHM,A':;

SECTION_NUMBER 1
 '@TIMECARD_LIB.TIMECARD(SCH_1):PAGE163_I37@PASSIVE.RESISTOR(CHIPS)':
 C_PATH='@timecard_lib.timecard(sch_1):page163_i37@passive.resistor(chips)',
 P_PATH='@timecard_lib.timecard(sch_1):page13_i37@passive.resistor(chips)',
 PATH='I37',
 DRAWING='@TIMECARD_LIB.TIMECARD(SCH_1):PAGE163',
 PACKAGE='0402',
 PHYS_PAGE='13',
 XY='(-5450,5850)',
 ROT='0',
 VER='1',
 CDS_LIB='passive',
 CDS_PART_NAME='RESISTOR-G155-11000-01,100OHM,A',
 NO_ASSY='TRUE',
 TOLERANCE='1%',
 CLS_PN='G155-11000-01',
 VALUE='100OHM',
 PRIM_FILE='./archive_libs/passive/resistor/chips/chips.prt';

PART_NAME
 R278 'RESISTOR-G155-11000-01,100OHM,A':;

SECTION_NUMBER 1
 '@TIMECARD_LIB.TIMECARD(SCH_1):PAGE163_I36@PASSIVE.RESISTOR(CHIPS)':
 C_PATH='@timecard_lib.timecard(sch_1):page163_i36@passive.resistor(chips)',
 P_PATH='@timecard_lib.timecard(sch_1):page13_i36@passive.resistor(chips)',
 PATH='I36',
 DRAWING='@TIMECARD_LIB.TIMECARD(SCH_1):PAGE163',
 PACKAGE='0402',
 PHYS_PAGE='13',
 XY='(-5600,5250)',
 ROT='0',
 VER='1',
 CDS_LIB='passive',
 CDS_PART_NAME='RESISTOR-G155-11000-01,100OHM,A',
 TOLERANCE='1%',
 CLS_PN='G155-11000-01',
 VALUE='100OHM',
 PRIM_FILE='./archive_libs/passive/resistor/chips/chips.prt';

PART_NAME
 R279 'RESISTOR-G155-13300-01,330OHM,A':;

SECTION_NUMBER 1
 '@TIMECARD_LIB.TIMECARD(SCH_1):PAGE14_I72@PASSIVE.RESISTOR(CHIPS)':
 C_PATH='@timecard_lib.timecard(sch_1):page14_i72@passive.resistor(chips)',
 P_PATH='@timecard_lib.timecard(sch_1):page26_i72@passive.resistor(chips)',
 PATH='I72',
 DRAWING='@TIMECARD_LIB.TIMECARD(SCH_1):PAGE14',
 PACKAGE='0402',
 PHYS_PAGE='26',
 XY='(-8900,10950)',
 ROT='0',
 VER='1',
 CDS_LIB='passive',
 CDS_PART_NAME='RESISTOR-G155-13300-01,330OHM,A',
 TOLERANCE='1%',
 CLS_PN='G155-13300-01',
 VALUE='330OHM',
 PRIM_FILE='./archive_libs/passive/resistor/chips/chips.prt';

PART_NAME
 R280 'RESISTOR-G155-13300-01,330OHM,A':;

SECTION_NUMBER 1
 '@TIMECARD_LIB.TIMECARD(SCH_1):PAGE14_I74@PASSIVE.RESISTOR(CHIPS)':
 C_PATH='@timecard_lib.timecard(sch_1):page14_i74@passive.resistor(chips)',
 P_PATH='@timecard_lib.timecard(sch_1):page26_i74@passive.resistor(chips)',
 PATH='I74',
 DRAWING='@TIMECARD_LIB.TIMECARD(SCH_1):PAGE14',
 PACKAGE='0402',
 PHYS_PAGE='26',
 XY='(-8900,10650)',
 ROT='0',
 VER='1',
 CDS_LIB='passive',
 CDS_PART_NAME='RESISTOR-G155-13300-01,330OHM,A',
 TOLERANCE='1%',
 CLS_PN='G155-13300-01',
 VALUE='330OHM',
 PRIM_FILE='./archive_libs/passive/resistor/chips/chips.prt';

PART_NAME
 R281 'RESISTOR-G155-14701-01,4.7KOHMA':;

SECTION_NUMBER 1
 '@TIMECARD_LIB.TIMECARD(SCH_1):PAGE8_I70@PASSIVE.RESISTOR(CHIPS)':
 C_PATH='@timecard_lib.timecard(sch_1):page8_i70@passive.resistor(chips)',
 P_PATH='@timecard_lib.timecard(sch_1):page19_i70@passive.resistor(chips)',
 PATH='I70',
 DRAWING='@TIMECARD_LIB.TIMECARD(SCH_1):PAGE8',
 PACKAGE='0402',
 PHYS_PAGE='19',
 XY='(-10000,6600)',
 ROT='0',
 VER='2',
 CDS_LIB='passive',
 CDS_PART_NAME='RESISTOR-G155-14701-01,4.7KOHMA',
 TOLERANCE='1%',
 CLS_PN='G155-14701-01',
 VALUE='4.7KOHM',
 PRIM_FILE='./archive_libs/passive/resistor/chips/chips.prt';

PART_NAME
 R282 'RESISTOR-G155-14701-01,4.7KOHMA':;

SECTION_NUMBER 1
 '@TIMECARD_LIB.TIMECARD(SCH_1):PAGE8_I69@PASSIVE.RESISTOR(CHIPS)':
 C_PATH='@timecard_lib.timecard(sch_1):page8_i69@passive.resistor(chips)',
 P_PATH='@timecard_lib.timecard(sch_1):page19_i69@passive.resistor(chips)',
 PATH='I69',
 DRAWING='@TIMECARD_LIB.TIMECARD(SCH_1):PAGE8',
 PACKAGE='0402',
 PHYS_PAGE='19',
 XY='(-9550,6600)',
 ROT='0',
 VER='2',
 CDS_LIB='passive',
 CDS_PART_NAME='RESISTOR-G155-14701-01,4.7KOHMA',
 TOLERANCE='1%',
 CLS_PN='G155-14701-01',
 VALUE='4.7KOHM',
 PRIM_FILE='./archive_libs/passive/resistor/chips/chips.prt';

PART_NAME
 R283 'RESISTOR-G155-11002-01,10KOHM,A':;

SECTION_NUMBER 1
 '@TIMECARD_LIB.TIMECARD(SCH_1):PAGE16_I1609@PASSIVE.RESISTOR(CHIPS)':
 C_PATH='@timecard_lib.timecard(sch_1):page16_i1609@passive.resistor(chips)',
 P_PATH='@timecard_lib.timecard(sch_1):page25_i1609@passive.resistor(chips)',
 PATH='I1609',
 DRAWING='@TIMECARD_LIB.TIMECARD(SCH_1):PAGE16',
 PACKAGE='0402',
 PHYS_PAGE='25',
 XY='(-12350,3500)',
 ROT='0',
 VER='1',
 CDS_LIB='passive',
 CDS_PART_NAME='RESISTOR-G155-11002-01,10KOHM,A',
 TOLERANCE='1%',
 CLS_PN='G155-11002-01',
 VALUE='10KOHM',
 PRIM_FILE='./archive_libs/passive/resistor/chips/chips.prt';

PART_NAME
 R284 'RESISTOR-G155-14701-01,4.7KOHMA':;

SECTION_NUMBER 1
 '@TIMECARD_LIB.TIMECARD(SCH_1):PAGE16_I1547@PASSIVE.RESISTOR(CHIPS)':
 C_PATH='@timecard_lib.timecard(sch_1):page16_i1547@passive.resistor(chips)',
 P_PATH='@timecard_lib.timecard(sch_1):page25_i1547@passive.resistor(chips)',
 PATH='I1547',
 DRAWING='@TIMECARD_LIB.TIMECARD(SCH_1):PAGE16',
 PACKAGE='0402',
 PHYS_PAGE='25',
 XY='(-12350,3400)',
 ROT='1',
 VER='2',
 CDS_LIB='passive',
 CDS_PART_NAME='RESISTOR-G155-14701-01,4.7KOHMA',
 NO_ASSY='TRUE',
 TOLERANCE='1%',
 CLS_PN='G155-14701-01',
 VALUE='4.7KOHM',
 PRIM_FILE='./archive_libs/passive/resistor/chips/chips.prt';

PART_NAME
 R285 'RESISTOR-G155-11002-01,10KOHM,A':;

SECTION_NUMBER 1
 '@TIMECARD_LIB.TIMECARD(SCH_1):PAGE16_I1606@PASSIVE.RESISTOR(CHIPS)':
 C_PATH='@timecard_lib.timecard(sch_1):page16_i1606@passive.resistor(chips)',
 P_PATH='@timecard_lib.timecard(sch_1):page25_i1606@passive.resistor(chips)',
 PATH='I1606',
 DRAWING='@TIMECARD_LIB.TIMECARD(SCH_1):PAGE16',
 PACKAGE='0402',
 PHYS_PAGE='25',
 XY='(-12350,3200)',
 ROT='0',
 VER='1',
 CDS_LIB='passive',
 CDS_PART_NAME='RESISTOR-G155-11002-01,10KOHM,A',
 TOLERANCE='1%',
 CLS_PN='G155-11002-01',
 VALUE='10KOHM',
 PRIM_FILE='./archive_libs/passive/resistor/chips/chips.prt';

PART_NAME
 R286 'RESISTOR-G155-14701-01,4.7KOHMA':;

SECTION_NUMBER 1
 '@TIMECARD_LIB.TIMECARD(SCH_1):PAGE16_I1549@PASSIVE.RESISTOR(CHIPS)':
 C_PATH='@timecard_lib.timecard(sch_1):page16_i1549@passive.resistor(chips)',
 P_PATH='@timecard_lib.timecard(sch_1):page25_i1549@passive.resistor(chips)',
 PATH='I1549',
 DRAWING='@TIMECARD_LIB.TIMECARD(SCH_1):PAGE16',
 PACKAGE='0402',
 PHYS_PAGE='25',
 XY='(-12350,3100)',
 ROT='1',
 VER='2',
 CDS_LIB='passive',
 CDS_PART_NAME='RESISTOR-G155-14701-01,4.7KOHMA',
 NO_ASSY='TRUE',
 TOLERANCE='1%',
 CLS_PN='G155-14701-01',
 VALUE='4.7KOHM',
 PRIM_FILE='./archive_libs/passive/resistor/chips/chips.prt';

PART_NAME
 R287 'RESISTOR-G155-14701-01,4.7KOHMA':;

SECTION_NUMBER 1
 '@TIMECARD_LIB.TIMECARD(SCH_1):PAGE527_I211@PASSIVE.RESISTOR(CHIPS)':
 C_PATH='@timecard_lib.timecard(sch_1):page527_i211@passive.resistor(chips)',
 P_PATH='@timecard_lib.timecard(sch_1):page21_i211@passive.resistor(chips)',
 PATH='I211',
 DRAWING='@TIMECARD_LIB.TIMECARD(SCH_1):PAGE527',
 PACKAGE='0402',
 PHYS_PAGE='21',
 XY='(-1950,6700)',
 ROT='0',
 VER='1',
 CDS_LIB='passive',
 CDS_PART_NAME='RESISTOR-G155-14701-01,4.7KOHMA',
 TOLERANCE='1%',
 CLS_PN='G155-14701-01',
 VALUE='4.7KOHM',
 PRIM_FILE='./archive_libs/passive/resistor/chips/chips.prt';

PART_NAME
 R288 'RESISTOR-G155-14701-01,4.7KOHMA':;

SECTION_NUMBER 1
 '@TIMECARD_LIB.TIMECARD(SCH_1):PAGE161_I201@PASSIVE.RESISTOR(CHIPS)':
 C_PATH='@timecard_lib.timecard(sch_1):page161_i201@passive.resistor(chips)',
 P_PATH='@timecard_lib.timecard(sch_1):page11_i201@passive.resistor(chips)',
 PATH='I201',
 DRAWING='@TIMECARD_LIB.TIMECARD(SCH_1):PAGE161',
 PACKAGE='0402',
 PHYS_PAGE='11',
 XY='(-12600,6900)',
 ROT='1',
 VER='2',
 LOCATION='R288',
 CDS_LIB='passive',
 CDS_PART_NAME='RESISTOR-G155-14701-01,4.7KOHMA',
 TOLERANCE='1%',
 CLS_PN='G155-14701-01',
 VALUE='4.7KOHM',
 PRIM_FILE='./archive_libs/passive/resistor/chips/chips.prt';

PART_NAME
 R289 'RESISTOR-G155-14701-01,4.7KOHMA':;

SECTION_NUMBER 1
 '@TIMECARD_LIB.TIMECARD(SCH_1):PAGE9_I38@PASSIVE.RESISTOR(CHIPS)':
 C_PATH='@timecard_lib.timecard(sch_1):page9_i38@passive.resistor(chips)',
 P_PATH='@timecard_lib.timecard(sch_1):page20_i38@passive.resistor(chips)',
 PATH='I38',
 DRAWING='@TIMECARD_LIB.TIMECARD(SCH_1):PAGE9',
 PACKAGE='0402',
 PHYS_PAGE='20',
 XY='(-10700,10700)',
 ROT='0',
 VER='2',
 LOCATION='R289',
 CDS_LIB='passive',
 CDS_PART_NAME='RESISTOR-G155-14701-01,4.7KOHMA',
 TOLERANCE='1%',
 CLS_PN='G155-14701-01',
 VALUE='4.7KOHM',
 PRIM_FILE='./archive_libs/passive/resistor/chips/chips.prt';

PART_NAME
 R290 'RESISTOR-G155-14701-01,4.7KOHMA':;

SECTION_NUMBER 1
 '@TIMECARD_LIB.TIMECARD(SCH_1):PAGE9_I51@PASSIVE.RESISTOR(CHIPS)':
 C_PATH='@timecard_lib.timecard(sch_1):page9_i51@passive.resistor(chips)',
 P_PATH='@timecard_lib.timecard(sch_1):page20_i51@passive.resistor(chips)',
 PATH='I51',
 DRAWING='@TIMECARD_LIB.TIMECARD(SCH_1):PAGE9',
 PACKAGE='0402',
 PHYS_PAGE='20',
 XY='(-9450,10650)',
 ROT='0',
 VER='2',
 LOCATION='R290',
 CDS_LIB='passive',
 CDS_PART_NAME='RESISTOR-G155-14701-01,4.7KOHMA',
 NO_ASSY='TRUE',
 TOLERANCE='1%',
 CLS_PN='G155-14701-01',
 VALUE='4.7KOHM',
 PRIM_FILE='./archive_libs/passive/resistor/chips/chips.prt';

PART_NAME
 R291 'RESISTOR-G155-14701-01,4.7KOHMA':;

SECTION_NUMBER 1
 '@TIMECARD_LIB.TIMECARD(SCH_1):PAGE9_I44@PASSIVE.RESISTOR(CHIPS)':
 C_PATH='@timecard_lib.timecard(sch_1):page9_i44@passive.resistor(chips)',
 P_PATH='@timecard_lib.timecard(sch_1):page20_i44@passive.resistor(chips)',
 PATH='I44',
 DRAWING='@TIMECARD_LIB.TIMECARD(SCH_1):PAGE9',
 PACKAGE='0402',
 PHYS_PAGE='20',
 XY='(-3100,10250)',
 ROT='5',
 VER='1',
 CDS_LIB='passive',
 CDS_PART_NAME='RESISTOR-G155-14701-01,4.7KOHMA',
 TOLERANCE='1%',
 CLS_PN='G155-14701-01',
 VALUE='4.7KOHM',
 PRIM_FILE='./archive_libs/passive/resistor/chips/chips.prt';

PART_NAME
 R292 'RESISTOR-G155-11002-01,10KOHM,A':;

SECTION_NUMBER 1
 '@TIMECARD_LIB.TIMECARD(SCH_1):PAGE16_I1605@PASSIVE.RESISTOR(CHIPS)':
 C_PATH='@timecard_lib.timecard(sch_1):page16_i1605@passive.resistor(chips)',
 P_PATH='@timecard_lib.timecard(sch_1):page25_i1605@passive.resistor(chips)',
 PATH='I1605',
 DRAWING='@TIMECARD_LIB.TIMECARD(SCH_1):PAGE16',
 PACKAGE='0402',
 PHYS_PAGE='25',
 XY='(-12350,2900)',
 ROT='0',
 VER='1',
 CDS_LIB='passive',
 CDS_PART_NAME='RESISTOR-G155-11002-01,10KOHM,A',
 TOLERANCE='1%',
 CLS_PN='G155-11002-01',
 VALUE='10KOHM',
 PRIM_FILE='./archive_libs/passive/resistor/chips/chips.prt';

PART_NAME
 R293 'RESISTOR-G155-14701-01,4.7KOHMA':;

SECTION_NUMBER 1
 '@TIMECARD_LIB.TIMECARD(SCH_1):PAGE16_I1555@PASSIVE.RESISTOR(CHIPS)':
 C_PATH='@timecard_lib.timecard(sch_1):page16_i1555@passive.resistor(chips)',
 P_PATH='@timecard_lib.timecard(sch_1):page25_i1555@passive.resistor(chips)',
 PATH='I1555',
 DRAWING='@TIMECARD_LIB.TIMECARD(SCH_1):PAGE16',
 PACKAGE='0402',
 PHYS_PAGE='25',
 XY='(-12350,2800)',
 ROT='1',
 VER='2',
 CDS_LIB='passive',
 CDS_PART_NAME='RESISTOR-G155-14701-01,4.7KOHMA',
 NO_ASSY='TRUE',
 TOLERANCE='1%',
 CLS_PN='G155-14701-01',
 VALUE='4.7KOHM',
 PRIM_FILE='./archive_libs/passive/resistor/chips/chips.prt';

PART_NAME
 R294 'RESISTOR-G155-133R0-01,33OHM,1%':
 SIGNAL_MODEL='DEFAULT_RESISTOR_33OHM_2_1';

SECTION_NUMBER 1
 '@TIMECARD_LIB.TIMECARD(SCH_1):PAGE516_I45@PASSIVE.RESISTOR(CHIPS)':
 C_PATH='@timecard_lib.timecard(sch_1):page516_i45@passive.resistor(chips)',
 P_PATH='@timecard_lib.timecard(sch_1):page32_i45@passive.resistor(chips)',
 PATH='I45',
 DRAWING='@TIMECARD_LIB.TIMECARD(SCH_1):PAGE516',
 PACKAGE='0402',
 PHYS_PAGE='32',
 XY='(-11550,4900)',
 ROT='0',
 VER='1',
 CDS_LIB='passive',
 CDS_PART_NAME='RESISTOR-G155-133R0-01,33OHM,1%',
 NO_ASSY='TRUE',
 TOLERANCE='1%',
 CLS_PN='G155-133R0-01',
 SIGNAL_MODEL='DEFAULT_RESISTOR_33OHM_2_1',
 VALUE='33OHM',
 PRIM_FILE='./archive_libs/passive/resistor/chips/chips.prt';

PART_NAME
 R295 'RESISTOR-G155-11002-01,10KOHM,A':;

SECTION_NUMBER 1
 '@TIMECARD_LIB.TIMECARD(SCH_1):PAGE515_I69@PASSIVE.RESISTOR(CHIPS)':
 C_PATH='@timecard_lib.timecard(sch_1):page515_i69@passive.resistor(chips)',
 P_PATH='@timecard_lib.timecard(sch_1):page31_i69@passive.resistor(chips)',
 PATH='I69',
 DRAWING='@TIMECARD_LIB.TIMECARD(SCH_1):PAGE515',
 PACKAGE='0402',
 PHYS_PAGE='31',
 XY='(-6100,7000)',
 ROT='0',
 VER='2',
 CDS_LIB='passive',
 CDS_PART_NAME='RESISTOR-G155-11002-01,10KOHM,A',
 NO_ASSY='TRUE',
 TOLERANCE='1%',
 CLS_PN='G155-11002-01',
 VALUE='10KOHM',
 PRIM_FILE='./archive_libs/passive/resistor/chips/chips.prt';

PART_NAME
 R296 'RESISTOR-G155-14701-01,4.7KOHMA':;

SECTION_NUMBER 1
 '@TIMECARD_LIB.TIMECARD(SCH_1):PAGE7_I38@PASSIVE.RESISTOR(CHIPS)':
 C_PATH='@timecard_lib.timecard(sch_1):page7_i38@passive.resistor(chips)',
 P_PATH='@timecard_lib.timecard(sch_1):page18_i38@passive.resistor(chips)',
 PATH='I38',
 DRAWING='@TIMECARD_LIB.TIMECARD(SCH_1):PAGE7',
 PACKAGE='0402',
 PHYS_PAGE='18',
 XY='(-5100,7500)',
 ROT='0',
 VER='2',
 LOCATION='R296',
 CDS_LIB='passive',
 CDS_PART_NAME='RESISTOR-G155-14701-01,4.7KOHMA',
 TOLERANCE='1%',
 CLS_PN='G155-14701-01',
 VALUE='4.7KOHM',
 PRIM_FILE='./archive_libs/passive/resistor/chips/chips.prt';

PART_NAME
 R297 'RESISTOR-G155-14701-01,4.7KOHMA':;

SECTION_NUMBER 1
 '@TIMECARD_LIB.TIMECARD(SCH_1):PAGE7_I39@PASSIVE.RESISTOR(CHIPS)':
 C_PATH='@timecard_lib.timecard(sch_1):page7_i39@passive.resistor(chips)',
 P_PATH='@timecard_lib.timecard(sch_1):page18_i39@passive.resistor(chips)',
 PATH='I39',
 DRAWING='@TIMECARD_LIB.TIMECARD(SCH_1):PAGE7',
 PACKAGE='0402',
 PHYS_PAGE='18',
 XY='(-5050,6600)',
 ROT='0',
 VER='2',
 LOCATION='R297',
 CDS_LIB='passive',
 CDS_PART_NAME='RESISTOR-G155-14701-01,4.7KOHMA',
 NO_ASSY='TRUE',
 TOLERANCE='1%',
 CLS_PN='G155-14701-01',
 VALUE='4.7KOHM',
 PRIM_FILE='./archive_libs/passive/resistor/chips/chips.prt';

PART_NAME
 R298 'RESISTOR-G155-133R0-01,33OHM,1%':
 SIGNAL_MODEL='DEFAULT_RESISTOR_33OHM_2_1';

SECTION_NUMBER 1
 '@TIMECARD_LIB.TIMECARD(SCH_1):PAGE7_I33@PASSIVE.RESISTOR(CHIPS)':
 C_PATH='@timecard_lib.timecard(sch_1):page7_i33@passive.resistor(chips)',
 P_PATH='@timecard_lib.timecard(sch_1):page18_i33@passive.resistor(chips)',
 PATH='I33',
 DRAWING='@TIMECARD_LIB.TIMECARD(SCH_1):PAGE7',
 PACKAGE='0402',
 PHYS_PAGE='18',
 XY='(-4550,7050)',
 ROT='0',
 VER='1',
 CDS_LIB='passive',
 CDS_PART_NAME='RESISTOR-G155-133R0-01,33OHM,1%',
 TOLERANCE='1%',
 CLS_PN='G155-133R0-01',
 SIGNAL_MODEL='DEFAULT_RESISTOR_33OHM_2_1',
 VALUE='33OHM',
 PRIM_FILE='./archive_libs/passive/resistor/chips/chips.prt';

PART_NAME
 R299 'RESISTOR-G155-133R0-01,33OHM,1%':
 SIGNAL_MODEL='DEFAULT_RESISTOR_33OHM_2_1';

SECTION_NUMBER 1
 '@TIMECARD_LIB.TIMECARD(SCH_1):PAGE7_I40@PASSIVE.RESISTOR(CHIPS)':
 C_PATH='@timecard_lib.timecard(sch_1):page7_i40@passive.resistor(chips)',
 P_PATH='@timecard_lib.timecard(sch_1):page18_i40@passive.resistor(chips)',
 PATH='I40',
 DRAWING='@TIMECARD_LIB.TIMECARD(SCH_1):PAGE7',
 PACKAGE='0402',
 PHYS_PAGE='18',
 XY='(-4550,6950)',
 ROT='0',
 VER='1',
 CDS_LIB='passive',
 CDS_PART_NAME='RESISTOR-G155-133R0-01,33OHM,1%',
 TOLERANCE='1%',
 CLS_PN='G155-133R0-01',
 SIGNAL_MODEL='DEFAULT_RESISTOR_33OHM_2_1',
 VALUE='33OHM',
 PRIM_FILE='./archive_libs/passive/resistor/chips/chips.prt';

PART_NAME
 R300 'RESISTOR-G155-14701-01,4.7KOHMA':;

SECTION_NUMBER 1
 '@TIMECARD_LIB.TIMECARD(SCH_1):PAGE7_I41@PASSIVE.RESISTOR(CHIPS)':
 C_PATH='@timecard_lib.timecard(sch_1):page7_i41@passive.resistor(chips)',
 P_PATH='@timecard_lib.timecard(sch_1):page18_i41@passive.resistor(chips)',
 PATH='I41',
 DRAWING='@TIMECARD_LIB.TIMECARD(SCH_1):PAGE7',
 PACKAGE='0402',
 PHYS_PAGE='18',
 XY='(-3800,7500)',
 ROT='0',
 VER='2',
 CDS_LIB='passive',
 CDS_PART_NAME='RESISTOR-G155-14701-01,4.7KOHMA',
 TOLERANCE='1%',
 CLS_PN='G155-14701-01',
 VALUE='4.7KOHM',
 PRIM_FILE='./archive_libs/passive/resistor/chips/chips.prt';

PART_NAME
 R301 'RESISTOR-G155-14701-01,4.7KOHMA':;

SECTION_NUMBER 1
 '@TIMECARD_LIB.TIMECARD(SCH_1):PAGE9_I43@PASSIVE.RESISTOR(CHIPS)':
 C_PATH='@timecard_lib.timecard(sch_1):page9_i43@passive.resistor(chips)',
 P_PATH='@timecard_lib.timecard(sch_1):page20_i43@passive.resistor(chips)',
 PATH='I43',
 DRAWING='@TIMECARD_LIB.TIMECARD(SCH_1):PAGE9',
 PACKAGE='0402',
 PHYS_PAGE='20',
 XY='(-4000,9350)',
 ROT='5',
 VER='1',
 CDS_LIB='passive',
 CDS_PART_NAME='RESISTOR-G155-14701-01,4.7KOHMA',
 NO_ASSY='TRUE',
 TOLERANCE='1%',
 CLS_PN='G155-14701-01',
 VALUE='4.7KOHM',
 PRIM_FILE='./archive_libs/passive/resistor/chips/chips.prt';

PART_NAME
 R302 'RESISTOR-G155-11001-01,1KOHM,1%':;

SECTION_NUMBER 1
 '@TIMECARD_LIB.TIMECARD(SCH_1):PAGE9_I52@PASSIVE.RESISTOR(CHIPS)':
 C_PATH='@timecard_lib.timecard(sch_1):page9_i52@passive.resistor(chips)',
 P_PATH='@timecard_lib.timecard(sch_1):page20_i52@passive.resistor(chips)',
 PATH='I52',
 DRAWING='@TIMECARD_LIB.TIMECARD(SCH_1):PAGE9',
 PACKAGE='0402',
 PHYS_PAGE='20',
 XY='(-9450,9050)',
 ROT='0',
 VER='2',
 CDS_LIB='passive',
 CDS_PART_NAME='RESISTOR-G155-11001-01,1KOHM,1%',
 TOLERANCE='1%',
 CLS_PN='G155-11001-01',
 VALUE='1KOHM',
 PRIM_FILE='./archive_libs/passive/resistor/chips/chips.prt';

PART_NAME
 R303 'RESISTOR-G155-11001-01,1KOHM,1%':;

SECTION_NUMBER 1
 '@TIMECARD_LIB.TIMECARD(SCH_1):PAGE9_I50@PASSIVE.RESISTOR(CHIPS)':
 C_PATH='@timecard_lib.timecard(sch_1):page9_i50@passive.resistor(chips)',
 P_PATH='@timecard_lib.timecard(sch_1):page20_i50@passive.resistor(chips)',
 PATH='I50',
 DRAWING='@TIMECARD_LIB.TIMECARD(SCH_1):PAGE9',
 PACKAGE='0402',
 PHYS_PAGE='20',
 XY='(-9100,9050)',
 ROT='0',
 VER='2',
 CDS_LIB='passive',
 CDS_PART_NAME='RESISTOR-G155-11001-01,1KOHM,1%',
 TOLERANCE='1%',
 CLS_PN='G155-11001-01',
 VALUE='1KOHM',
 PRIM_FILE='./archive_libs/passive/resistor/chips/chips.prt';

PART_NAME
 R304 'RESISTOR-G155-14701-01,4.7KOHMA':;

SECTION_NUMBER 1
 '@TIMECARD_LIB.TIMECARD(SCH_1):PAGE9_I37@PASSIVE.RESISTOR(CHIPS)':
 C_PATH='@timecard_lib.timecard(sch_1):page9_i37@passive.resistor(chips)',
 P_PATH='@timecard_lib.timecard(sch_1):page20_i37@passive.resistor(chips)',
 PATH='I37',
 DRAWING='@TIMECARD_LIB.TIMECARD(SCH_1):PAGE9',
 PACKAGE='0402',
 PHYS_PAGE='20',
 XY='(-9050,10650)',
 ROT='0',
 VER='2',
 CDS_LIB='passive',
 CDS_PART_NAME='RESISTOR-G155-14701-01,4.7KOHMA',
 TOLERANCE='1%',
 CLS_PN='G155-14701-01',
 VALUE='4.7KOHM',
 PRIM_FILE='./archive_libs/passive/resistor/chips/chips.prt';

PART_NAME
 R305 'RESISTOR-G155-11001-01,1KOHM,1%':;

SECTION_NUMBER 1
 '@TIMECARD_LIB.TIMECARD(SCH_1):PAGE9_I49@PASSIVE.RESISTOR(CHIPS)':
 C_PATH='@timecard_lib.timecard(sch_1):page9_i49@passive.resistor(chips)',
 P_PATH='@timecard_lib.timecard(sch_1):page20_i49@passive.resistor(chips)',
 PATH='I49',
 DRAWING='@TIMECARD_LIB.TIMECARD(SCH_1):PAGE9',
 PACKAGE='0402',
 PHYS_PAGE='20',
 XY='(-8750,9050)',
 ROT='0',
 VER='2',
 CDS_LIB='passive',
 CDS_PART_NAME='RESISTOR-G155-11001-01,1KOHM,1%',
 TOLERANCE='1%',
 CLS_PN='G155-11001-01',
 VALUE='1KOHM',
 PRIM_FILE='./archive_libs/passive/resistor/chips/chips.prt';

PART_NAME
 R306 'RESISTOR-G155-14701-01,4.7KOHMA':;

SECTION_NUMBER 1
 '@TIMECARD_LIB.TIMECARD(SCH_1):PAGE9_I55@PASSIVE.RESISTOR(CHIPS)':
 C_PATH='@timecard_lib.timecard(sch_1):page9_i55@passive.resistor(chips)',
 P_PATH='@timecard_lib.timecard(sch_1):page20_i55@passive.resistor(chips)',
 PATH='I55',
 DRAWING='@TIMECARD_LIB.TIMECARD(SCH_1):PAGE9',
 PACKAGE='0402',
 PHYS_PAGE='20',
 XY='(-8650,10650)',
 ROT='0',
 VER='2',
 CDS_LIB='passive',
 CDS_PART_NAME='RESISTOR-G155-14701-01,4.7KOHMA',
 NO_ASSY='TRUE',
 TOLERANCE='1%',
 CLS_PN='G155-14701-01',
 VALUE='4.7KOHM',
 PRIM_FILE='./archive_libs/passive/resistor/chips/chips.prt';

PART_NAME
 R307 'RESISTOR-G155-11001-01,1KOHM,1%':;

SECTION_NUMBER 1
 '@TIMECARD_LIB.TIMECARD(SCH_1):PAGE9_I47@PASSIVE.RESISTOR(CHIPS)':
 C_PATH='@timecard_lib.timecard(sch_1):page9_i47@passive.resistor(chips)',
 P_PATH='@timecard_lib.timecard(sch_1):page20_i47@passive.resistor(chips)',
 PATH='I47',
 DRAWING='@TIMECARD_LIB.TIMECARD(SCH_1):PAGE9',
 PACKAGE='0402',
 PHYS_PAGE='20',
 XY='(-8400,9050)',
 ROT='0',
 VER='2',
 CDS_LIB='passive',
 CDS_PART_NAME='RESISTOR-G155-11001-01,1KOHM,1%',
 TOLERANCE='1%',
 CLS_PN='G155-11001-01',
 VALUE='1KOHM',
 PRIM_FILE='./archive_libs/passive/resistor/chips/chips.prt';

PART_NAME
 R308 'RESISTOR-G155-11002-01,10KOHM,A':;

SECTION_NUMBER 1
 '@TIMECARD_LIB.TIMECARD(SCH_1):PAGE16_I1604@PASSIVE.RESISTOR(CHIPS)':
 C_PATH='@timecard_lib.timecard(sch_1):page16_i1604@passive.resistor(chips)',
 P_PATH='@timecard_lib.timecard(sch_1):page25_i1604@passive.resistor(chips)',
 PATH='I1604',
 DRAWING='@TIMECARD_LIB.TIMECARD(SCH_1):PAGE16',
 PACKAGE='0402',
 PHYS_PAGE='25',
 XY='(-12350,2600)',
 ROT='0',
 VER='1',
 CDS_LIB='passive',
 CDS_PART_NAME='RESISTOR-G155-11002-01,10KOHM,A',
 TOLERANCE='1%',
 CLS_PN='G155-11002-01',
 VALUE='10KOHM',
 PRIM_FILE='./archive_libs/passive/resistor/chips/chips.prt';

PART_NAME
 R309 'RESISTOR-G155-14701-01,4.7KOHMA':;

SECTION_NUMBER 1
 '@TIMECARD_LIB.TIMECARD(SCH_1):PAGE16_I1557@PASSIVE.RESISTOR(CHIPS)':
 C_PATH='@timecard_lib.timecard(sch_1):page16_i1557@passive.resistor(chips)',
 P_PATH='@timecard_lib.timecard(sch_1):page25_i1557@passive.resistor(chips)',
 PATH='I1557',
 DRAWING='@TIMECARD_LIB.TIMECARD(SCH_1):PAGE16',
 PACKAGE='0402',
 PHYS_PAGE='25',
 XY='(-12350,2500)',
 ROT='1',
 VER='2',
 CDS_LIB='passive',
 CDS_PART_NAME='RESISTOR-G155-14701-01,4.7KOHMA',
 NO_ASSY='TRUE',
 TOLERANCE='1%',
 CLS_PN='G155-14701-01',
 VALUE='4.7KOHM',
 PRIM_FILE='./archive_libs/passive/resistor/chips/chips.prt';

PART_NAME
 R310 'RESISTOR-G155-100R0-J0,0OHM,-':;

SECTION_NUMBER 1
 '@TIMECARD_LIB.TIMECARD(SCH_1):PAGE5_I116@PASSIVE.RESISTOR(CHIPS)':
 C_PATH='@timecard_lib.timecard(sch_1):page5_i116@passive.resistor(chips)',
 P_PATH='@timecard_lib.timecard(sch_1):page16_i116@passive.resistor(chips)',
 PATH='I116',
 DRAWING='@TIMECARD_LIB.TIMECARD(SCH_1):PAGE5',
 PACKAGE='0402',
 PHYS_PAGE='16',
 XY='(-9750,9900)',
 ROT='0',
 VER='1',
 CDS_LIB='passive',
 CDS_PART_NAME='RESISTOR-G155-100R0-J0,0OHM,-',
 TOLERANCE='-',
 CLS_PN='G155-100R0-J0',
 VALUE='0OHM',
 PRIM_FILE='./archive_libs/passive/resistor/chips/chips.prt';

PART_NAME
 R311 'RESISTOR-G155-100R0-J0,0OHM,-':;

SECTION_NUMBER 1
 '@TIMECARD_LIB.TIMECARD(SCH_1):PAGE5_I115@PASSIVE.RESISTOR(CHIPS)':
 C_PATH='@timecard_lib.timecard(sch_1):page5_i115@passive.resistor(chips)',
 P_PATH='@timecard_lib.timecard(sch_1):page16_i115@passive.resistor(chips)',
 PATH='I115',
 DRAWING='@TIMECARD_LIB.TIMECARD(SCH_1):PAGE5',
 PACKAGE='0402',
 PHYS_PAGE='16',
 XY='(-9750,9800)',
 ROT='0',
 VER='1',
 CDS_LIB='passive',
 CDS_PART_NAME='RESISTOR-G155-100R0-J0,0OHM,-',
 TOLERANCE='-',
 CLS_PN='G155-100R0-J0',
 VALUE='0OHM',
 PRIM_FILE='./archive_libs/passive/resistor/chips/chips.prt';

PART_NAME
 R312 'RESISTOR-G155-100R0-J0,0OHM,-':;

SECTION_NUMBER 1
 '@TIMECARD_LIB.TIMECARD(SCH_1):PAGE5_I112@PASSIVE.RESISTOR(CHIPS)':
 C_PATH='@timecard_lib.timecard(sch_1):page5_i112@passive.resistor(chips)',
 P_PATH='@timecard_lib.timecard(sch_1):page16_i112@passive.resistor(chips)',
 PATH='I112',
 DRAWING='@TIMECARD_LIB.TIMECARD(SCH_1):PAGE5',
 PACKAGE='0402',
 PHYS_PAGE='16',
 XY='(-11000,6350)',
 ROT='0',
 VER='1',
 CDS_LIB='passive',
 CDS_PART_NAME='RESISTOR-G155-100R0-J0,0OHM,-',
 TOLERANCE='-',
 CLS_PN='G155-100R0-J0',
 VALUE='0OHM',
 PRIM_FILE='./archive_libs/passive/resistor/chips/chips.prt';

PART_NAME
 R313 'RESISTOR-G155-100R0-J0,0OHM,-':;

SECTION_NUMBER 1
 '@TIMECARD_LIB.TIMECARD(SCH_1):PAGE5_I111@PASSIVE.RESISTOR(CHIPS)':
 C_PATH='@timecard_lib.timecard(sch_1):page5_i111@passive.resistor(chips)',
 P_PATH='@timecard_lib.timecard(sch_1):page16_i111@passive.resistor(chips)',
 PATH='I111',
 DRAWING='@TIMECARD_LIB.TIMECARD(SCH_1):PAGE5',
 PACKAGE='0402',
 PHYS_PAGE='16',
 XY='(-11000,6250)',
 ROT='0',
 VER='1',
 CDS_LIB='passive',
 CDS_PART_NAME='RESISTOR-G155-100R0-J0,0OHM,-',
 TOLERANCE='-',
 CLS_PN='G155-100R0-J0',
 VALUE='0OHM',
 PRIM_FILE='./archive_libs/passive/resistor/chips/chips.prt';

PART_NAME
 R314 'RESISTOR-G155-14701-01,4.7KOHMA':;

SECTION_NUMBER 1
 '@TIMECARD_LIB.TIMECARD(SCH_1):PAGE8_I71@PASSIVE.RESISTOR(CHIPS)':
 C_PATH='@timecard_lib.timecard(sch_1):page8_i71@passive.resistor(chips)',
 P_PATH='@timecard_lib.timecard(sch_1):page19_i71@passive.resistor(chips)',
 PATH='I71',
 DRAWING='@TIMECARD_LIB.TIMECARD(SCH_1):PAGE8',
 PACKAGE='0402',
 PHYS_PAGE='19',
 XY='(-9100,6650)',
 ROT='3',
 VER='1',
 CDS_LIB='passive',
 CDS_PART_NAME='RESISTOR-G155-14701-01,4.7KOHMA',
 TOLERANCE='1%',
 CLS_PN='G155-14701-01',
 VALUE='4.7KOHM',
 PRIM_FILE='./archive_libs/passive/resistor/chips/chips.prt';

PART_NAME
 R315 'RESISTOR-G155-100R0-J0,0OHM,-':;

SECTION_NUMBER 1
 '@TIMECARD_LIB.TIMECARD(SCH_1):PAGE8_I63@PASSIVE.RESISTOR(CHIPS)':
 C_PATH='@timecard_lib.timecard(sch_1):page8_i63@passive.resistor(chips)',
 P_PATH='@timecard_lib.timecard(sch_1):page19_i63@passive.resistor(chips)',
 PATH='I63',
 DRAWING='@TIMECARD_LIB.TIMECARD(SCH_1):PAGE8',
 PACKAGE='0402',
 PHYS_PAGE='19',
 XY='(-8350,5550)',
 ROT='0',
 VER='1',
 CDS_LIB='passive',
 CDS_PART_NAME='RESISTOR-G155-100R0-J0,0OHM,-',
 NO_ASSY='TRUE',
 TOLERANCE='-',
 CLS_PN='G155-100R0-J0',
 VALUE='0OHM',
 PRIM_FILE='./archive_libs/passive/resistor/chips/chips.prt';

PART_NAME
 R316 'RESISTOR-G155-100R0-J0,0OHM,-':;

SECTION_NUMBER 1
 '@TIMECARD_LIB.TIMECARD(SCH_1):PAGE8_I64@PASSIVE.RESISTOR(CHIPS)':
 C_PATH='@timecard_lib.timecard(sch_1):page8_i64@passive.resistor(chips)',
 P_PATH='@timecard_lib.timecard(sch_1):page19_i64@passive.resistor(chips)',
 PATH='I64',
 DRAWING='@TIMECARD_LIB.TIMECARD(SCH_1):PAGE8',
 PACKAGE='0402',
 PHYS_PAGE='19',
 XY='(-8350,5450)',
 ROT='0',
 VER='1',
 CDS_LIB='passive',
 CDS_PART_NAME='RESISTOR-G155-100R0-J0,0OHM,-',
 NO_ASSY='TRUE',
 TOLERANCE='-',
 CLS_PN='G155-100R0-J0',
 VALUE='0OHM',
 PRIM_FILE='./archive_libs/passive/resistor/chips/chips.prt';

PART_NAME
 R317 'RESISTOR-G155-11002-01,10KOHM,A':;

SECTION_NUMBER 1
 '@TIMECARD_LIB.TIMECARD(SCH_1):PAGE14_I259@PASSIVE.RESISTOR(CHIPS)':
 C_PATH='@timecard_lib.timecard(sch_1):page14_i259@passive.resistor(chips)',
 P_PATH='@timecard_lib.timecard(sch_1):page26_i259@passive.resistor(chips)',
 PATH='I259',
 DRAWING='@TIMECARD_LIB.TIMECARD(SCH_1):PAGE14',
 PACKAGE='0402',
 PHYS_PAGE='26',
 XY='(-11400,5850)',
 ROT='0',
 VER='2',
 CDS_LIB='passive',
 CDS_PART_NAME='RESISTOR-G155-11002-01,10KOHM,A',
 TOLERANCE='1%',
 CLS_PN='G155-11002-01',
 VALUE='10KOHM',
 PRIM_FILE='./archive_libs/passive/resistor/chips/chips.prt';

PART_NAME
 R318 'RESISTOR-G155-11002-01,10KOHM,A':;

SECTION_NUMBER 1
 '@TIMECARD_LIB.TIMECARD(SCH_1):PAGE14_I261@PASSIVE.RESISTOR(CHIPS)':
 C_PATH='@timecard_lib.timecard(sch_1):page14_i261@passive.resistor(chips)',
 P_PATH='@timecard_lib.timecard(sch_1):page26_i261@passive.resistor(chips)',
 PATH='I261',
 DRAWING='@TIMECARD_LIB.TIMECARD(SCH_1):PAGE14',
 PACKAGE='0402',
 PHYS_PAGE='26',
 XY='(-11000,5850)',
 ROT='0',
 VER='2',
 CDS_LIB='passive',
 CDS_PART_NAME='RESISTOR-G155-11002-01,10KOHM,A',
 TOLERANCE='1%',
 CLS_PN='G155-11002-01',
 VALUE='10KOHM',
 PRIM_FILE='./archive_libs/passive/resistor/chips/chips.prt';

PART_NAME
 R319 'RESISTOR-G155-133R0-01,33OHM,1%':
 SIGNAL_MODEL='DEFAULT_RESISTOR_33OHM_2_1';

SECTION_NUMBER 1
 '@TIMECARD_LIB.TIMECARD(SCH_1):PAGE14_I249@PASSIVE.RESISTOR(CHIPS)':
 C_PATH='@timecard_lib.timecard(sch_1):page14_i249@passive.resistor(chips)',
 P_PATH='@timecard_lib.timecard(sch_1):page26_i249@passive.resistor(chips)',
 PATH='I249',
 DRAWING='@TIMECARD_LIB.TIMECARD(SCH_1):PAGE14',
 PACKAGE='0402',
 PHYS_PAGE='26',
 XY='(-11900,4800)',
 ROT='0',
 VER='1',
 CDS_LIB='passive',
 CDS_PART_NAME='RESISTOR-G155-133R0-01,33OHM,1%',
 NO_ASSY='TRUE',
 TOLERANCE='1%',
 CLS_PN='G155-133R0-01',
 SIGNAL_MODEL='DEFAULT_RESISTOR_33OHM_2_1',
 VALUE='33OHM',
 PRIM_FILE='./archive_libs/passive/resistor/chips/chips.prt';

PART_NAME
 R320 'RESISTOR-G155-14701-01,4.7KOHMA':;

SECTION_NUMBER 1
 '@TIMECARD_LIB.TIMECARD(SCH_1):PAGE14_I264@PASSIVE.RESISTOR(CHIPS)':
 C_PATH='@timecard_lib.timecard(sch_1):page14_i264@passive.resistor(chips)',
 P_PATH='@timecard_lib.timecard(sch_1):page26_i264@passive.resistor(chips)',
 PATH='I264',
 DRAWING='@TIMECARD_LIB.TIMECARD(SCH_1):PAGE14',
 PACKAGE='0402',
 PHYS_PAGE='26',
 XY='(-9700,5500)',
 ROT='0',
 VER='2',
 LOCATION='R320',
 CDS_LIB='passive',
 CDS_PART_NAME='RESISTOR-G155-14701-01,4.7KOHMA',
 TOLERANCE='1%',
 CLS_PN='G155-14701-01',
 VALUE='4.7KOHM',
 PRIM_FILE='./archive_libs/passive/resistor/chips/chips.prt';

PART_NAME
 R321 'RESISTOR-G155-133R0-01,33OHM,1%':
 SIGNAL_MODEL='DEFAULT_RESISTOR_33OHM_2_1';

SECTION_NUMBER 1
 '@TIMECARD_LIB.TIMECARD(SCH_1):PAGE14_I258@PASSIVE.RESISTOR(CHIPS)':
 C_PATH='@timecard_lib.timecard(sch_1):page14_i258@passive.resistor(chips)',
 P_PATH='@timecard_lib.timecard(sch_1):page26_i258@passive.resistor(chips)',
 PATH='I258',
 DRAWING='@TIMECARD_LIB.TIMECARD(SCH_1):PAGE14',
 PACKAGE='0402',
 PHYS_PAGE='26',
 XY='(-11900,5300)',
 ROT='0',
 VER='1',
 CDS_LIB='passive',
 CDS_PART_NAME='RESISTOR-G155-133R0-01,33OHM,1%',
 NO_ASSY='TRUE',
 TOLERANCE='1%',
 CLS_PN='G155-133R0-01',
 SIGNAL_MODEL='DEFAULT_RESISTOR_33OHM_2_1',
 VALUE='33OHM',
 PRIM_FILE='./archive_libs/passive/resistor/chips/chips.prt';

PART_NAME
 R322 'RESISTOR-G155-133R0-01,33OHM,1%':
 SIGNAL_MODEL='DEFAULT_RESISTOR_33OHM_2_1';

SECTION_NUMBER 1
 '@TIMECARD_LIB.TIMECARD(SCH_1):PAGE14_I257@PASSIVE.RESISTOR(CHIPS)':
 C_PATH='@timecard_lib.timecard(sch_1):page14_i257@passive.resistor(chips)',
 P_PATH='@timecard_lib.timecard(sch_1):page26_i257@passive.resistor(chips)',
 PATH='I257',
 DRAWING='@TIMECARD_LIB.TIMECARD(SCH_1):PAGE14',
 PACKAGE='0402',
 PHYS_PAGE='26',
 XY='(-11900,5200)',
 ROT='0',
 VER='1',
 CDS_LIB='passive',
 CDS_PART_NAME='RESISTOR-G155-133R0-01,33OHM,1%',
 NO_ASSY='TRUE',
 TOLERANCE='1%',
 CLS_PN='G155-133R0-01',
 SIGNAL_MODEL='DEFAULT_RESISTOR_33OHM_2_1',
 VALUE='33OHM',
 PRIM_FILE='./archive_libs/passive/resistor/chips/chips.prt';

PART_NAME
 R323 'RESISTOR-G155-14701-01,4.7KOHMA':;

SECTION_NUMBER 1
 '@TIMECARD_LIB.TIMECARD(SCH_1):PAGE14_I246@PASSIVE.RESISTOR(CHIPS)':
 C_PATH='@timecard_lib.timecard(sch_1):page14_i246@passive.resistor(chips)',
 P_PATH='@timecard_lib.timecard(sch_1):page26_i246@passive.resistor(chips)',
 PATH='I246',
 DRAWING='@TIMECARD_LIB.TIMECARD(SCH_1):PAGE14',
 PACKAGE='0402',
 PHYS_PAGE='26',
 XY='(-10050,3750)',
 ROT='0',
 VER='2',
 CDS_LIB='passive',
 CDS_PART_NAME='RESISTOR-G155-14701-01,4.7KOHMA',
 TOLERANCE='1%',
 CLS_PN='G155-14701-01',
 VALUE='4.7KOHM',
 PRIM_FILE='./archive_libs/passive/resistor/chips/chips.prt';

PART_NAME
 R324 'RESISTOR-G155-100R0-J0,0OHM,-':;

SECTION_NUMBER 1
 '@TIMECARD_LIB.TIMECARD(SCH_1):PAGE14_I247@PASSIVE.RESISTOR(CHIPS)':
 C_PATH='@timecard_lib.timecard(sch_1):page14_i247@passive.resistor(chips)',
 P_PATH='@timecard_lib.timecard(sch_1):page26_i247@passive.resistor(chips)',
 PATH='I247',
 DRAWING='@TIMECARD_LIB.TIMECARD(SCH_1):PAGE14',
 PACKAGE='0402',
 PHYS_PAGE='26',
 XY='(-9600,3700)',
 ROT='1',
 VER='1',
 CDS_LIB='passive',
 CDS_PART_NAME='RESISTOR-G155-100R0-J0,0OHM,-',
 TOLERANCE='-',
 CLS_PN='G155-100R0-J0',
 VALUE='0OHM',
 PRIM_FILE='./archive_libs/passive/resistor/chips/chips.prt';

PART_NAME
 R325 'RESISTOR-G155-11002-01,10KOHM,A':;

SECTION_NUMBER 1
 '@TIMECARD_LIB.TIMECARD(SCH_1):PAGE16_I1602@PASSIVE.RESISTOR(CHIPS)':
 C_PATH='@timecard_lib.timecard(sch_1):page16_i1602@passive.resistor(chips)',
 P_PATH='@timecard_lib.timecard(sch_1):page25_i1602@passive.resistor(chips)',
 PATH='I1602',
 DRAWING='@TIMECARD_LIB.TIMECARD(SCH_1):PAGE16',
 PACKAGE='0402',
 PHYS_PAGE='25',
 XY='(-12350,2300)',
 ROT='0',
 VER='1',
 CDS_LIB='passive',
 CDS_PART_NAME='RESISTOR-G155-11002-01,10KOHM,A',
 TOLERANCE='1%',
 CLS_PN='G155-11002-01',
 VALUE='10KOHM',
 PRIM_FILE='./archive_libs/passive/resistor/chips/chips.prt';

PART_NAME
 R326 'RESISTOR-G155-14701-01,4.7KOHMA':;

SECTION_NUMBER 1
 '@TIMECARD_LIB.TIMECARD(SCH_1):PAGE16_I1552@PASSIVE.RESISTOR(CHIPS)':
 C_PATH='@timecard_lib.timecard(sch_1):page16_i1552@passive.resistor(chips)',
 P_PATH='@timecard_lib.timecard(sch_1):page25_i1552@passive.resistor(chips)',
 PATH='I1552',
 DRAWING='@TIMECARD_LIB.TIMECARD(SCH_1):PAGE16',
 PACKAGE='0402',
 PHYS_PAGE='25',
 XY='(-12350,2200)',
 ROT='1',
 VER='2',
 CDS_LIB='passive',
 CDS_PART_NAME='RESISTOR-G155-14701-01,4.7KOHMA',
 NO_ASSY='TRUE',
 TOLERANCE='1%',
 CLS_PN='G155-14701-01',
 VALUE='4.7KOHM',
 PRIM_FILE='./archive_libs/passive/resistor/chips/chips.prt';

PART_NAME
 R327 'RESISTOR-G155-11002-01,10KOHM,A':;

SECTION_NUMBER 1
 '@TIMECARD_LIB.TIMECARD(SCH_1):PAGE16_I1603@PASSIVE.RESISTOR(CHIPS)':
 C_PATH='@timecard_lib.timecard(sch_1):page16_i1603@passive.resistor(chips)',
 P_PATH='@timecard_lib.timecard(sch_1):page25_i1603@passive.resistor(chips)',
 PATH='I1603',
 DRAWING='@TIMECARD_LIB.TIMECARD(SCH_1):PAGE16',
 PACKAGE='0402',
 PHYS_PAGE='25',
 XY='(-12350,2000)',
 ROT='0',
 VER='1',
 CDS_LIB='passive',
 CDS_PART_NAME='RESISTOR-G155-11002-01,10KOHM,A',
 TOLERANCE='1%',
 CLS_PN='G155-11002-01',
 VALUE='10KOHM',
 PRIM_FILE='./archive_libs/passive/resistor/chips/chips.prt';

PART_NAME
 R328 'RESISTOR-G155-14701-01,4.7KOHMA':;

SECTION_NUMBER 1
 '@TIMECARD_LIB.TIMECARD(SCH_1):PAGE16_I1550@PASSIVE.RESISTOR(CHIPS)':
 C_PATH='@timecard_lib.timecard(sch_1):page16_i1550@passive.resistor(chips)',
 P_PATH='@timecard_lib.timecard(sch_1):page25_i1550@passive.resistor(chips)',
 PATH='I1550',
 DRAWING='@TIMECARD_LIB.TIMECARD(SCH_1):PAGE16',
 PACKAGE='0402',
 PHYS_PAGE='25',
 XY='(-12350,1900)',
 ROT='1',
 VER='2',
 CDS_LIB='passive',
 CDS_PART_NAME='RESISTOR-G155-14701-01,4.7KOHMA',
 NO_ASSY='TRUE',
 TOLERANCE='1%',
 CLS_PN='G155-14701-01',
 VALUE='4.7KOHM',
 PRIM_FILE='./archive_libs/passive/resistor/chips/chips.prt';

PART_NAME
 R329 'RESISTOR-G155-133R0-01,33OHM,1%':;

SECTION_NUMBER 1
 '@TIMECARD_LIB.TIMECARD(SCH_1):PAGE16_I1707@PASSIVE.RESISTOR(CHIPS)':
 C_PATH='@timecard_lib.timecard(sch_1):page16_i1707@passive.resistor(chips)',
 P_PATH='@timecard_lib.timecard(sch_1):page25_i1707@passive.resistor(chips)',
 PATH='I1707',
 DRAWING='@TIMECARD_LIB.TIMECARD(SCH_1):PAGE16',
 PACKAGE='0402',
 PHYS_PAGE='25',
 XY='(-7150,3250)',
 ROT='0',
 VER='1',
 CDS_LIB='passive',
 CDS_PART_NAME='RESISTOR-G155-133R0-01,33OHM,1%',
 TOLERANCE='1%',
 CLS_PN='G155-133R0-01',
 VALUE='33OHM',
 PRIM_FILE='./archive_libs/passive/resistor/chips/chips.prt';

PART_NAME
 R330 'RESISTOR-G155-133R0-01,33OHM,1%':
 SIGNAL_MODEL='DEFAULT_RESISTOR_33OHM_2_1';

SECTION_NUMBER 1
 '@TIMECARD_LIB.TIMECARD(SCH_1):PAGE9_I64@PASSIVE.RESISTOR(CHIPS)':
 C_PATH='@timecard_lib.timecard(sch_1):page9_i64@passive.resistor(chips)',
 P_PATH='@timecard_lib.timecard(sch_1):page20_i64@passive.resistor(chips)',
 PATH='I64',
 DRAWING='@TIMECARD_LIB.TIMECARD(SCH_1):PAGE9',
 PACKAGE='0402',
 PHYS_PAGE='20',
 XY='(-3850,8350)',
 ROT='0',
 VER='1',
 CDS_LIB='passive',
 CDS_PART_NAME='RESISTOR-G155-133R0-01,33OHM,1%',
 TOLERANCE='1%',
 CLS_PN='G155-133R0-01',
 SIGNAL_MODEL='DEFAULT_RESISTOR_33OHM_2_1',
 VALUE='33OHM',
 PRIM_FILE='./archive_libs/passive/resistor/chips/chips.prt';

PART_NAME
 R331 'RESISTOR-G155-14701-01,4.7KOHMA':;

SECTION_NUMBER 1
 '@TIMECARD_LIB.TIMECARD(SCH_1):PAGE12_I280@PASSIVE.RESISTOR(CHIPS)':
 C_PATH='@timecard_lib.timecard(sch_1):page12_i280@passive.resistor(chips)',
 P_PATH='@timecard_lib.timecard(sch_1):page23_i280@passive.resistor(chips)',
 PATH='I280',
 DRAWING='@TIMECARD_LIB.TIMECARD(SCH_1):PAGE12',
 PACKAGE='0402',
 PHYS_PAGE='23',
 XY='(-10650,3050)',
 ROT='1',
 VER='2',
 LOCATION='R331',
 CDS_LIB='passive',
 CDS_PART_NAME='RESISTOR-G155-14701-01,4.7KOHMA',
 TOLERANCE='1%',
 CLS_PN='G155-14701-01',
 VALUE='4.7KOHM',
 PRIM_FILE='./archive_libs/passive/resistor/chips/chips.prt';

PART_NAME
 R332 'RESISTOR-G155-133R0-01,33OHM,1%':;

SECTION_NUMBER 1
 '@TIMECARD_LIB.TIMECARD(SCH_1):PAGE6_I15@PASSIVE.RESISTOR(CHIPS)':
 C_PATH='@timecard_lib.timecard(sch_1):page6_i15@passive.resistor(chips)',
 P_PATH='@timecard_lib.timecard(sch_1):page17_i15@passive.resistor(chips)',
 PATH='I15',
 DRAWING='@TIMECARD_LIB.TIMECARD(SCH_1):PAGE6',
 PACKAGE='0402',
 PHYS_PAGE='17',
 XY='(-5350,7600)',
 ROT='0',
 VER='1',
 CDS_LIB='passive',
 CDS_PART_NAME='RESISTOR-G155-133R0-01,33OHM,1%',
 TOLERANCE='1%',
 CLS_PN='G155-133R0-01',
 VALUE='33OHM',
 PRIM_FILE='./archive_libs/passive/resistor/chips/chips.prt';

PART_NAME
 R333 'RESISTOR-G155-14701-01,4.7KOHMA':;

SECTION_NUMBER 1
 '@TIMECARD_LIB.TIMECARD(SCH_1):PAGE6_I31@PASSIVE.RESISTOR(CHIPS)':
 C_PATH='@timecard_lib.timecard(sch_1):page6_i31@passive.resistor(chips)',
 P_PATH='@timecard_lib.timecard(sch_1):page17_i31@passive.resistor(chips)',
 PATH='I31',
 DRAWING='@TIMECARD_LIB.TIMECARD(SCH_1):PAGE6',
 PACKAGE='0402',
 PHYS_PAGE='17',
 XY='(-3850,8150)',
 ROT='0',
 VER='2',
 CDS_LIB='passive',
 CDS_PART_NAME='RESISTOR-G155-14701-01,4.7KOHMA',
 NO_ASSY='TRUE',
 TOLERANCE='1%',
 CLS_PN='G155-14701-01',
 VALUE='4.7KOHM',
 PRIM_FILE='./archive_libs/passive/resistor/chips/chips.prt';

PART_NAME
 R334 'RESISTOR-G155-11001-01,1KOHM,1%':;

SECTION_NUMBER 1
 '@TIMECARD_LIB.TIMECARD(SCH_1):PAGE6_I30@PASSIVE.RESISTOR(CHIPS)':
 C_PATH='@timecard_lib.timecard(sch_1):page6_i30@passive.resistor(chips)',
 P_PATH='@timecard_lib.timecard(sch_1):page17_i30@passive.resistor(chips)',
 PATH='I30',
 DRAWING='@TIMECARD_LIB.TIMECARD(SCH_1):PAGE6',
 PACKAGE='0402',
 PHYS_PAGE='17',
 XY='(-3850,6900)',
 ROT='0',
 VER='2',
 CDS_LIB='passive',
 CDS_PART_NAME='RESISTOR-G155-11001-01,1KOHM,1%',
 TOLERANCE='1%',
 CLS_PN='G155-11001-01',
 VALUE='1KOHM',
 PRIM_FILE='./archive_libs/passive/resistor/chips/chips.prt';

PART_NAME
 R335 'RESISTOR-G155-14701-01,4.7KOHMA':;

SECTION_NUMBER 1
 '@TIMECARD_LIB.TIMECARD(SCH_1):PAGE6_I35@PASSIVE.RESISTOR(CHIPS)':
 C_PATH='@timecard_lib.timecard(sch_1):page6_i35@passive.resistor(chips)',
 P_PATH='@timecard_lib.timecard(sch_1):page17_i35@passive.resistor(chips)',
 PATH='I35',
 DRAWING='@TIMECARD_LIB.TIMECARD(SCH_1):PAGE6',
 PACKAGE='0402',
 PHYS_PAGE='17',
 XY='(-3400,8150)',
 ROT='0',
 VER='2',
 CDS_LIB='passive',
 CDS_PART_NAME='RESISTOR-G155-14701-01,4.7KOHMA',
 NO_ASSY='TRUE',
 TOLERANCE='1%',
 CLS_PN='G155-14701-01',
 VALUE='4.7KOHM',
 PRIM_FILE='./archive_libs/passive/resistor/chips/chips.prt';

PART_NAME
 R336 'RESISTOR-G155-11001-01,1KOHM,1%':;

SECTION_NUMBER 1
 '@TIMECARD_LIB.TIMECARD(SCH_1):PAGE6_I32@PASSIVE.RESISTOR(CHIPS)':
 C_PATH='@timecard_lib.timecard(sch_1):page6_i32@passive.resistor(chips)',
 P_PATH='@timecard_lib.timecard(sch_1):page17_i32@passive.resistor(chips)',
 PATH='I32',
 DRAWING='@TIMECARD_LIB.TIMECARD(SCH_1):PAGE6',
 PACKAGE='0402',
 PHYS_PAGE='17',
 XY='(-3400,6900)',
 ROT='0',
 VER='2',
 CDS_LIB='passive',
 CDS_PART_NAME='RESISTOR-G155-11001-01,1KOHM,1%',
 TOLERANCE='1%',
 CLS_PN='G155-11001-01',
 VALUE='1KOHM',
 PRIM_FILE='./archive_libs/passive/resistor/chips/chips.prt';

PART_NAME
 R337 'RESISTOR-G155-14701-01,4.7KOHMA':;

SECTION_NUMBER 1
 '@TIMECARD_LIB.TIMECARD(SCH_1):PAGE6_I36@PASSIVE.RESISTOR(CHIPS)':
 C_PATH='@timecard_lib.timecard(sch_1):page6_i36@passive.resistor(chips)',
 P_PATH='@timecard_lib.timecard(sch_1):page17_i36@passive.resistor(chips)',
 PATH='I36',
 DRAWING='@TIMECARD_LIB.TIMECARD(SCH_1):PAGE6',
 PACKAGE='0402',
 PHYS_PAGE='17',
 XY='(-3000,8150)',
 ROT='0',
 VER='2',
 CDS_LIB='passive',
 CDS_PART_NAME='RESISTOR-G155-14701-01,4.7KOHMA',
 NO_ASSY='TRUE',
 TOLERANCE='1%',
 CLS_PN='G155-14701-01',
 VALUE='4.7KOHM',
 PRIM_FILE='./archive_libs/passive/resistor/chips/chips.prt';

PART_NAME
 R338 'RESISTOR-G155-11001-01,1KOHM,1%':;

SECTION_NUMBER 1
 '@TIMECARD_LIB.TIMECARD(SCH_1):PAGE6_I33@PASSIVE.RESISTOR(CHIPS)':
 C_PATH='@timecard_lib.timecard(sch_1):page6_i33@passive.resistor(chips)',
 P_PATH='@timecard_lib.timecard(sch_1):page17_i33@passive.resistor(chips)',
 PATH='I33',
 DRAWING='@TIMECARD_LIB.TIMECARD(SCH_1):PAGE6',
 PACKAGE='0402',
 PHYS_PAGE='17',
 XY='(-3020,6890)',
 ROT='0',
 VER='2',
 CDS_LIB='passive',
 CDS_PART_NAME='RESISTOR-G155-11001-01,1KOHM,1%',
 TOLERANCE='1%',
 CLS_PN='G155-11001-01',
 VALUE='1KOHM',
 PRIM_FILE='./archive_libs/passive/resistor/chips/chips.prt';

PART_NAME
 R339 'RESISTOR-G155-133R0-01,33OHM,1%':;

SECTION_NUMBER 1
 '@TIMECARD_LIB.TIMECARD(SCH_1):PAGE161_I261@PASSIVE.RESISTOR(CHIPS)':
 C_PATH='@timecard_lib.timecard(sch_1):page161_i261@passive.resistor(chips)',
 P_PATH='@timecard_lib.timecard(sch_1):page11_i261@passive.resistor(chips)',
 PATH='I261',
 DRAWING='@TIMECARD_LIB.TIMECARD(SCH_1):PAGE161',
 PACKAGE='0402',
 PHYS_PAGE='11',
 XY='(-5350,7950)',
 ROT='0',
 VER='1',
 CDS_LIB='passive',
 CDS_PART_NAME='RESISTOR-G155-133R0-01,33OHM,1%',
 TOLERANCE='1%',
 CLS_PN='G155-133R0-01',
 VALUE='33OHM',
 PRIM_FILE='./archive_libs/passive/resistor/chips/chips.prt';

PART_NAME
 R340 'RESISTOR-G155-14701-01,4.7KOHMA':;

SECTION_NUMBER 1
 '@TIMECARD_LIB.TIMECARD(SCH_1):PAGE6_I41@PASSIVE.RESISTOR(CHIPS)':
 C_PATH='@timecard_lib.timecard(sch_1):page6_i41@passive.resistor(chips)',
 P_PATH='@timecard_lib.timecard(sch_1):page17_i41@passive.resistor(chips)',
 PATH='I41',
 DRAWING='@TIMECARD_LIB.TIMECARD(SCH_1):PAGE6',
 PACKAGE='0402',
 PHYS_PAGE='17',
 XY='(-1350,7900)',
 ROT='0',
 VER='2',
 CDS_LIB='passive',
 CDS_PART_NAME='RESISTOR-G155-14701-01,4.7KOHMA',
 TOLERANCE='1%',
 CLS_PN='G155-14701-01',
 VALUE='4.7KOHM',
 PRIM_FILE='./archive_libs/passive/resistor/chips/chips.prt';

PART_NAME
 R341 'RESISTOR-G155-14701-01,4.7KOHMA':;

SECTION_NUMBER 1
 '@TIMECARD_LIB.TIMECARD(SCH_1):PAGE9_I65@PASSIVE.RESISTOR(CHIPS)':
 C_PATH='@timecard_lib.timecard(sch_1):page9_i65@passive.resistor(chips)',
 P_PATH='@timecard_lib.timecard(sch_1):page20_i65@passive.resistor(chips)',
 PATH='I65',
 DRAWING='@TIMECARD_LIB.TIMECARD(SCH_1):PAGE9',
 PACKAGE='0402',
 PHYS_PAGE='20',
 XY='(-3100,8700)',
 ROT='5',
 VER='1',
 CDS_LIB='passive',
 CDS_PART_NAME='RESISTOR-G155-14701-01,4.7KOHMA',
 TOLERANCE='1%',
 CLS_PN='G155-14701-01',
 VALUE='4.7KOHM',
 PRIM_FILE='./archive_libs/passive/resistor/chips/chips.prt';

PART_NAME
 R342 'RESISTOR-G155-14701-01,4.7KOHMA':;

SECTION_NUMBER 1
 '@TIMECARD_LIB.TIMECARD(SCH_1):PAGE9_I66@PASSIVE.RESISTOR(CHIPS)':
 C_PATH='@timecard_lib.timecard(sch_1):page9_i66@passive.resistor(chips)',
 P_PATH='@timecard_lib.timecard(sch_1):page20_i66@passive.resistor(chips)',
 PATH='I66',
 DRAWING='@TIMECARD_LIB.TIMECARD(SCH_1):PAGE9',
 PACKAGE='0402',
 PHYS_PAGE='20',
 XY='(-2600,8700)',
 ROT='5',
 VER='1',
 CDS_LIB='passive',
 CDS_PART_NAME='RESISTOR-G155-14701-01,4.7KOHMA',
 TOLERANCE='1%',
 CLS_PN='G155-14701-01',
 VALUE='4.7KOHM',
 PRIM_FILE='./archive_libs/passive/resistor/chips/chips.prt';

PART_NAME
 R343 'RESISTOR-G155-100R0-J0,0OHM,-':;

SECTION_NUMBER 1
 '@TIMECARD_LIB.TIMECARD(SCH_1):PAGE8_I34@PASSIVE.RESISTOR(CHIPS)':
 C_PATH='@timecard_lib.timecard(sch_1):page8_i34@passive.resistor(chips)',
 P_PATH='@timecard_lib.timecard(sch_1):page19_i34@passive.resistor(chips)',
 PATH='I34',
 DRAWING='@TIMECARD_LIB.TIMECARD(SCH_1):PAGE8',
 PACKAGE='0402',
 PHYS_PAGE='19',
 XY='(-5350,8650)',
 ROT='0',
 VER='1',
 LOCATION='R343',
 CDS_LIB='passive',
 CDS_PART_NAME='RESISTOR-G155-100R0-J0,0OHM,-',
 TOLERANCE='-',
 CLS_PN='G155-100R0-J0',
 VALUE='0OHM',
 PRIM_FILE='./archive_libs/passive/resistor/chips/chips.prt';

PART_NAME
 R344 'RESISTOR-G155-14701-01,4.7KOHMA':;

SECTION_NUMBER 1
 '@TIMECARD_LIB.TIMECARD(SCH_1):PAGE5_I97@PASSIVE.RESISTOR(CHIPS)':
 C_PATH='@timecard_lib.timecard(sch_1):page5_i97@passive.resistor(chips)',
 P_PATH='@timecard_lib.timecard(sch_1):page16_i97@passive.resistor(chips)',
 PATH='I97',
 DRAWING='@TIMECARD_LIB.TIMECARD(SCH_1):PAGE5',
 PACKAGE='0402',
 PHYS_PAGE='16',
 XY='(-9750,5300)',
 ROT='0',
 VER='2',
 CDS_LIB='passive',
 CDS_PART_NAME='RESISTOR-G155-14701-01,4.7KOHMA',
 NO_ASSY='TRUE',
 TOLERANCE='1%',
 CLS_PN='G155-14701-01',
 VALUE='4.7KOHM',
 PRIM_FILE='./archive_libs/passive/resistor/chips/chips.prt';

PART_NAME
 R345 'RESISTOR-G155-133R0-01,33OHM,1%':;

SECTION_NUMBER 1
 '@TIMECARD_LIB.TIMECARD(SCH_1):PAGE5_I90@PASSIVE.RESISTOR(CHIPS)':
 C_PATH='@timecard_lib.timecard(sch_1):page5_i90@passive.resistor(chips)',
 P_PATH='@timecard_lib.timecard(sch_1):page16_i90@passive.resistor(chips)',
 PATH='I90',
 DRAWING='@TIMECARD_LIB.TIMECARD(SCH_1):PAGE5',
 PACKAGE='0402',
 PHYS_PAGE='16',
 XY='(-7500,5850)',
 ROT='0',
 VER='1',
 CDS_LIB='passive',
 CDS_PART_NAME='RESISTOR-G155-133R0-01,33OHM,1%',
 TOLERANCE='1%',
 CLS_PN='G155-133R0-01',
 VALUE='33OHM',
 PRIM_FILE='./archive_libs/passive/resistor/chips/chips.prt';

PART_NAME
 R346 'RESISTOR-G155-100R0-J0,0OHM,-':;

SECTION_NUMBER 1
 '@TIMECARD_LIB.TIMECARD(SCH_1):PAGE8_I33@PASSIVE.RESISTOR(CHIPS)':
 C_PATH='@timecard_lib.timecard(sch_1):page8_i33@passive.resistor(chips)',
 P_PATH='@timecard_lib.timecard(sch_1):page19_i33@passive.resistor(chips)',
 PATH='I33',
 DRAWING='@TIMECARD_LIB.TIMECARD(SCH_1):PAGE8',
 PACKAGE='0402',
 PHYS_PAGE='19',
 XY='(-5350,8550)',
 ROT='0',
 VER='1',
 LOCATION='R346',
 CDS_LIB='passive',
 CDS_PART_NAME='RESISTOR-G155-100R0-J0,0OHM,-',
 TOLERANCE='-',
 CLS_PN='G155-100R0-J0',
 VALUE='0OHM',
 PRIM_FILE='./archive_libs/passive/resistor/chips/chips.prt';

PART_NAME
 R347 'RESISTOR-G155-100R0-J0,0OHM,-':;

SECTION_NUMBER 1
 '@TIMECARD_LIB.TIMECARD(SCH_1):PAGE8_I32@PASSIVE.RESISTOR(CHIPS)':
 C_PATH='@timecard_lib.timecard(sch_1):page8_i32@passive.resistor(chips)',
 P_PATH='@timecard_lib.timecard(sch_1):page19_i32@passive.resistor(chips)',
 PATH='I32',
 DRAWING='@TIMECARD_LIB.TIMECARD(SCH_1):PAGE8',
 PACKAGE='0402',
 PHYS_PAGE='19',
 XY='(-5350,8450)',
 ROT='0',
 VER='1',
 LOCATION='R347',
 CDS_LIB='passive',
 CDS_PART_NAME='RESISTOR-G155-100R0-J0,0OHM,-',
 TOLERANCE='-',
 CLS_PN='G155-100R0-J0',
 VALUE='0OHM',
 PRIM_FILE='./archive_libs/passive/resistor/chips/chips.prt';

PART_NAME
 R348 'RESISTOR-G155-133R0-01,33OHM,1%':;

SECTION_NUMBER 1
 '@TIMECARD_LIB.TIMECARD(SCH_1):PAGE161_I260@PASSIVE.RESISTOR(CHIPS)':
 C_PATH='@timecard_lib.timecard(sch_1):page161_i260@passive.resistor(chips)',
 P_PATH='@timecard_lib.timecard(sch_1):page11_i260@passive.resistor(chips)',
 PATH='I260',
 DRAWING='@TIMECARD_LIB.TIMECARD(SCH_1):PAGE161',
 PACKAGE='0402',
 PHYS_PAGE='11',
 XY='(-5350,7850)',
 ROT='0',
 VER='1',
 CDS_LIB='passive',
 CDS_PART_NAME='RESISTOR-G155-133R0-01,33OHM,1%',
 TOLERANCE='1%',
 CLS_PN='G155-133R0-01',
 VALUE='33OHM',
 PRIM_FILE='./archive_libs/passive/resistor/chips/chips.prt';

PART_NAME
 R349 'RESISTOR-G155-11003-01,100KOHMA':;

SECTION_NUMBER 1
 '@TIMECARD_LIB.TIMECARD(SCH_1):PAGE524_I184@PASSIVE.RESISTOR(CHIPS)':
 C_PATH='@timecard_lib.timecard(sch_1):page524_i184@passive.resistor(chips)',
 P_PATH='@timecard_lib.timecard(sch_1):page24_i184@passive.resistor(chips)',
 PATH='I184',
 DRAWING='@TIMECARD_LIB.TIMECARD(SCH_1):PAGE524',
 PACKAGE='0402',
 PHYS_PAGE='24',
 XY='(-4200,9000)',
 ROT='1',
 VER='2',
 CDS_LIB='passive',
 CDS_PART_NAME='RESISTOR-G155-11003-01,100KOHMA',
 TOLERANCE='1%',
 CLS_PN='G155-11003-01',
 VALUE='100KOHM',
 PRIM_FILE='./archive_libs/passive/resistor/chips/chips.prt';

PART_NAME
 R350 'RESISTOR-G155-100R0-J0,0OHM,-':;

SECTION_NUMBER 1
 '@TIMECARD_LIB.TIMECARD(SCH_1):PAGE8_I31@PASSIVE.RESISTOR(CHIPS)':
 C_PATH='@timecard_lib.timecard(sch_1):page8_i31@passive.resistor(chips)',
 P_PATH='@timecard_lib.timecard(sch_1):page19_i31@passive.resistor(chips)',
 PATH='I31',
 DRAWING='@TIMECARD_LIB.TIMECARD(SCH_1):PAGE8',
 PACKAGE='0402',
 PHYS_PAGE='19',
 XY='(-5350,8350)',
 ROT='0',
 VER='1',
 LOCATION='R350',
 CDS_LIB='passive',
 CDS_PART_NAME='RESISTOR-G155-100R0-J0,0OHM,-',
 TOLERANCE='-',
 CLS_PN='G155-100R0-J0',
 VALUE='0OHM',
 PRIM_FILE='./archive_libs/passive/resistor/chips/chips.prt';

PART_NAME
 R351 'RESISTOR-G155-100R0-J0,0OHM,-':;

SECTION_NUMBER 1
 '@TIMECARD_LIB.TIMECARD(SCH_1):PAGE8_I30@PASSIVE.RESISTOR(CHIPS)':
 C_PATH='@timecard_lib.timecard(sch_1):page8_i30@passive.resistor(chips)',
 P_PATH='@timecard_lib.timecard(sch_1):page19_i30@passive.resistor(chips)',
 PATH='I30',
 DRAWING='@TIMECARD_LIB.TIMECARD(SCH_1):PAGE8',
 PACKAGE='0402',
 PHYS_PAGE='19',
 XY='(-5350,8250)',
 ROT='0',
 VER='1',
 CDS_LIB='passive',
 CDS_PART_NAME='RESISTOR-G155-100R0-J0,0OHM,-',
 TOLERANCE='-',
 CLS_PN='G155-100R0-J0',
 VALUE='0OHM',
 PRIM_FILE='./archive_libs/passive/resistor/chips/chips.prt';

PART_NAME
 R352 'RESISTOR-G155-11000-01,100OHM,A':;

SECTION_NUMBER 1
 '@TIMECARD_LIB.TIMECARD(SCH_1):PAGE524_I154@PASSIVE.RESISTOR(CHIPS)':
 C_PATH='@timecard_lib.timecard(sch_1):page524_i154@passive.resistor(chips)',
 P_PATH='@timecard_lib.timecard(sch_1):page24_i154@passive.resistor(chips)',
 PATH='I154',
 DRAWING='@TIMECARD_LIB.TIMECARD(SCH_1):PAGE524',
 PACKAGE='0402',
 PHYS_PAGE='24',
 XY='(-5300,9550)',
 ROT='0',
 VER='1',
 CDS_LIB='passive',
 CDS_PART_NAME='RESISTOR-G155-11000-01,100OHM,A',
 TOLERANCE='1%',
 CLS_PN='G155-11000-01',
 VALUE='100OHM',
 PRIM_FILE='./archive_libs/passive/resistor/chips/chips.prt';

PART_NAME
 R353 'RESISTOR-G155-11000-01,100OHM,A':;

SECTION_NUMBER 1
 '@TIMECARD_LIB.TIMECARD(SCH_1):PAGE524_I153@PASSIVE.RESISTOR(CHIPS)':
 C_PATH='@timecard_lib.timecard(sch_1):page524_i153@passive.resistor(chips)',
 P_PATH='@timecard_lib.timecard(sch_1):page24_i153@passive.resistor(chips)',
 PATH='I153',
 DRAWING='@TIMECARD_LIB.TIMECARD(SCH_1):PAGE524',
 PACKAGE='0402',
 PHYS_PAGE='24',
 XY='(-5300,9650)',
 ROT='0',
 VER='1',
 CDS_LIB='passive',
 CDS_PART_NAME='RESISTOR-G155-11000-01,100OHM,A',
 TOLERANCE='1%',
 CLS_PN='G155-11000-01',
 VALUE='100OHM',
 PRIM_FILE='./archive_libs/passive/resistor/chips/chips.prt';

PART_NAME
 R354 'RESISTOR-G155-133R0-01,33OHM,1%':
 SIGNAL_MODEL='DEFAULT_RESISTOR_33OHM_2_1';

SECTION_NUMBER 1
 '@TIMECARD_LIB.TIMECARD(SCH_1):PAGE3_I114@PASSIVE.RESISTOR(CHIPS)':
 C_PATH='@timecard_lib.timecard(sch_1):page3_i114@passive.resistor(chips)',
 P_PATH='@timecard_lib.timecard(sch_1):page9_i114@passive.resistor(chips)',
 PATH='I114',
 DRAWING='@TIMECARD_LIB.TIMECARD(SCH_1):PAGE3',
 PACKAGE='0402',
 PHYS_PAGE='9',
 XY='(-7900,2100)',
 ROT='0',
 VER='1',
 CDS_LIB='passive',
 CDS_PART_NAME='RESISTOR-G155-133R0-01,33OHM,1%',
 NO_ASSY='TRUE',
 TOLERANCE='1%',
 CLS_PN='G155-133R0-01',
 SIGNAL_MODEL='DEFAULT_RESISTOR_33OHM_2_1',
 VALUE='33OHM',
 PRIM_FILE='./archive_libs/passive/resistor/chips/chips.prt';

PART_NAME
 R355 'RESISTOR-G155-11002-01,10KOHM,A':;

SECTION_NUMBER 1
 '@TIMECARD_LIB.TIMECARD(SCH_1):PAGE163_I120@PASSIVE.RESISTOR(CHIPS)':
 C_PATH='@timecard_lib.timecard(sch_1):page163_i120@passive.resistor(chips)',
 P_PATH='@timecard_lib.timecard(sch_1):page13_i120@passive.resistor(chips)',
 PATH='I120',
 DRAWING='@TIMECARD_LIB.TIMECARD(SCH_1):PAGE163',
 PACKAGE='0402',
 PHYS_PAGE='13',
 XY='(-3850,5350)',
 ROT='1',
 VER='2',
 CDS_LIB='passive',
 CDS_PART_NAME='RESISTOR-G155-11002-01,10KOHM,A',
 TOLERANCE='1%',
 CLS_PN='G155-11002-01',
 VALUE='10KOHM',
 PRIM_FILE='./archive_libs/passive/resistor/chips/chips.prt';

PART_NAME
 R356 'RESISTOR-G155-100R0-J0,0OHM,-':;

SECTION_NUMBER 1
 '@TIMECARD_LIB.TIMECARD(SCH_1):PAGE3_I122@PASSIVE.RESISTOR(CHIPS)':
 C_PATH='@timecard_lib.timecard(sch_1):page3_i122@passive.resistor(chips)',
 P_PATH='@timecard_lib.timecard(sch_1):page9_i122@passive.resistor(chips)',
 PATH='I122',
 DRAWING='@TIMECARD_LIB.TIMECARD(SCH_1):PAGE3',
 PACKAGE='0402',
 PHYS_PAGE='9',
 XY='(900,7150)',
 ROT='0',
 VER='1',
 CDS_LIB='passive',
 CDS_PART_NAME='RESISTOR-G155-100R0-J0,0OHM,-',
 TOLERANCE='-',
 CLS_PN='G155-100R0-J0',
 VALUE='0OHM',
 PRIM_FILE='./archive_libs/passive/resistor/chips/chips.prt';

PART_NAME
 R357 'RESISTOR-G157-100R0-J0,0OHM,-':;

SECTION_NUMBER 1
 '@TIMECARD_LIB.TIMECARD(SCH_1):PAGE527_I245@PASSIVE.RESISTOR(CHIPS)':
 C_PATH='@timecard_lib.timecard(sch_1):page527_i245@passive.resistor(chips)',
 P_PATH='@timecard_lib.timecard(sch_1):page21_i245@passive.resistor(chips)',
 PATH='I245',
 DRAWING='@TIMECARD_LIB.TIMECARD(SCH_1):PAGE527',
 PACKAGE='0805',
 PHYS_PAGE='21',
 XY='(750,1850)',
 ROT='0',
 VER='1',
 CDS_LIB='passive',
 CDS_PART_NAME='RESISTOR-G157-100R0-J0,0OHM,-',
 NO_ASSY='TRUE',
 TOLERANCE='-',
 CLS_PN='G157-100R0-J0',
 VALUE='0OHM',
 PRIM_FILE='./archive_libs/passive/resistor/chips/chips.prt';

PART_NAME
 R358 'RESISTOR-G155-11002-01,10KOHM,A':;

SECTION_NUMBER 1
 '@TIMECARD_LIB.TIMECARD(SCH_1):PAGE163_I126@PASSIVE.RESISTOR(CHIPS)':
 C_PATH='@timecard_lib.timecard(sch_1):page163_i126@passive.resistor(chips)',
 P_PATH='@timecard_lib.timecard(sch_1):page13_i126@passive.resistor(chips)',
 PATH='I126',
 DRAWING='@TIMECARD_LIB.TIMECARD(SCH_1):PAGE163',
 PACKAGE='0402',
 PHYS_PAGE='13',
 XY='(-3850,5250)',
 ROT='1',
 VER='2',
 LOCATION='R358',
 CDS_LIB='passive',
 CDS_PART_NAME='RESISTOR-G155-11002-01,10KOHM,A',
 TOLERANCE='1%',
 CLS_PN='G155-11002-01',
 VALUE='10KOHM',
 PRIM_FILE='./archive_libs/passive/resistor/chips/chips.prt';

PART_NAME
 R359 'RESISTOR-G155-11002-01,10KOHM,A':;

SECTION_NUMBER 1
 '@TIMECARD_LIB.TIMECARD(SCH_1):PAGE163_I127@PASSIVE.RESISTOR(CHIPS)':
 C_PATH='@timecard_lib.timecard(sch_1):page163_i127@passive.resistor(chips)',
 P_PATH='@timecard_lib.timecard(sch_1):page13_i127@passive.resistor(chips)',
 PATH='I127',
 DRAWING='@TIMECARD_LIB.TIMECARD(SCH_1):PAGE163',
 PACKAGE='0402',
 PHYS_PAGE='13',
 XY='(-3850,4950)',
 ROT='1',
 VER='2',
 LOCATION='R359',
 CDS_LIB='passive',
 CDS_PART_NAME='RESISTOR-G155-11002-01,10KOHM,A',
 TOLERANCE='1%',
 CLS_PN='G155-11002-01',
 VALUE='10KOHM',
 PRIM_FILE='./archive_libs/passive/resistor/chips/chips.prt';

PART_NAME
 R360 'RESISTOR-G155-11002-01,10KOHM,A':;

SECTION_NUMBER 1
 '@TIMECARD_LIB.TIMECARD(SCH_1):PAGE163_I128@PASSIVE.RESISTOR(CHIPS)':
 C_PATH='@timecard_lib.timecard(sch_1):page163_i128@passive.resistor(chips)',
 P_PATH='@timecard_lib.timecard(sch_1):page13_i128@passive.resistor(chips)',
 PATH='I128',
 DRAWING='@TIMECARD_LIB.TIMECARD(SCH_1):PAGE163',
 PACKAGE='0402',
 PHYS_PAGE='13',
 XY='(-3850,4850)',
 ROT='1',
 VER='2',
 LOCATION='R360',
 CDS_LIB='passive',
 CDS_PART_NAME='RESISTOR-G155-11002-01,10KOHM,A',
 TOLERANCE='1%',
 CLS_PN='G155-11002-01',
 VALUE='10KOHM',
 PRIM_FILE='./archive_libs/passive/resistor/chips/chips.prt';

PART_NAME
 R361 'RESISTOR-G155-14701-01,4.7KOHMA':;

SECTION_NUMBER 1
 '@TIMECARD_LIB.TIMECARD(SCH_1):PAGE12_I261@PASSIVE.RESISTOR(CHIPS)':
 C_PATH='@timecard_lib.timecard(sch_1):page12_i261@passive.resistor(chips)',
 P_PATH='@timecard_lib.timecard(sch_1):page23_i261@passive.resistor(chips)',
 PATH='I261',
 DRAWING='@TIMECARD_LIB.TIMECARD(SCH_1):PAGE12',
 PACKAGE='0402',
 PHYS_PAGE='23',
 XY='(-10700,5200)',
 ROT='1',
 VER='2',
 LOCATION='R361',
 CDS_LIB='passive',
 CDS_PART_NAME='RESISTOR-G155-14701-01,4.7KOHMA',
 TOLERANCE='1%',
 CLS_PN='G155-14701-01',
 VALUE='4.7KOHM',
 PRIM_FILE='./archive_libs/passive/resistor/chips/chips.prt';

PART_NAME
 R362 'RESISTOR-G155-133R0-01,33OHM,1%':;

SECTION_NUMBER 1
 '@TIMECARD_LIB.TIMECARD(SCH_1):PAGE161_I263@PASSIVE.RESISTOR(CHIPS)':
 C_PATH='@timecard_lib.timecard(sch_1):page161_i263@passive.resistor(chips)',
 P_PATH='@timecard_lib.timecard(sch_1):page11_i263@passive.resistor(chips)',
 PATH='I263',
 DRAWING='@TIMECARD_LIB.TIMECARD(SCH_1):PAGE161',
 PACKAGE='0402',
 PHYS_PAGE='11',
 XY='(-5350,7150)',
 ROT='0',
 VER='1',
 CDS_LIB='passive',
 CDS_PART_NAME='RESISTOR-G155-133R0-01,33OHM,1%',
 TOLERANCE='1%',
 CLS_PN='G155-133R0-01',
 VALUE='33OHM',
 PRIM_FILE='./archive_libs/passive/resistor/chips/chips.prt';

PART_NAME
 R363 'RESISTOR-G155-133R0-01,33OHM,1%':
 SIGNAL_MODEL='DEFAULT_RESISTOR_33OHM_2_1';

SECTION_NUMBER 1
 '@TIMECARD_LIB.TIMECARD(SCH_1):PAGE9_I67@PASSIVE.RESISTOR(CHIPS)':
 C_PATH='@timecard_lib.timecard(sch_1):page9_i67@passive.resistor(chips)',
 P_PATH='@timecard_lib.timecard(sch_1):page20_i67@passive.resistor(chips)',
 PATH='I67',
 DRAWING='@TIMECARD_LIB.TIMECARD(SCH_1):PAGE9',
 PACKAGE='0402',
 PHYS_PAGE='20',
 XY='(-3850,8250)',
 ROT='0',
 VER='1',
 CDS_LIB='passive',
 CDS_PART_NAME='RESISTOR-G155-133R0-01,33OHM,1%',
 TOLERANCE='1%',
 CLS_PN='G155-133R0-01',
 SIGNAL_MODEL='DEFAULT_RESISTOR_33OHM_2_1',
 VALUE='33OHM',
 PRIM_FILE='./archive_libs/passive/resistor/chips/chips.prt';

PART_NAME
 R364 'RESISTOR-G155-133R0-01,33OHM,1%':
 SIGNAL_MODEL='DEFAULT_RESISTOR_33OHM_2_1';

SECTION_NUMBER 1
 '@TIMECARD_LIB.TIMECARD(SCH_1):PAGE14_I298@PASSIVE.RESISTOR(CHIPS)':
 C_PATH='@timecard_lib.timecard(sch_1):page14_i298@passive.resistor(chips)',
 P_PATH='@timecard_lib.timecard(sch_1):page26_i298@passive.resistor(chips)',
 PATH='I298',
 DRAWING='@TIMECARD_LIB.TIMECARD(SCH_1):PAGE14',
 PACKAGE='0402',
 PHYS_PAGE='26',
 XY='(-11900,5100)',
 ROT='0',
 VER='1',
 CDS_LIB='passive',
 CDS_PART_NAME='RESISTOR-G155-133R0-01,33OHM,1%',
 TOLERANCE='1%',
 CLS_PN='G155-133R0-01',
 SIGNAL_MODEL='DEFAULT_RESISTOR_33OHM_2_1',
 VALUE='33OHM',
 PRIM_FILE='./archive_libs/passive/resistor/chips/chips.prt';

PART_NAME
 R365 'RESISTOR-G155-14701-01,4.7KOHMA':;

SECTION_NUMBER 1
 '@TIMECARD_LIB.TIMECARD(SCH_1):PAGE12_I88@PASSIVE.RESISTOR(CHIPS)':
 C_PATH='@timecard_lib.timecard(sch_1):page12_i88@passive.resistor(chips)',
 P_PATH='@timecard_lib.timecard(sch_1):page23_i88@passive.resistor(chips)',
 PATH='I88',
 DRAWING='@TIMECARD_LIB.TIMECARD(SCH_1):PAGE12',
 PACKAGE='0402',
 PHYS_PAGE='23',
 XY='(-10750,9500)',
 ROT='1',
 VER='2',
 CDS_LIB='passive',
 CDS_PART_NAME='RESISTOR-G155-14701-01,4.7KOHMA',
 TOLERANCE='1%',
 CLS_PN='G155-14701-01',
 VALUE='4.7KOHM',
 PRIM_FILE='./archive_libs/passive/resistor/chips/chips.prt';

PART_NAME
 R366 'RESISTOR-G155-133R0-01,33OHM,1%':
 SIGNAL_MODEL='DEFAULT_RESISTOR_33OHM_2_1';

SECTION_NUMBER 1
 '@TIMECARD_LIB.TIMECARD(SCH_1):PAGE14_I299@PASSIVE.RESISTOR(CHIPS)':
 C_PATH='@timecard_lib.timecard(sch_1):page14_i299@passive.resistor(chips)',
 P_PATH='@timecard_lib.timecard(sch_1):page26_i299@passive.resistor(chips)',
 PATH='I299',
 DRAWING='@TIMECARD_LIB.TIMECARD(SCH_1):PAGE14',
 PACKAGE='0402',
 PHYS_PAGE='26',
 XY='(-11900,5000)',
 ROT='0',
 VER='1',
 CDS_LIB='passive',
 CDS_PART_NAME='RESISTOR-G155-133R0-01,33OHM,1%',
 TOLERANCE='1%',
 CLS_PN='G155-133R0-01',
 SIGNAL_MODEL='DEFAULT_RESISTOR_33OHM_2_1',
 VALUE='33OHM',
 PRIM_FILE='./archive_libs/passive/resistor/chips/chips.prt';

PART_NAME
 R367 'RESISTOR-G155-149R9-01,49.9OHMA':;

SECTION_NUMBER 1
 '@TIMECARD_LIB.TIMECARD(SCH_1):PAGE12_I209@PASSIVE.RESISTOR(CHIPS)':
 C_PATH='@timecard_lib.timecard(sch_1):page12_i209@passive.resistor(chips)',
 P_PATH='@timecard_lib.timecard(sch_1):page23_i209@passive.resistor(chips)',
 PATH='I209',
 DRAWING='@TIMECARD_LIB.TIMECARD(SCH_1):PAGE12',
 PACKAGE='0402',
 PHYS_PAGE='23',
 XY='(-6400,8950)',
 ROT='3',
 VER='2',
 CDS_LIB='passive',
 CDS_PART_NAME='RESISTOR-G155-149R9-01,49.9OHMA',
 TOLERANCE='1%',
 CLS_PN='G155-149R9-01',
 VALUE='49.9OHM',
 PRIM_FILE='./archive_libs/passive/resistor/chips/chips.prt';

PART_NAME
 R368 'RESISTOR-G155-14701-01,4.7KOHMA':;

SECTION_NUMBER 1
 '@TIMECARD_LIB.TIMECARD(SCH_1):PAGE12_I233@PASSIVE.RESISTOR(CHIPS)':
 C_PATH='@timecard_lib.timecard(sch_1):page12_i233@passive.resistor(chips)',
 P_PATH='@timecard_lib.timecard(sch_1):page23_i233@passive.resistor(chips)',
 PATH='I233',
 DRAWING='@TIMECARD_LIB.TIMECARD(SCH_1):PAGE12',
 PACKAGE='0402',
 PHYS_PAGE='23',
 XY='(-10700,7350)',
 ROT='1',
 VER='2',
 LOCATION='R368',
 CDS_LIB='passive',
 CDS_PART_NAME='RESISTOR-G155-14701-01,4.7KOHMA',
 TOLERANCE='1%',
 CLS_PN='G155-14701-01',
 VALUE='4.7KOHM',
 PRIM_FILE='./archive_libs/passive/resistor/chips/chips.prt';

PART_NAME
 R370 'RESISTOR-G155-149R9-01,49.9OHMA':;

SECTION_NUMBER 1
 '@TIMECARD_LIB.TIMECARD(SCH_1):PAGE12_I229@PASSIVE.RESISTOR(CHIPS)':
 C_PATH='@timecard_lib.timecard(sch_1):page12_i229@passive.resistor(chips)',
 P_PATH='@timecard_lib.timecard(sch_1):page23_i229@passive.resistor(chips)',
 PATH='I229',
 DRAWING='@TIMECARD_LIB.TIMECARD(SCH_1):PAGE12',
 PACKAGE='0402',
 PHYS_PAGE='23',
 XY='(-6350,6800)',
 ROT='3',
 VER='2',
 LOCATION='R370',
 CDS_LIB='passive',
 CDS_PART_NAME='RESISTOR-G155-149R9-01,49.9OHMA',
 TOLERANCE='1%',
 CLS_PN='G155-149R9-01',
 VALUE='49.9OHM',
 PRIM_FILE='./archive_libs/passive/resistor/chips/chips.prt';

PART_NAME
 R371 'RESISTOR-G155-149R9-01,49.9OHMA':;

SECTION_NUMBER 1
 '@TIMECARD_LIB.TIMECARD(SCH_1):PAGE12_I258@PASSIVE.RESISTOR(CHIPS)':
 C_PATH='@timecard_lib.timecard(sch_1):page12_i258@passive.resistor(chips)',
 P_PATH='@timecard_lib.timecard(sch_1):page23_i258@passive.resistor(chips)',
 PATH='I258',
 DRAWING='@TIMECARD_LIB.TIMECARD(SCH_1):PAGE12',
 PACKAGE='0402',
 PHYS_PAGE='23',
 XY='(-6350,4650)',
 ROT='3',
 VER='2',
 LOCATION='R371',
 CDS_LIB='passive',
 CDS_PART_NAME='RESISTOR-G155-149R9-01,49.9OHMA',
 TOLERANCE='1%',
 CLS_PN='G155-149R9-01',
 VALUE='49.9OHM',
 PRIM_FILE='./archive_libs/passive/resistor/chips/chips.prt';

PART_NAME
 R372 'RESISTOR-G155-149R9-01,49.9OHMA':;

SECTION_NUMBER 1
 '@TIMECARD_LIB.TIMECARD(SCH_1):PAGE12_I275@PASSIVE.RESISTOR(CHIPS)':
 C_PATH='@timecard_lib.timecard(sch_1):page12_i275@passive.resistor(chips)',
 P_PATH='@timecard_lib.timecard(sch_1):page23_i275@passive.resistor(chips)',
 PATH='I275',
 DRAWING='@TIMECARD_LIB.TIMECARD(SCH_1):PAGE12',
 PACKAGE='0402',
 PHYS_PAGE='23',
 XY='(-6300,2500)',
 ROT='3',
 VER='2',
 LOCATION='R372',
 CDS_LIB='passive',
 CDS_PART_NAME='RESISTOR-G155-149R9-01,49.9OHMA',
 TOLERANCE='1%',
 CLS_PN='G155-149R9-01',
 VALUE='49.9OHM',
 PRIM_FILE='./archive_libs/passive/resistor/chips/chips.prt';

PART_NAME
 R373 'RESISTOR-G155-11000-01,100OHM,A':;

SECTION_NUMBER 1
 '@TIMECARD_LIB.TIMECARD(SCH_1):PAGE14_I181@PASSIVE.RESISTOR(CHIPS)':
 C_PATH='@timecard_lib.timecard(sch_1):page14_i181@passive.resistor(chips)',
 P_PATH='@timecard_lib.timecard(sch_1):page26_i181@passive.resistor(chips)',
 PATH='I181',
 DRAWING='@TIMECARD_LIB.TIMECARD(SCH_1):PAGE14',
 PACKAGE='0402',
 PHYS_PAGE='26',
 XY='(-2800,9400)',
 ROT='0',
 VER='1',
 CDS_LIB='passive',
 CDS_PART_NAME='RESISTOR-G155-11000-01,100OHM,A',
 NO_ASSY='TRUE',
 TOLERANCE='1%',
 CLS_PN='G155-11000-01',
 VALUE='100OHM',
 PRIM_FILE='./archive_libs/passive/resistor/chips/chips.prt';

PART_NAME
 R374 'RESISTOR-G155-11000-01,100OHM,A':;

SECTION_NUMBER 1
 '@TIMECARD_LIB.TIMECARD(SCH_1):PAGE14_I168@PASSIVE.RESISTOR(CHIPS)':
 C_PATH='@timecard_lib.timecard(sch_1):page14_i168@passive.resistor(chips)',
 P_PATH='@timecard_lib.timecard(sch_1):page26_i168@passive.resistor(chips)',
 PATH='I168',
 DRAWING='@TIMECARD_LIB.TIMECARD(SCH_1):PAGE14',
 PACKAGE='0402',
 PHYS_PAGE='26',
 XY='(-2800,7550)',
 ROT='0',
 VER='1',
 CDS_LIB='passive',
 CDS_PART_NAME='RESISTOR-G155-11000-01,100OHM,A',
 NO_ASSY='TRUE',
 TOLERANCE='1%',
 CLS_PN='G155-11000-01',
 VALUE='100OHM',
 PRIM_FILE='./archive_libs/passive/resistor/chips/chips.prt';

PART_NAME
 R375 'RESISTOR-G155-11000-01,100OHM,A':;

SECTION_NUMBER 1
 '@TIMECARD_LIB.TIMECARD(SCH_1):PAGE14_I174@PASSIVE.RESISTOR(CHIPS)':
 C_PATH='@timecard_lib.timecard(sch_1):page14_i174@passive.resistor(chips)',
 P_PATH='@timecard_lib.timecard(sch_1):page26_i174@passive.resistor(chips)',
 PATH='I174',
 DRAWING='@TIMECARD_LIB.TIMECARD(SCH_1):PAGE14',
 PACKAGE='0402',
 PHYS_PAGE='26',
 XY='(-2800,8150)',
 ROT='0',
 VER='1',
 CDS_LIB='passive',
 CDS_PART_NAME='RESISTOR-G155-11000-01,100OHM,A',
 NO_ASSY='TRUE',
 TOLERANCE='1%',
 CLS_PN='G155-11000-01',
 VALUE='100OHM',
 PRIM_FILE='./archive_libs/passive/resistor/chips/chips.prt';

PART_NAME
 R376 'RESISTOR-G155-11000-01,100OHM,A':;

SECTION_NUMBER 1
 '@TIMECARD_LIB.TIMECARD(SCH_1):PAGE14_I184@PASSIVE.RESISTOR(CHIPS)':
 C_PATH='@timecard_lib.timecard(sch_1):page14_i184@passive.resistor(chips)',
 P_PATH='@timecard_lib.timecard(sch_1):page26_i184@passive.resistor(chips)',
 PATH='I184',
 DRAWING='@TIMECARD_LIB.TIMECARD(SCH_1):PAGE14',
 PACKAGE='0402',
 PHYS_PAGE='26',
 XY='(-2800,7850)',
 ROT='0',
 VER='1',
 CDS_LIB='passive',
 CDS_PART_NAME='RESISTOR-G155-11000-01,100OHM,A',
 NO_ASSY='TRUE',
 TOLERANCE='1%',
 CLS_PN='G155-11000-01',
 VALUE='100OHM',
 PRIM_FILE='./archive_libs/passive/resistor/chips/chips.prt';

PART_NAME
 R377 'RESISTOR-G155-14701-01,4.7KOHMA':;

SECTION_NUMBER 1
 '@TIMECARD_LIB.TIMECARD(SCH_1):PAGE12_I206@PASSIVE.RESISTOR(CHIPS)':
 C_PATH='@timecard_lib.timecard(sch_1):page12_i206@passive.resistor(chips)',
 P_PATH='@timecard_lib.timecard(sch_1):page23_i206@passive.resistor(chips)',
 PATH='I206',
 DRAWING='@TIMECARD_LIB.TIMECARD(SCH_1):PAGE12',
 PACKAGE='0402',
 PHYS_PAGE='23',
 XY='(-10750,9400)',
 ROT='1',
 VER='2',
 LOCATION='R377',
 CDS_LIB='passive',
 CDS_PART_NAME='RESISTOR-G155-14701-01,4.7KOHMA',
 TOLERANCE='1%',
 CLS_PN='G155-14701-01',
 VALUE='4.7KOHM',
 PRIM_FILE='./archive_libs/passive/resistor/chips/chips.prt';

PART_NAME
 R379 'RESISTOR-G155-14701-01,4.7KOHMA':;

SECTION_NUMBER 1
 '@TIMECARD_LIB.TIMECARD(SCH_1):PAGE12_I234@PASSIVE.RESISTOR(CHIPS)':
 C_PATH='@timecard_lib.timecard(sch_1):page12_i234@passive.resistor(chips)',
 P_PATH='@timecard_lib.timecard(sch_1):page23_i234@passive.resistor(chips)',
 PATH='I234',
 DRAWING='@TIMECARD_LIB.TIMECARD(SCH_1):PAGE12',
 PACKAGE='0402',
 PHYS_PAGE='23',
 XY='(-10700,7250)',
 ROT='1',
 VER='2',
 LOCATION='R379',
 CDS_LIB='passive',
 CDS_PART_NAME='RESISTOR-G155-14701-01,4.7KOHMA',
 TOLERANCE='1%',
 CLS_PN='G155-14701-01',
 VALUE='4.7KOHM',
 PRIM_FILE='./archive_libs/passive/resistor/chips/chips.prt';

PART_NAME
 R381 'RESISTOR-G155-14701-01,4.7KOHMA':;

SECTION_NUMBER 1
 '@TIMECARD_LIB.TIMECARD(SCH_1):PAGE12_I262@PASSIVE.RESISTOR(CHIPS)':
 C_PATH='@timecard_lib.timecard(sch_1):page12_i262@passive.resistor(chips)',
 P_PATH='@timecard_lib.timecard(sch_1):page23_i262@passive.resistor(chips)',
 PATH='I262',
 DRAWING='@TIMECARD_LIB.TIMECARD(SCH_1):PAGE12',
 PACKAGE='0402',
 PHYS_PAGE='23',
 XY='(-10700,5100)',
 ROT='1',
 VER='2',
 LOCATION='R381',
 CDS_LIB='passive',
 CDS_PART_NAME='RESISTOR-G155-14701-01,4.7KOHMA',
 TOLERANCE='1%',
 CLS_PN='G155-14701-01',
 VALUE='4.7KOHM',
 PRIM_FILE='./archive_libs/passive/resistor/chips/chips.prt';

PART_NAME
 R383 'RESISTOR-G155-14701-01,4.7KOHMA':;

SECTION_NUMBER 1
 '@TIMECARD_LIB.TIMECARD(SCH_1):PAGE12_I281@PASSIVE.RESISTOR(CHIPS)':
 C_PATH='@timecard_lib.timecard(sch_1):page12_i281@passive.resistor(chips)',
 P_PATH='@timecard_lib.timecard(sch_1):page23_i281@passive.resistor(chips)',
 PATH='I281',
 DRAWING='@TIMECARD_LIB.TIMECARD(SCH_1):PAGE12',
 PACKAGE='0402',
 PHYS_PAGE='23',
 XY='(-10650,2950)',
 ROT='1',
 VER='2',
 LOCATION='R383',
 CDS_LIB='passive',
 CDS_PART_NAME='RESISTOR-G155-14701-01,4.7KOHMA',
 TOLERANCE='1%',
 CLS_PN='G155-14701-01',
 VALUE='4.7KOHM',
 PRIM_FILE='./archive_libs/passive/resistor/chips/chips.prt';

PART_NAME
 R385 'RESISTOR-G155-133R0-01,33OHM,1%':;

SECTION_NUMBER 1
 '@TIMECARD_LIB.TIMECARD(SCH_1):PAGE14_I107@PASSIVE.RESISTOR(CHIPS)':
 C_PATH='@timecard_lib.timecard(sch_1):page14_i107@passive.resistor(chips)',
 P_PATH='@timecard_lib.timecard(sch_1):page26_i107@passive.resistor(chips)',
 PATH='I107',
 DRAWING='@TIMECARD_LIB.TIMECARD(SCH_1):PAGE14',
 PACKAGE='0402',
 PHYS_PAGE='26',
 XY='(-2800,10750)',
 ROT='0',
 VER='1',
 CDS_LIB='passive',
 CDS_PART_NAME='RESISTOR-G155-133R0-01,33OHM,1%',
 TOLERANCE='1%',
 CLS_PN='G155-133R0-01',
 VALUE='33OHM',
 PRIM_FILE='./archive_libs/passive/resistor/chips/chips.prt';

PART_NAME
 R386 'RESISTOR-G155-133R0-01,33OHM,1%':;

SECTION_NUMBER 1
 '@TIMECARD_LIB.TIMECARD(SCH_1):PAGE14_I108@PASSIVE.RESISTOR(CHIPS)':
 C_PATH='@timecard_lib.timecard(sch_1):page14_i108@passive.resistor(chips)',
 P_PATH='@timecard_lib.timecard(sch_1):page26_i108@passive.resistor(chips)',
 PATH='I108',
 DRAWING='@TIMECARD_LIB.TIMECARD(SCH_1):PAGE14',
 PACKAGE='0402',
 PHYS_PAGE='26',
 XY='(-2800,11350)',
 ROT='0',
 VER='1',
 CDS_LIB='passive',
 CDS_PART_NAME='RESISTOR-G155-133R0-01,33OHM,1%',
 TOLERANCE='1%',
 CLS_PN='G155-133R0-01',
 VALUE='33OHM',
 PRIM_FILE='./archive_libs/passive/resistor/chips/chips.prt';

PART_NAME
 R387 'RESISTOR-G155-133R0-01,33OHM,1%':;

SECTION_NUMBER 1
 '@TIMECARD_LIB.TIMECARD(SCH_1):PAGE14_I110@PASSIVE.RESISTOR(CHIPS)':
 C_PATH='@timecard_lib.timecard(sch_1):page14_i110@passive.resistor(chips)',
 P_PATH='@timecard_lib.timecard(sch_1):page26_i110@passive.resistor(chips)',
 PATH='I110',
 DRAWING='@TIMECARD_LIB.TIMECARD(SCH_1):PAGE14',
 PACKAGE='0402',
 PHYS_PAGE='26',
 XY='(-2800,11050)',
 ROT='0',
 VER='1',
 CDS_LIB='passive',
 CDS_PART_NAME='RESISTOR-G155-133R0-01,33OHM,1%',
 TOLERANCE='1%',
 CLS_PN='G155-133R0-01',
 VALUE='33OHM',
 PRIM_FILE='./archive_libs/passive/resistor/chips/chips.prt';

PART_NAME
 R388 'RESISTOR-G155-133R0-01,33OHM,1%':;

SECTION_NUMBER 1
 '@TIMECARD_LIB.TIMECARD(SCH_1):PAGE14_I147@PASSIVE.RESISTOR(CHIPS)':
 C_PATH='@timecard_lib.timecard(sch_1):page14_i147@passive.resistor(chips)',
 P_PATH='@timecard_lib.timecard(sch_1):page26_i147@passive.resistor(chips)',
 PATH='I147',
 DRAWING='@TIMECARD_LIB.TIMECARD(SCH_1):PAGE14',
 PACKAGE='0402',
 PHYS_PAGE='26',
 XY='(-2800,9250)',
 ROT='0',
 VER='1',
 LOCATION='R388',
 CDS_LIB='passive',
 CDS_PART_NAME='RESISTOR-G155-133R0-01,33OHM,1%',
 TOLERANCE='1%',
 CLS_PN='G155-133R0-01',
 VALUE='33OHM',
 PRIM_FILE='./archive_libs/passive/resistor/chips/chips.prt';

PART_NAME
 R389 'RESISTOR-G155-133R0-01,33OHM,1%':;

SECTION_NUMBER 1
 '@TIMECARD_LIB.TIMECARD(SCH_1):PAGE14_I148@PASSIVE.RESISTOR(CHIPS)':
 C_PATH='@timecard_lib.timecard(sch_1):page14_i148@passive.resistor(chips)',
 P_PATH='@timecard_lib.timecard(sch_1):page26_i148@passive.resistor(chips)',
 PATH='I148',
 DRAWING='@TIMECARD_LIB.TIMECARD(SCH_1):PAGE14',
 PACKAGE='0402',
 PHYS_PAGE='26',
 XY='(-2800,9850)',
 ROT='0',
 VER='1',
 LOCATION='R389',
 CDS_LIB='passive',
 CDS_PART_NAME='RESISTOR-G155-133R0-01,33OHM,1%',
 TOLERANCE='1%',
 CLS_PN='G155-133R0-01',
 VALUE='33OHM',
 PRIM_FILE='./archive_libs/passive/resistor/chips/chips.prt';

PART_NAME
 R390 'RESISTOR-G155-133R0-01,33OHM,1%':;

SECTION_NUMBER 1
 '@TIMECARD_LIB.TIMECARD(SCH_1):PAGE14_I146@PASSIVE.RESISTOR(CHIPS)':
 C_PATH='@timecard_lib.timecard(sch_1):page14_i146@passive.resistor(chips)',
 P_PATH='@timecard_lib.timecard(sch_1):page26_i146@passive.resistor(chips)',
 PATH='I146',
 DRAWING='@TIMECARD_LIB.TIMECARD(SCH_1):PAGE14',
 PACKAGE='0402',
 PHYS_PAGE='26',
 XY='(-2800,9550)',
 ROT='0',
 VER='1',
 LOCATION='R390',
 CDS_LIB='passive',
 CDS_PART_NAME='RESISTOR-G155-133R0-01,33OHM,1%',
 TOLERANCE='1%',
 CLS_PN='G155-133R0-01',
 VALUE='33OHM',
 PRIM_FILE='./archive_libs/passive/resistor/chips/chips.prt';

PART_NAME
 R391 'RESISTOR-G155-133R0-01,33OHM,1%':;

SECTION_NUMBER 1
 '@TIMECARD_LIB.TIMECARD(SCH_1):PAGE14_I150@PASSIVE.RESISTOR(CHIPS)':
 C_PATH='@timecard_lib.timecard(sch_1):page14_i150@passive.resistor(chips)',
 P_PATH='@timecard_lib.timecard(sch_1):page26_i150@passive.resistor(chips)',
 PATH='I150',
 DRAWING='@TIMECARD_LIB.TIMECARD(SCH_1):PAGE14',
 PACKAGE='0402',
 PHYS_PAGE='26',
 XY='(-2800,7700)',
 ROT='0',
 VER='1',
 LOCATION='R391',
 CDS_LIB='passive',
 CDS_PART_NAME='RESISTOR-G155-133R0-01,33OHM,1%',
 TOLERANCE='1%',
 CLS_PN='G155-133R0-01',
 VALUE='33OHM',
 PRIM_FILE='./archive_libs/passive/resistor/chips/chips.prt';

PART_NAME
 R392 'RESISTOR-G155-133R0-01,33OHM,1%':;

SECTION_NUMBER 1
 '@TIMECARD_LIB.TIMECARD(SCH_1):PAGE14_I149@PASSIVE.RESISTOR(CHIPS)':
 C_PATH='@timecard_lib.timecard(sch_1):page14_i149@passive.resistor(chips)',
 P_PATH='@timecard_lib.timecard(sch_1):page26_i149@passive.resistor(chips)',
 PATH='I149',
 DRAWING='@TIMECARD_LIB.TIMECARD(SCH_1):PAGE14',
 PACKAGE='0402',
 PHYS_PAGE='26',
 XY='(-2800,8300)',
 ROT='0',
 VER='1',
 LOCATION='R392',
 CDS_LIB='passive',
 CDS_PART_NAME='RESISTOR-G155-133R0-01,33OHM,1%',
 TOLERANCE='1%',
 CLS_PN='G155-133R0-01',
 VALUE='33OHM',
 PRIM_FILE='./archive_libs/passive/resistor/chips/chips.prt';

PART_NAME
 R393 'RESISTOR-G155-133R0-01,33OHM,1%':;

SECTION_NUMBER 1
 '@TIMECARD_LIB.TIMECARD(SCH_1):PAGE14_I151@PASSIVE.RESISTOR(CHIPS)':
 C_PATH='@timecard_lib.timecard(sch_1):page14_i151@passive.resistor(chips)',
 P_PATH='@timecard_lib.timecard(sch_1):page26_i151@passive.resistor(chips)',
 PATH='I151',
 DRAWING='@TIMECARD_LIB.TIMECARD(SCH_1):PAGE14',
 PACKAGE='0402',
 PHYS_PAGE='26',
 XY='(-2800,8000)',
 ROT='0',
 VER='1',
 LOCATION='R393',
 CDS_LIB='passive',
 CDS_PART_NAME='RESISTOR-G155-133R0-01,33OHM,1%',
 TOLERANCE='1%',
 CLS_PN='G155-133R0-01',
 VALUE='33OHM',
 PRIM_FILE='./archive_libs/passive/resistor/chips/chips.prt';

PART_NAME
 R394 'RESISTOR-G155-133R0-01,33OHM,1%':;

SECTION_NUMBER 1
 '@TIMECARD_LIB.TIMECARD(SCH_1):PAGE14_I153@PASSIVE.RESISTOR(CHIPS)':
 C_PATH='@timecard_lib.timecard(sch_1):page14_i153@passive.resistor(chips)',
 P_PATH='@timecard_lib.timecard(sch_1):page26_i153@passive.resistor(chips)',
 PATH='I153',
 DRAWING='@TIMECARD_LIB.TIMECARD(SCH_1):PAGE14',
 PACKAGE='0402',
 PHYS_PAGE='26',
 XY='(-2800,6150)',
 ROT='0',
 VER='1',
 LOCATION='R394',
 CDS_LIB='passive',
 CDS_PART_NAME='RESISTOR-G155-133R0-01,33OHM,1%',
 TOLERANCE='1%',
 CLS_PN='G155-133R0-01',
 VALUE='33OHM',
 PRIM_FILE='./archive_libs/passive/resistor/chips/chips.prt';

PART_NAME
 R395 'RESISTOR-G155-133R0-01,33OHM,1%':;

SECTION_NUMBER 1
 '@TIMECARD_LIB.TIMECARD(SCH_1):PAGE14_I152@PASSIVE.RESISTOR(CHIPS)':
 C_PATH='@timecard_lib.timecard(sch_1):page14_i152@passive.resistor(chips)',
 P_PATH='@timecard_lib.timecard(sch_1):page26_i152@passive.resistor(chips)',
 PATH='I152',
 DRAWING='@TIMECARD_LIB.TIMECARD(SCH_1):PAGE14',
 PACKAGE='0402',
 PHYS_PAGE='26',
 XY='(-2800,6750)',
 ROT='0',
 VER='1',
 LOCATION='R395',
 CDS_LIB='passive',
 CDS_PART_NAME='RESISTOR-G155-133R0-01,33OHM,1%',
 TOLERANCE='1%',
 CLS_PN='G155-133R0-01',
 VALUE='33OHM',
 PRIM_FILE='./archive_libs/passive/resistor/chips/chips.prt';

PART_NAME
 R396 'RESISTOR-G155-133R0-01,33OHM,1%':;

SECTION_NUMBER 1
 '@TIMECARD_LIB.TIMECARD(SCH_1):PAGE14_I154@PASSIVE.RESISTOR(CHIPS)':
 C_PATH='@timecard_lib.timecard(sch_1):page14_i154@passive.resistor(chips)',
 P_PATH='@timecard_lib.timecard(sch_1):page26_i154@passive.resistor(chips)',
 PATH='I154',
 DRAWING='@TIMECARD_LIB.TIMECARD(SCH_1):PAGE14',
 PACKAGE='0402',
 PHYS_PAGE='26',
 XY='(-2800,6450)',
 ROT='0',
 VER='1',
 LOCATION='R396',
 CDS_LIB='passive',
 CDS_PART_NAME='RESISTOR-G155-133R0-01,33OHM,1%',
 TOLERANCE='1%',
 CLS_PN='G155-133R0-01',
 VALUE='33OHM',
 PRIM_FILE='./archive_libs/passive/resistor/chips/chips.prt';

PART_NAME
 R397 'RESISTOR-G155-133R0-01,33OHM,1%':;

SECTION_NUMBER 1
 '@TIMECARD_LIB.TIMECARD(SCH_1):PAGE14_I156@PASSIVE.RESISTOR(CHIPS)':
 C_PATH='@timecard_lib.timecard(sch_1):page14_i156@passive.resistor(chips)',
 P_PATH='@timecard_lib.timecard(sch_1):page26_i156@passive.resistor(chips)',
 PATH='I156',
 DRAWING='@TIMECARD_LIB.TIMECARD(SCH_1):PAGE14',
 PACKAGE='0402',
 PHYS_PAGE='26',
 XY='(-2750,4600)',
 ROT='0',
 VER='1',
 LOCATION='R397',
 CDS_LIB='passive',
 CDS_PART_NAME='RESISTOR-G155-133R0-01,33OHM,1%',
 TOLERANCE='1%',
 CLS_PN='G155-133R0-01',
 VALUE='33OHM',
 PRIM_FILE='./archive_libs/passive/resistor/chips/chips.prt';

PART_NAME
 R398 'RESISTOR-G155-133R0-01,33OHM,1%':;

SECTION_NUMBER 1
 '@TIMECARD_LIB.TIMECARD(SCH_1):PAGE14_I155@PASSIVE.RESISTOR(CHIPS)':
 C_PATH='@timecard_lib.timecard(sch_1):page14_i155@passive.resistor(chips)',
 P_PATH='@timecard_lib.timecard(sch_1):page26_i155@passive.resistor(chips)',
 PATH='I155',
 DRAWING='@TIMECARD_LIB.TIMECARD(SCH_1):PAGE14',
 PACKAGE='0402',
 PHYS_PAGE='26',
 XY='(-2750,5200)',
 ROT='0',
 VER='1',
 LOCATION='R398',
 CDS_LIB='passive',
 CDS_PART_NAME='RESISTOR-G155-133R0-01,33OHM,1%',
 TOLERANCE='1%',
 CLS_PN='G155-133R0-01',
 VALUE='33OHM',
 PRIM_FILE='./archive_libs/passive/resistor/chips/chips.prt';

PART_NAME
 R399 'RESISTOR-G155-133R0-01,33OHM,1%':;

SECTION_NUMBER 1
 '@TIMECARD_LIB.TIMECARD(SCH_1):PAGE14_I157@PASSIVE.RESISTOR(CHIPS)':
 C_PATH='@timecard_lib.timecard(sch_1):page14_i157@passive.resistor(chips)',
 P_PATH='@timecard_lib.timecard(sch_1):page26_i157@passive.resistor(chips)',
 PATH='I157',
 DRAWING='@TIMECARD_LIB.TIMECARD(SCH_1):PAGE14',
 PACKAGE='0402',
 PHYS_PAGE='26',
 XY='(-2750,4900)',
 ROT='0',
 VER='1',
 LOCATION='R399',
 CDS_LIB='passive',
 CDS_PART_NAME='RESISTOR-G155-133R0-01,33OHM,1%',
 TOLERANCE='1%',
 CLS_PN='G155-133R0-01',
 VALUE='33OHM',
 PRIM_FILE='./archive_libs/passive/resistor/chips/chips.prt';

PART_NAME
 R400 'RESISTOR-G155-11000-01,100OHM,A':;

SECTION_NUMBER 1
 '@TIMECARD_LIB.TIMECARD(SCH_1):PAGE14_I177@PASSIVE.RESISTOR(CHIPS)':
 C_PATH='@timecard_lib.timecard(sch_1):page14_i177@passive.resistor(chips)',
 P_PATH='@timecard_lib.timecard(sch_1):page26_i177@passive.resistor(chips)',
 PATH='I177',
 DRAWING='@TIMECARD_LIB.TIMECARD(SCH_1):PAGE14',
 PACKAGE='0402',
 PHYS_PAGE='26',
 XY='(-2800,6000)',
 ROT='0',
 VER='1',
 CDS_LIB='passive',
 CDS_PART_NAME='RESISTOR-G155-11000-01,100OHM,A',
 NO_ASSY='TRUE',
 TOLERANCE='1%',
 CLS_PN='G155-11000-01',
 VALUE='100OHM',
 PRIM_FILE='./archive_libs/passive/resistor/chips/chips.prt';

PART_NAME
 R401 'RESISTOR-G155-11000-01,100OHM,A':;

SECTION_NUMBER 1
 '@TIMECARD_LIB.TIMECARD(SCH_1):PAGE14_I176@PASSIVE.RESISTOR(CHIPS)':
 C_PATH='@timecard_lib.timecard(sch_1):page14_i176@passive.resistor(chips)',
 P_PATH='@timecard_lib.timecard(sch_1):page26_i176@passive.resistor(chips)',
 PATH='I176',
 DRAWING='@TIMECARD_LIB.TIMECARD(SCH_1):PAGE14',
 PACKAGE='0402',
 PHYS_PAGE='26',
 XY='(-2800,6600)',
 ROT='0',
 VER='1',
 CDS_LIB='passive',
 CDS_PART_NAME='RESISTOR-G155-11000-01,100OHM,A',
 NO_ASSY='TRUE',
 TOLERANCE='1%',
 CLS_PN='G155-11000-01',
 VALUE='100OHM',
 PRIM_FILE='./archive_libs/passive/resistor/chips/chips.prt';

PART_NAME
 R402 'RESISTOR-G155-12201-01,2.2KOHMA':;

SECTION_NUMBER 1
 '@TIMECARD_LIB.TIMECARD(SCH_1):PAGE127_I440@PASSIVE.RESISTOR(CHIPS)':
 C_PATH='@timecard_lib.timecard(sch_1):page127_i440@passive.resistor(chips)',
 P_PATH='@timecard_lib.timecard(sch_1):page10_i440@passive.resistor(chips)',
 PATH='I440',
 DRAWING='@TIMECARD_LIB.TIMECARD(SCH_1):PAGE127',
 PACKAGE='0402',
 PHYS_PAGE='10',
 XY='(-10250,800)',
 ROT='0',
 VER='2',
 CDS_LIB='passive',
 CDS_PART_NAME='RESISTOR-G155-12201-01,2.2KOHMA',
 TOLERANCE='1%',
 CLS_PN='G155-12201-01',
 VALUE='2.2KOHM',
 PRIM_FILE='./archive_libs/passive/resistor/chips/chips.prt';

PART_NAME
 R403 'RESISTOR-G155-11002-01,10KOHM,A':;

SECTION_NUMBER 1
 '@TIMECARD_LIB.TIMECARD(SCH_1):PAGE127_I435@PASSIVE.RESISTOR(CHIPS)':
 C_PATH='@timecard_lib.timecard(sch_1):page127_i435@passive.resistor(chips)',
 P_PATH='@timecard_lib.timecard(sch_1):page10_i435@passive.resistor(chips)',
 PATH='I435',
 DRAWING='@TIMECARD_LIB.TIMECARD(SCH_1):PAGE127',
 PACKAGE='0402',
 PHYS_PAGE='10',
 XY='(-11150,1950)',
 ROT='0',
 VER='2',
 CDS_LIB='passive',
 CDS_PART_NAME='RESISTOR-G155-11002-01,10KOHM,A',
 TOLERANCE='1%',
 CLS_PN='G155-11002-01',
 VALUE='10KOHM',
 PRIM_FILE='./archive_libs/passive/resistor/chips/chips.prt';

PART_NAME
 R404 'RESISTOR-G155-11002-01,10KOHM,A':;

SECTION_NUMBER 1
 '@TIMECARD_LIB.TIMECARD(SCH_1):PAGE127_I434@PASSIVE.RESISTOR(CHIPS)':
 C_PATH='@timecard_lib.timecard(sch_1):page127_i434@passive.resistor(chips)',
 P_PATH='@timecard_lib.timecard(sch_1):page10_i434@passive.resistor(chips)',
 PATH='I434',
 DRAWING='@TIMECARD_LIB.TIMECARD(SCH_1):PAGE127',
 PACKAGE='0402',
 PHYS_PAGE='10',
 XY='(-10800,1950)',
 ROT='0',
 VER='2',
 CDS_LIB='passive',
 CDS_PART_NAME='RESISTOR-G155-11002-01,10KOHM,A',
 TOLERANCE='1%',
 CLS_PN='G155-11002-01',
 VALUE='10KOHM',
 PRIM_FILE='./archive_libs/passive/resistor/chips/chips.prt';

PART_NAME
 R405 'RESISTOR-G155-11002-01,10KOHM,A':;

SECTION_NUMBER 1
 '@TIMECARD_LIB.TIMECARD(SCH_1):PAGE127_I432@PASSIVE.RESISTOR(CHIPS)':
 C_PATH='@timecard_lib.timecard(sch_1):page127_i432@passive.resistor(chips)',
 P_PATH='@timecard_lib.timecard(sch_1):page10_i432@passive.resistor(chips)',
 PATH='I432',
 DRAWING='@TIMECARD_LIB.TIMECARD(SCH_1):PAGE127',
 PACKAGE='0402',
 PHYS_PAGE='10',
 XY='(-10450,1950)',
 ROT='0',
 VER='2',
 CDS_LIB='passive',
 CDS_PART_NAME='RESISTOR-G155-11002-01,10KOHM,A',
 TOLERANCE='1%',
 CLS_PN='G155-11002-01',
 VALUE='10KOHM',
 PRIM_FILE='./archive_libs/passive/resistor/chips/chips.prt';

PART_NAME
 R406 'RESISTOR-G155-133R0-01,33OHM,1%':;

SECTION_NUMBER 1
 '@TIMECARD_LIB.TIMECARD(SCH_1):PAGE6_I76@PASSIVE.RESISTOR(CHIPS)':
 C_PATH='@timecard_lib.timecard(sch_1):page6_i76@passive.resistor(chips)',
 P_PATH='@timecard_lib.timecard(sch_1):page17_i76@passive.resistor(chips)',
 PATH='I76',
 DRAWING='@TIMECARD_LIB.TIMECARD(SCH_1):PAGE6',
 PACKAGE='0402',
 PHYS_PAGE='17',
 XY='(-5600,4450)',
 ROT='0',
 VER='1',
 CDS_LIB='passive',
 CDS_PART_NAME='RESISTOR-G155-133R0-01,33OHM,1%',
 TOLERANCE='1%',
 CLS_PN='G155-133R0-01',
 VALUE='33OHM',
 PRIM_FILE='./archive_libs/passive/resistor/chips/chips.prt';

PART_NAME
 R407 'RESISTOR-G155-133R0-01,33OHM,1%':;

SECTION_NUMBER 1
 '@TIMECARD_LIB.TIMECARD(SCH_1):PAGE6_I100@PASSIVE.RESISTOR(CHIPS)':
 C_PATH='@timecard_lib.timecard(sch_1):page6_i100@passive.resistor(chips)',
 P_PATH='@timecard_lib.timecard(sch_1):page17_i100@passive.resistor(chips)',
 PATH='I100',
 DRAWING='@TIMECARD_LIB.TIMECARD(SCH_1):PAGE6',
 PACKAGE='0402',
 PHYS_PAGE='17',
 XY='(-5600,1600)',
 ROT='0',
 VER='1',
 CDS_LIB='passive',
 CDS_PART_NAME='RESISTOR-G155-133R0-01,33OHM,1%',
 TOLERANCE='1%',
 CLS_PN='G155-133R0-01',
 VALUE='33OHM',
 PRIM_FILE='./archive_libs/passive/resistor/chips/chips.prt';

PART_NAME
 R408 'RESISTOR-G155-14701-01,4.7KOHMA':;

SECTION_NUMBER 1
 '@TIMECARD_LIB.TIMECARD(SCH_1):PAGE6_I71@PASSIVE.RESISTOR(CHIPS)':
 C_PATH='@timecard_lib.timecard(sch_1):page6_i71@passive.resistor(chips)',
 P_PATH='@timecard_lib.timecard(sch_1):page17_i71@passive.resistor(chips)',
 PATH='I71',
 DRAWING='@TIMECARD_LIB.TIMECARD(SCH_1):PAGE6',
 PACKAGE='0402',
 PHYS_PAGE='17',
 XY='(-3850,5000)',
 ROT='0',
 VER='2',
 CDS_LIB='passive',
 CDS_PART_NAME='RESISTOR-G155-14701-01,4.7KOHMA',
 NO_ASSY='TRUE',
 TOLERANCE='1%',
 CLS_PN='G155-14701-01',
 VALUE='4.7KOHM',
 PRIM_FILE='./archive_libs/passive/resistor/chips/chips.prt';

PART_NAME
 R409 'RESISTOR-G155-11001-01,1KOHM,1%':;

SECTION_NUMBER 1
 '@TIMECARD_LIB.TIMECARD(SCH_1):PAGE6_I73@PASSIVE.RESISTOR(CHIPS)':
 C_PATH='@timecard_lib.timecard(sch_1):page6_i73@passive.resistor(chips)',
 P_PATH='@timecard_lib.timecard(sch_1):page17_i73@passive.resistor(chips)',
 PATH='I73',
 DRAWING='@TIMECARD_LIB.TIMECARD(SCH_1):PAGE6',
 PACKAGE='0402',
 PHYS_PAGE='17',
 XY='(-3850,3750)',
 ROT='0',
 VER='2',
 CDS_LIB='passive',
 CDS_PART_NAME='RESISTOR-G155-11001-01,1KOHM,1%',
 TOLERANCE='1%',
 CLS_PN='G155-11001-01',
 VALUE='1KOHM',
 PRIM_FILE='./archive_libs/passive/resistor/chips/chips.prt';

PART_NAME
 R410 'RESISTOR-G155-14701-01,4.7KOHMA':;

SECTION_NUMBER 1
 '@TIMECARD_LIB.TIMECARD(SCH_1):PAGE6_I86@PASSIVE.RESISTOR(CHIPS)':
 C_PATH='@timecard_lib.timecard(sch_1):page6_i86@passive.resistor(chips)',
 P_PATH='@timecard_lib.timecard(sch_1):page17_i86@passive.resistor(chips)',
 PATH='I86',
 DRAWING='@TIMECARD_LIB.TIMECARD(SCH_1):PAGE6',
 PACKAGE='0402',
 PHYS_PAGE='17',
 XY='(-3850,2150)',
 ROT='0',
 VER='2',
 CDS_LIB='passive',
 CDS_PART_NAME='RESISTOR-G155-14701-01,4.7KOHMA',
 NO_ASSY='TRUE',
 TOLERANCE='1%',
 CLS_PN='G155-14701-01',
 VALUE='4.7KOHM',
 PRIM_FILE='./archive_libs/passive/resistor/chips/chips.prt';

PART_NAME
 R411 'RESISTOR-G155-11001-01,1KOHM,1%':;

SECTION_NUMBER 1
 '@TIMECARD_LIB.TIMECARD(SCH_1):PAGE6_I95@PASSIVE.RESISTOR(CHIPS)':
 C_PATH='@timecard_lib.timecard(sch_1):page6_i95@passive.resistor(chips)',
 P_PATH='@timecard_lib.timecard(sch_1):page17_i95@passive.resistor(chips)',
 PATH='I95',
 DRAWING='@TIMECARD_LIB.TIMECARD(SCH_1):PAGE6',
 PACKAGE='0402',
 PHYS_PAGE='17',
 XY='(-3850,900)',
 ROT='0',
 VER='2',
 CDS_LIB='passive',
 CDS_PART_NAME='RESISTOR-G155-11001-01,1KOHM,1%',
 TOLERANCE='1%',
 CLS_PN='G155-11001-01',
 VALUE='1KOHM',
 PRIM_FILE='./archive_libs/passive/resistor/chips/chips.prt';

PART_NAME
 R412 'RESISTOR-G155-14701-01,4.7KOHMA':;

SECTION_NUMBER 1
 '@TIMECARD_LIB.TIMECARD(SCH_1):PAGE6_I70@PASSIVE.RESISTOR(CHIPS)':
 C_PATH='@timecard_lib.timecard(sch_1):page6_i70@passive.resistor(chips)',
 P_PATH='@timecard_lib.timecard(sch_1):page17_i70@passive.resistor(chips)',
 PATH='I70',
 DRAWING='@TIMECARD_LIB.TIMECARD(SCH_1):PAGE6',
 PACKAGE='0402',
 PHYS_PAGE='17',
 XY='(-3400,5000)',
 ROT='0',
 VER='2',
 CDS_LIB='passive',
 CDS_PART_NAME='RESISTOR-G155-14701-01,4.7KOHMA',
 NO_ASSY='TRUE',
 TOLERANCE='1%',
 CLS_PN='G155-14701-01',
 VALUE='4.7KOHM',
 PRIM_FILE='./archive_libs/passive/resistor/chips/chips.prt';

PART_NAME
 R413 'RESISTOR-G155-11001-01,1KOHM,1%':;

SECTION_NUMBER 1
 '@TIMECARD_LIB.TIMECARD(SCH_1):PAGE6_I60@PASSIVE.RESISTOR(CHIPS)':
 C_PATH='@timecard_lib.timecard(sch_1):page6_i60@passive.resistor(chips)',
 P_PATH='@timecard_lib.timecard(sch_1):page17_i60@passive.resistor(chips)',
 PATH='I60',
 DRAWING='@TIMECARD_LIB.TIMECARD(SCH_1):PAGE6',
 PACKAGE='0402',
 PHYS_PAGE='17',
 XY='(-3400,3750)',
 ROT='0',
 VER='2',
 CDS_LIB='passive',
 CDS_PART_NAME='RESISTOR-G155-11001-01,1KOHM,1%',
 TOLERANCE='1%',
 CLS_PN='G155-11001-01',
 VALUE='1KOHM',
 PRIM_FILE='./archive_libs/passive/resistor/chips/chips.prt';

PART_NAME
 R414 'RESISTOR-G155-14701-01,4.7KOHMA':;

SECTION_NUMBER 1
 '@TIMECARD_LIB.TIMECARD(SCH_1):PAGE6_I85@PASSIVE.RESISTOR(CHIPS)':
 C_PATH='@timecard_lib.timecard(sch_1):page6_i85@passive.resistor(chips)',
 P_PATH='@timecard_lib.timecard(sch_1):page17_i85@passive.resistor(chips)',
 PATH='I85',
 DRAWING='@TIMECARD_LIB.TIMECARD(SCH_1):PAGE6',
 PACKAGE='0402',
 PHYS_PAGE='17',
 XY='(-3400,2150)',
 ROT='0',
 VER='2',
 CDS_LIB='passive',
 CDS_PART_NAME='RESISTOR-G155-14701-01,4.7KOHMA',
 TOLERANCE='1%',
 CLS_PN='G155-14701-01',
 VALUE='4.7KOHM',
 PRIM_FILE='./archive_libs/passive/resistor/chips/chips.prt';

PART_NAME
 R415 'RESISTOR-G155-11001-01,1KOHM,1%':;

SECTION_NUMBER 1
 '@TIMECARD_LIB.TIMECARD(SCH_1):PAGE6_I94@PASSIVE.RESISTOR(CHIPS)':
 C_PATH='@timecard_lib.timecard(sch_1):page6_i94@passive.resistor(chips)',
 P_PATH='@timecard_lib.timecard(sch_1):page17_i94@passive.resistor(chips)',
 PATH='I94',
 DRAWING='@TIMECARD_LIB.TIMECARD(SCH_1):PAGE6',
 PACKAGE='0402',
 PHYS_PAGE='17',
 XY='(-3400,900)',
 ROT='0',
 VER='2',
 CDS_LIB='passive',
 CDS_PART_NAME='RESISTOR-G155-11001-01,1KOHM,1%',
 NO_ASSY='TRUE',
 TOLERANCE='1%',
 CLS_PN='G155-11001-01',
 VALUE='1KOHM',
 PRIM_FILE='./archive_libs/passive/resistor/chips/chips.prt';

PART_NAME
 R416 'RESISTOR-G155-11001-01,1KOHM,1%':;

SECTION_NUMBER 1
 '@TIMECARD_LIB.TIMECARD(SCH_1):PAGE6_I72@PASSIVE.RESISTOR(CHIPS)':
 C_PATH='@timecard_lib.timecard(sch_1):page6_i72@passive.resistor(chips)',
 P_PATH='@timecard_lib.timecard(sch_1):page17_i72@passive.resistor(chips)',
 PATH='I72',
 DRAWING='@TIMECARD_LIB.TIMECARD(SCH_1):PAGE6',
 PACKAGE='0402',
 PHYS_PAGE='17',
 XY='(-3020,3740)',
 ROT='0',
 VER='2',
 CDS_LIB='passive',
 CDS_PART_NAME='RESISTOR-G155-11001-01,1KOHM,1%',
 NO_ASSY='TRUE',
 TOLERANCE='1%',
 CLS_PN='G155-11001-01',
 VALUE='1KOHM',
 PRIM_FILE='./archive_libs/passive/resistor/chips/chips.prt';

PART_NAME
 R417 'RESISTOR-G155-11001-01,1KOHM,1%':;

SECTION_NUMBER 1
 '@TIMECARD_LIB.TIMECARD(SCH_1):PAGE6_I93@PASSIVE.RESISTOR(CHIPS)':
 C_PATH='@timecard_lib.timecard(sch_1):page6_i93@passive.resistor(chips)',
 P_PATH='@timecard_lib.timecard(sch_1):page17_i93@passive.resistor(chips)',
 PATH='I93',
 DRAWING='@TIMECARD_LIB.TIMECARD(SCH_1):PAGE6',
 PACKAGE='0402',
 PHYS_PAGE='17',
 XY='(-3020,890)',
 ROT='0',
 VER='2',
 CDS_LIB='passive',
 CDS_PART_NAME='RESISTOR-G155-11001-01,1KOHM,1%',
 TOLERANCE='1%',
 CLS_PN='G155-11001-01',
 VALUE='1KOHM',
 PRIM_FILE='./archive_libs/passive/resistor/chips/chips.prt';

PART_NAME
 R418 'RESISTOR-G155-14701-01,4.7KOHMA':;

SECTION_NUMBER 1
 '@TIMECARD_LIB.TIMECARD(SCH_1):PAGE6_I69@PASSIVE.RESISTOR(CHIPS)':
 C_PATH='@timecard_lib.timecard(sch_1):page6_i69@passive.resistor(chips)',
 P_PATH='@timecard_lib.timecard(sch_1):page17_i69@passive.resistor(chips)',
 PATH='I69',
 DRAWING='@TIMECARD_LIB.TIMECARD(SCH_1):PAGE6',
 PACKAGE='0402',
 PHYS_PAGE='17',
 XY='(-3000,5000)',
 ROT='0',
 VER='2',
 CDS_LIB='passive',
 CDS_PART_NAME='RESISTOR-G155-14701-01,4.7KOHMA',
 TOLERANCE='1%',
 CLS_PN='G155-14701-01',
 VALUE='4.7KOHM',
 PRIM_FILE='./archive_libs/passive/resistor/chips/chips.prt';

PART_NAME
 R419 'RESISTOR-G155-14701-01,4.7KOHMA':;

SECTION_NUMBER 1
 '@TIMECARD_LIB.TIMECARD(SCH_1):PAGE6_I84@PASSIVE.RESISTOR(CHIPS)':
 C_PATH='@timecard_lib.timecard(sch_1):page6_i84@passive.resistor(chips)',
 P_PATH='@timecard_lib.timecard(sch_1):page17_i84@passive.resistor(chips)',
 PATH='I84',
 DRAWING='@TIMECARD_LIB.TIMECARD(SCH_1):PAGE6',
 PACKAGE='0402',
 PHYS_PAGE='17',
 XY='(-3000,2150)',
 ROT='0',
 VER='2',
 CDS_LIB='passive',
 CDS_PART_NAME='RESISTOR-G155-14701-01,4.7KOHMA',
 NO_ASSY='TRUE',
 TOLERANCE='1%',
 CLS_PN='G155-14701-01',
 VALUE='4.7KOHM',
 PRIM_FILE='./archive_libs/passive/resistor/chips/chips.prt';

PART_NAME
 R422 'RESISTOR-G155-14701-01,4.7KOHMA':;

SECTION_NUMBER 1
 '@TIMECARD_LIB.TIMECARD(SCH_1):PAGE6_I64@PASSIVE.RESISTOR(CHIPS)':
 C_PATH='@timecard_lib.timecard(sch_1):page6_i64@passive.resistor(chips)',
 P_PATH='@timecard_lib.timecard(sch_1):page17_i64@passive.resistor(chips)',
 PATH='I64',
 DRAWING='@TIMECARD_LIB.TIMECARD(SCH_1):PAGE6',
 PACKAGE='0402',
 PHYS_PAGE='17',
 XY='(-1150,4750)',
 ROT='0',
 VER='2',
 CDS_LIB='passive',
 CDS_PART_NAME='RESISTOR-G155-14701-01,4.7KOHMA',
 TOLERANCE='1%',
 CLS_PN='G155-14701-01',
 VALUE='4.7KOHM',
 PRIM_FILE='./archive_libs/passive/resistor/chips/chips.prt';

PART_NAME
 R423 'RESISTOR-G155-14701-01,4.7KOHMA':;

SECTION_NUMBER 1
 '@TIMECARD_LIB.TIMECARD(SCH_1):PAGE6_I88@PASSIVE.RESISTOR(CHIPS)':
 C_PATH='@timecard_lib.timecard(sch_1):page6_i88@passive.resistor(chips)',
 P_PATH='@timecard_lib.timecard(sch_1):page17_i88@passive.resistor(chips)',
 PATH='I88',
 DRAWING='@TIMECARD_LIB.TIMECARD(SCH_1):PAGE6',
 PACKAGE='0402',
 PHYS_PAGE='17',
 XY='(-1200,1900)',
 ROT='0',
 VER='2',
 CDS_LIB='passive',
 CDS_PART_NAME='RESISTOR-G155-14701-01,4.7KOHMA',
 TOLERANCE='1%',
 CLS_PN='G155-14701-01',
 VALUE='4.7KOHM',
 PRIM_FILE='./archive_libs/passive/resistor/chips/chips.prt';

PART_NAME
 R424 'RESISTOR-G155-11000-01,100OHM,A':;

SECTION_NUMBER 1
 '@TIMECARD_LIB.TIMECARD(SCH_1):PAGE14_I186@PASSIVE.RESISTOR(CHIPS)':
 C_PATH='@timecard_lib.timecard(sch_1):page14_i186@passive.resistor(chips)',
 P_PATH='@timecard_lib.timecard(sch_1):page26_i186@passive.resistor(chips)',
 PATH='I186',
 DRAWING='@TIMECARD_LIB.TIMECARD(SCH_1):PAGE14',
 PACKAGE='0402',
 PHYS_PAGE='26',
 XY='(-2800,6300)',
 ROT='0',
 VER='1',
 CDS_LIB='passive',
 CDS_PART_NAME='RESISTOR-G155-11000-01,100OHM,A',
 NO_ASSY='TRUE',
 TOLERANCE='1%',
 CLS_PN='G155-11000-01',
 VALUE='100OHM',
 PRIM_FILE='./archive_libs/passive/resistor/chips/chips.prt';

PART_NAME
 R425 'RESISTOR-G155-11000-01,100OHM,A':;

SECTION_NUMBER 1
 '@TIMECARD_LIB.TIMECARD(SCH_1):PAGE14_I170@PASSIVE.RESISTOR(CHIPS)':
 C_PATH='@timecard_lib.timecard(sch_1):page14_i170@passive.resistor(chips)',
 P_PATH='@timecard_lib.timecard(sch_1):page26_i170@passive.resistor(chips)',
 PATH='I170',
 DRAWING='@TIMECARD_LIB.TIMECARD(SCH_1):PAGE14',
 PACKAGE='0402',
 PHYS_PAGE='26',
 XY='(-2750,4450)',
 ROT='0',
 VER='1',
 CDS_LIB='passive',
 CDS_PART_NAME='RESISTOR-G155-11000-01,100OHM,A',
 NO_ASSY='TRUE',
 TOLERANCE='1%',
 CLS_PN='G155-11000-01',
 VALUE='100OHM',
 PRIM_FILE='./archive_libs/passive/resistor/chips/chips.prt';

PART_NAME
 R426 'RESISTOR-G155-11000-01,100OHM,A':;

SECTION_NUMBER 1
 '@TIMECARD_LIB.TIMECARD(SCH_1):PAGE14_I179@PASSIVE.RESISTOR(CHIPS)':
 C_PATH='@timecard_lib.timecard(sch_1):page14_i179@passive.resistor(chips)',
 P_PATH='@timecard_lib.timecard(sch_1):page26_i179@passive.resistor(chips)',
 PATH='I179',
 DRAWING='@TIMECARD_LIB.TIMECARD(SCH_1):PAGE14',
 PACKAGE='0402',
 PHYS_PAGE='26',
 XY='(-2750,5050)',
 ROT='0',
 VER='1',
 CDS_LIB='passive',
 CDS_PART_NAME='RESISTOR-G155-11000-01,100OHM,A',
 NO_ASSY='TRUE',
 TOLERANCE='1%',
 CLS_PN='G155-11000-01',
 VALUE='100OHM',
 PRIM_FILE='./archive_libs/passive/resistor/chips/chips.prt';

PART_NAME
 R427 'RESISTOR-G155-11000-01,100OHM,A':;

SECTION_NUMBER 1
 '@TIMECARD_LIB.TIMECARD(SCH_1):PAGE14_I188@PASSIVE.RESISTOR(CHIPS)':
 C_PATH='@timecard_lib.timecard(sch_1):page14_i188@passive.resistor(chips)',
 P_PATH='@timecard_lib.timecard(sch_1):page26_i188@passive.resistor(chips)',
 PATH='I188',
 DRAWING='@TIMECARD_LIB.TIMECARD(SCH_1):PAGE14',
 PACKAGE='0402',
 PHYS_PAGE='26',
 XY='(-2750,4750)',
 ROT='0',
 VER='1',
 CDS_LIB='passive',
 CDS_PART_NAME='RESISTOR-G155-11000-01,100OHM,A',
 NO_ASSY='TRUE',
 TOLERANCE='1%',
 CLS_PN='G155-11000-01',
 VALUE='100OHM',
 PRIM_FILE='./archive_libs/passive/resistor/chips/chips.prt';

PART_NAME
 R428 'RESISTOR-G155-133R0-01,33OHM,1%':;

SECTION_NUMBER 1
 '@TIMECARD_LIB.TIMECARD(SCH_1):PAGE16_I1708@PASSIVE.RESISTOR(CHIPS)':
 C_PATH='@timecard_lib.timecard(sch_1):page16_i1708@passive.resistor(chips)',
 P_PATH='@timecard_lib.timecard(sch_1):page25_i1708@passive.resistor(chips)',
 PATH='I1708',
 DRAWING='@TIMECARD_LIB.TIMECARD(SCH_1):PAGE16',
 PACKAGE='0402',
 PHYS_PAGE='25',
 XY='(-7150,3150)',
 ROT='0',
 VER='1',
 CDS_LIB='passive',
 CDS_PART_NAME='RESISTOR-G155-133R0-01,33OHM,1%',
 TOLERANCE='1%',
 CLS_PN='G155-133R0-01',
 VALUE='33OHM',
 PRIM_FILE='./archive_libs/passive/resistor/chips/chips.prt';

PART_NAME
 R429 'RESISTOR-G155-133R0-01,33OHM,1%':;

SECTION_NUMBER 1
 '@TIMECARD_LIB.TIMECARD(SCH_1):PAGE16_I1709@PASSIVE.RESISTOR(CHIPS)':
 C_PATH='@timecard_lib.timecard(sch_1):page16_i1709@passive.resistor(chips)',
 P_PATH='@timecard_lib.timecard(sch_1):page25_i1709@passive.resistor(chips)',
 PATH='I1709',
 DRAWING='@TIMECARD_LIB.TIMECARD(SCH_1):PAGE16',
 PACKAGE='0402',
 PHYS_PAGE='25',
 XY='(-7150,3050)',
 ROT='0',
 VER='1',
 CDS_LIB='passive',
 CDS_PART_NAME='RESISTOR-G155-133R0-01,33OHM,1%',
 TOLERANCE='1%',
 CLS_PN='G155-133R0-01',
 VALUE='33OHM',
 PRIM_FILE='./archive_libs/passive/resistor/chips/chips.prt';

PART_NAME
 R430 'RESISTOR-G155-133R0-01,33OHM,1%':;

SECTION_NUMBER 1
 '@TIMECARD_LIB.TIMECARD(SCH_1):PAGE16_I1706@PASSIVE.RESISTOR(CHIPS)':
 C_PATH='@timecard_lib.timecard(sch_1):page16_i1706@passive.resistor(chips)',
 P_PATH='@timecard_lib.timecard(sch_1):page25_i1706@passive.resistor(chips)',
 PATH='I1706',
 DRAWING='@TIMECARD_LIB.TIMECARD(SCH_1):PAGE16',
 PACKAGE='0402',
 PHYS_PAGE='25',
 XY='(-7150,2950)',
 ROT='0',
 VER='1',
 CDS_LIB='passive',
 CDS_PART_NAME='RESISTOR-G155-133R0-01,33OHM,1%',
 TOLERANCE='1%',
 CLS_PN='G155-133R0-01',
 VALUE='33OHM',
 PRIM_FILE='./archive_libs/passive/resistor/chips/chips.prt';

PART_NAME
 R431 'RESISTOR-G155-133R0-01,33OHM,1%':;

SECTION_NUMBER 1
 '@TIMECARD_LIB.TIMECARD(SCH_1):PAGE16_I1718@PASSIVE.RESISTOR(CHIPS)':
 C_PATH='@timecard_lib.timecard(sch_1):page16_i1718@passive.resistor(chips)',
 P_PATH='@timecard_lib.timecard(sch_1):page25_i1718@passive.resistor(chips)',
 PATH='I1718',
 DRAWING='@TIMECARD_LIB.TIMECARD(SCH_1):PAGE16',
 PACKAGE='0402',
 PHYS_PAGE='25',
 XY='(-5100,3250)',
 ROT='0',
 VER='1',
 CDS_LIB='passive',
 CDS_PART_NAME='RESISTOR-G155-133R0-01,33OHM,1%',
 TOLERANCE='1%',
 CLS_PN='G155-133R0-01',
 VALUE='33OHM',
 PRIM_FILE='./archive_libs/passive/resistor/chips/chips.prt';

PART_NAME
 R432 'RESISTOR-G155-133R0-01,33OHM,1%':;

SECTION_NUMBER 1
 '@TIMECARD_LIB.TIMECARD(SCH_1):PAGE16_I1719@PASSIVE.RESISTOR(CHIPS)':
 C_PATH='@timecard_lib.timecard(sch_1):page16_i1719@passive.resistor(chips)',
 P_PATH='@timecard_lib.timecard(sch_1):page25_i1719@passive.resistor(chips)',
 PATH='I1719',
 DRAWING='@TIMECARD_LIB.TIMECARD(SCH_1):PAGE16',
 PACKAGE='0402',
 PHYS_PAGE='25',
 XY='(-5100,3150)',
 ROT='0',
 VER='1',
 CDS_LIB='passive',
 CDS_PART_NAME='RESISTOR-G155-133R0-01,33OHM,1%',
 TOLERANCE='1%',
 CLS_PN='G155-133R0-01',
 VALUE='33OHM',
 PRIM_FILE='./archive_libs/passive/resistor/chips/chips.prt';

PART_NAME
 R433 'RESISTOR-G155-133R0-01,33OHM,1%':;

SECTION_NUMBER 1
 '@TIMECARD_LIB.TIMECARD(SCH_1):PAGE16_I1720@PASSIVE.RESISTOR(CHIPS)':
 C_PATH='@timecard_lib.timecard(sch_1):page16_i1720@passive.resistor(chips)',
 P_PATH='@timecard_lib.timecard(sch_1):page25_i1720@passive.resistor(chips)',
 PATH='I1720',
 DRAWING='@TIMECARD_LIB.TIMECARD(SCH_1):PAGE16',
 PACKAGE='0402',
 PHYS_PAGE='25',
 XY='(-5100,3050)',
 ROT='0',
 VER='1',
 CDS_LIB='passive',
 CDS_PART_NAME='RESISTOR-G155-133R0-01,33OHM,1%',
 TOLERANCE='1%',
 CLS_PN='G155-133R0-01',
 VALUE='33OHM',
 PRIM_FILE='./archive_libs/passive/resistor/chips/chips.prt';

PART_NAME
 R434 'RESISTOR-G155-133R0-01,33OHM,1%':;

SECTION_NUMBER 1
 '@TIMECARD_LIB.TIMECARD(SCH_1):PAGE16_I1721@PASSIVE.RESISTOR(CHIPS)':
 C_PATH='@timecard_lib.timecard(sch_1):page16_i1721@passive.resistor(chips)',
 P_PATH='@timecard_lib.timecard(sch_1):page25_i1721@passive.resistor(chips)',
 PATH='I1721',
 DRAWING='@TIMECARD_LIB.TIMECARD(SCH_1):PAGE16',
 PACKAGE='0402',
 PHYS_PAGE='25',
 XY='(-5100,2950)',
 ROT='0',
 VER='1',
 CDS_LIB='passive',
 CDS_PART_NAME='RESISTOR-G155-133R0-01,33OHM,1%',
 TOLERANCE='1%',
 CLS_PN='G155-133R0-01',
 VALUE='33OHM',
 PRIM_FILE='./archive_libs/passive/resistor/chips/chips.prt';

PART_NAME
 R435 'RESISTOR-G155-11003-01,100KOHMA':;

SECTION_NUMBER 1
 '@TIMECARD_LIB.TIMECARD(SCH_1):PAGE161_I251@PASSIVE.RESISTOR(CHIPS)':
 C_PATH='@timecard_lib.timecard(sch_1):page161_i251@passive.resistor(chips)',
 P_PATH='@timecard_lib.timecard(sch_1):page11_i251@passive.resistor(chips)',
 PATH='I251',
 DRAWING='@TIMECARD_LIB.TIMECARD(SCH_1):PAGE161',
 PACKAGE='0402',
 PHYS_PAGE='11',
 XY='(-2800,8000)',
 ROT='1',
 VER='2',
 CDS_LIB='passive',
 CDS_PART_NAME='RESISTOR-G155-11003-01,100KOHMA',
 TOLERANCE='1%',
 CLS_PN='G155-11003-01',
 VALUE='100KOHM',
 PRIM_FILE='./archive_libs/passive/resistor/chips/chips.prt';

PART_NAME
 R436 'RESISTOR-G155-11502-01,15KOHM,A':;

SECTION_NUMBER 1
 '@TIMECARD_LIB.TIMECARD(SCH_1):PAGE161_I240@PASSIVE.RESISTOR(CHIPS)':
 C_PATH='@timecard_lib.timecard(sch_1):page161_i240@passive.resistor(chips)',
 P_PATH='@timecard_lib.timecard(sch_1):page11_i240@passive.resistor(chips)',
 PATH='I240',
 DRAWING='@TIMECARD_LIB.TIMECARD(SCH_1):PAGE161',
 PACKAGE='0402',
 PHYS_PAGE='11',
 XY='(-3650,4500)',
 ROT='4',
 VER='1',
 CDS_LIB='passive',
 CDS_PART_NAME='RESISTOR-G155-11502-01,15KOHM,A',
 NO_ASSY='TRUE',
 TOLERANCE='1%',
 CLS_PN='G155-11502-01',
 VALUE='15KOHM',
 PRIM_FILE='./archive_libs/passive/resistor/chips/chips.prt';

PART_NAME
 R437 'RESISTOR-G155-11502-01,15KOHM,A':;

SECTION_NUMBER 1
 '@TIMECARD_LIB.TIMECARD(SCH_1):PAGE161_I239@PASSIVE.RESISTOR(CHIPS)':
 C_PATH='@timecard_lib.timecard(sch_1):page161_i239@passive.resistor(chips)',
 P_PATH='@timecard_lib.timecard(sch_1):page11_i239@passive.resistor(chips)',
 PATH='I239',
 DRAWING='@TIMECARD_LIB.TIMECARD(SCH_1):PAGE161',
 PACKAGE='0402',
 PHYS_PAGE='11',
 XY='(-3650,4400)',
 ROT='4',
 VER='1',
 CDS_LIB='passive',
 CDS_PART_NAME='RESISTOR-G155-11502-01,15KOHM,A',
 NO_ASSY='TRUE',
 TOLERANCE='1%',
 CLS_PN='G155-11502-01',
 VALUE='15KOHM',
 PRIM_FILE='./archive_libs/passive/resistor/chips/chips.prt';

PART_NAME
 R438 'RESISTOR-G155-11002-01,10KOHM,A':;

SECTION_NUMBER 1
 '@TIMECARD_LIB.TIMECARD(SCH_1):PAGE163_I132@PASSIVE.RESISTOR(CHIPS)':
 C_PATH='@timecard_lib.timecard(sch_1):page163_i132@passive.resistor(chips)',
 P_PATH='@timecard_lib.timecard(sch_1):page13_i132@passive.resistor(chips)',
 PATH='I132',
 DRAWING='@TIMECARD_LIB.TIMECARD(SCH_1):PAGE163',
 PACKAGE='0402',
 PHYS_PAGE='13',
 XY='(-3850,6950)',
 ROT='1',
 VER='2',
 CDS_LIB='passive',
 CDS_PART_NAME='RESISTOR-G155-11002-01,10KOHM,A',
 TOLERANCE='1%',
 CLS_PN='G155-11002-01',
 VALUE='10KOHM',
 PRIM_FILE='./archive_libs/passive/resistor/chips/chips.prt';

PART_NAME
 R439 'RESISTOR-G155-11002-01,10KOHM,A':;

SECTION_NUMBER 1
 '@TIMECARD_LIB.TIMECARD(SCH_1):PAGE163_I133@PASSIVE.RESISTOR(CHIPS)':
 C_PATH='@timecard_lib.timecard(sch_1):page163_i133@passive.resistor(chips)',
 P_PATH='@timecard_lib.timecard(sch_1):page13_i133@passive.resistor(chips)',
 PATH='I133',
 DRAWING='@TIMECARD_LIB.TIMECARD(SCH_1):PAGE163',
 PACKAGE='0402',
 PHYS_PAGE='13',
 XY='(-3850,6850)',
 ROT='1',
 VER='2',
 CDS_LIB='passive',
 CDS_PART_NAME='RESISTOR-G155-11002-01,10KOHM,A',
 TOLERANCE='1%',
 CLS_PN='G155-11002-01',
 VALUE='10KOHM',
 PRIM_FILE='./archive_libs/passive/resistor/chips/chips.prt';

PART_NAME
 R440 'RESISTOR-G155-11002-01,10KOHM,A':;

SECTION_NUMBER 1
 '@TIMECARD_LIB.TIMECARD(SCH_1):PAGE163_I135@PASSIVE.RESISTOR(CHIPS)':
 C_PATH='@timecard_lib.timecard(sch_1):page163_i135@passive.resistor(chips)',
 P_PATH='@timecard_lib.timecard(sch_1):page13_i135@passive.resistor(chips)',
 PATH='I135',
 DRAWING='@TIMECARD_LIB.TIMECARD(SCH_1):PAGE163',
 PACKAGE='0402',
 PHYS_PAGE='13',
 XY='(-3850,6550)',
 ROT='1',
 VER='2',
 CDS_LIB='passive',
 CDS_PART_NAME='RESISTOR-G155-11002-01,10KOHM,A',
 TOLERANCE='1%',
 CLS_PN='G155-11002-01',
 VALUE='10KOHM',
 PRIM_FILE='./archive_libs/passive/resistor/chips/chips.prt';

PART_NAME
 R441 'RESISTOR-G155-11002-01,10KOHM,A':;

SECTION_NUMBER 1
 '@TIMECARD_LIB.TIMECARD(SCH_1):PAGE163_I134@PASSIVE.RESISTOR(CHIPS)':
 C_PATH='@timecard_lib.timecard(sch_1):page163_i134@passive.resistor(chips)',
 P_PATH='@timecard_lib.timecard(sch_1):page13_i134@passive.resistor(chips)',
 PATH='I134',
 DRAWING='@TIMECARD_LIB.TIMECARD(SCH_1):PAGE163',
 PACKAGE='0402',
 PHYS_PAGE='13',
 XY='(-3850,6450)',
 ROT='1',
 VER='2',
 CDS_LIB='passive',
 CDS_PART_NAME='RESISTOR-G155-11002-01,10KOHM,A',
 TOLERANCE='1%',
 CLS_PN='G155-11002-01',
 VALUE='10KOHM',
 PRIM_FILE='./archive_libs/passive/resistor/chips/chips.prt';

PART_NAME
 R442 'RESISTOR-G155-05101-01,5.1KOHMA':;

SECTION_NUMBER 1
 '@TIMECARD_LIB.TIMECARD(SCH_1):PAGE524_I497@PASSIVE.RESISTOR(CHIPS)':
 C_PATH='@timecard_lib.timecard(sch_1):page524_i497@passive.resistor(chips)',
 P_PATH='@timecard_lib.timecard(sch_1):page24_i497@passive.resistor(chips)',
 PATH='I497',
 DRAWING='@TIMECARD_LIB.TIMECARD(SCH_1):PAGE524',
 PACKAGE='0402',
 PHYS_PAGE='24',
 XY='(-14250,10050)',
 ROT='7',
 VER='2',
 LOCATION='R442',
 CDS_LIB='passive',
 CDS_PART_NAME='RESISTOR-G155-05101-01,5.1KOHMA',
 TOLERANCE='1%',
 CLS_PN='G155-05101-01',
 VALUE='5.1KOHM',
 PRIM_FILE='./archive_libs/passive/resistor/chips/chips.prt';

PART_NAME
 R443 'RESISTOR-G155-11000-01,100OHM,A':;

SECTION_NUMBER 1
 '@TIMECARD_LIB.TIMECARD(SCH_1):PAGE524_I446@PASSIVE.RESISTOR(CHIPS)':
 C_PATH='@timecard_lib.timecard(sch_1):page524_i446@passive.resistor(chips)',
 P_PATH='@timecard_lib.timecard(sch_1):page24_i446@passive.resistor(chips)',
 PATH='I446',
 DRAWING='@TIMECARD_LIB.TIMECARD(SCH_1):PAGE524',
 PACKAGE='0402',
 PHYS_PAGE='24',
 XY='(-13200,3450)',
 ROT='0',
 VER='1',
 CDS_LIB='passive',
 CDS_PART_NAME='RESISTOR-G155-11000-01,100OHM,A',
 NO_ASSY='TRUE',
 TOLERANCE='1%',
 CLS_PN='G155-11000-01',
 VALUE='100OHM',
 PRIM_FILE='./archive_libs/passive/resistor/chips/chips.prt';

PART_NAME
 R444 'RESISTOR-G155-11002-01,10KOHM,A':;

SECTION_NUMBER 1
 '@TIMECARD_LIB.TIMECARD(SCH_1):PAGE524_I208@PASSIVE.RESISTOR(CHIPS)':
 C_PATH='@timecard_lib.timecard(sch_1):page524_i208@passive.resistor(chips)',
 P_PATH='@timecard_lib.timecard(sch_1):page24_i208@passive.resistor(chips)',
 PATH='I208',
 DRAWING='@TIMECARD_LIB.TIMECARD(SCH_1):PAGE524',
 PACKAGE='0402',
 PHYS_PAGE='24',
 XY='(-13100,7550)',
 ROT='0',
 VER='2',
 CDS_LIB='passive',
 CDS_PART_NAME='RESISTOR-G155-11002-01,10KOHM,A',
 TOLERANCE='1%',
 CLS_PN='G155-11002-01',
 VALUE='10KOHM',
 PRIM_FILE='./archive_libs/passive/resistor/chips/chips.prt';

PART_NAME
 R445 'RESISTOR-G155-05101-01,5.1KOHMA':;

SECTION_NUMBER 1
 '@TIMECARD_LIB.TIMECARD(SCH_1):PAGE524_I395@PASSIVE.RESISTOR(CHIPS)':
 C_PATH='@timecard_lib.timecard(sch_1):page524_i395@passive.resistor(chips)',
 P_PATH='@timecard_lib.timecard(sch_1):page24_i395@passive.resistor(chips)',
 PATH='I395',
 DRAWING='@TIMECARD_LIB.TIMECARD(SCH_1):PAGE524',
 PACKAGE='0402',
 PHYS_PAGE='24',
 XY='(-12350,10050)',
 ROT='1',
 VER='2',
 CDS_LIB='passive',
 CDS_PART_NAME='RESISTOR-G155-05101-01,5.1KOHMA',
 TOLERANCE='1%',
 CLS_PN='G155-05101-01',
 VALUE='5.1KOHM',
 PRIM_FILE='./archive_libs/passive/resistor/chips/chips.prt';

PART_NAME
 R446 'RESISTOR-G155-11002-01,10KOHM,A':;

SECTION_NUMBER 1
 '@TIMECARD_LIB.TIMECARD(SCH_1):PAGE524_I207@PASSIVE.RESISTOR(CHIPS)':
 C_PATH='@timecard_lib.timecard(sch_1):page524_i207@passive.resistor(chips)',
 P_PATH='@timecard_lib.timecard(sch_1):page24_i207@passive.resistor(chips)',
 PATH='I207',
 DRAWING='@TIMECARD_LIB.TIMECARD(SCH_1):PAGE524',
 PACKAGE='0402',
 PHYS_PAGE='24',
 XY='(-12350,8050)',
 ROT='0',
 VER='1',
 CDS_LIB='passive',
 CDS_PART_NAME='RESISTOR-G155-11002-01,10KOHM,A',
 TOLERANCE='1%',
 CLS_PN='G155-11002-01',
 VALUE='10KOHM',
 PRIM_FILE='./archive_libs/passive/resistor/chips/chips.prt';

PART_NAME
 R447 'RESISTOR-G155-11002-01,10KOHM,A':;

SECTION_NUMBER 1
 '@TIMECARD_LIB.TIMECARD(SCH_1):PAGE524_I206@PASSIVE.RESISTOR(CHIPS)':
 C_PATH='@timecard_lib.timecard(sch_1):page524_i206@passive.resistor(chips)',
 P_PATH='@timecard_lib.timecard(sch_1):page24_i206@passive.resistor(chips)',
 PATH='I206',
 DRAWING='@TIMECARD_LIB.TIMECARD(SCH_1):PAGE524',
 PACKAGE='0402',
 PHYS_PAGE='24',
 XY='(-12350,7950)',
 ROT='0',
 VER='1',
 CDS_LIB='passive',
 CDS_PART_NAME='RESISTOR-G155-11002-01,10KOHM,A',
 TOLERANCE='1%',
 CLS_PN='G155-11002-01',
 VALUE='10KOHM',
 PRIM_FILE='./archive_libs/passive/resistor/chips/chips.prt';

PART_NAME
 R448 'RESISTOR-G155-133R0-01,33OHM,1%':;

SECTION_NUMBER 1
 '@TIMECARD_LIB.TIMECARD(SCH_1):PAGE524_I423@PASSIVE.RESISTOR(CHIPS)':
 C_PATH='@timecard_lib.timecard(sch_1):page524_i423@passive.resistor(chips)',
 P_PATH='@timecard_lib.timecard(sch_1):page24_i423@passive.resistor(chips)',
 PATH='I423',
 DRAWING='@TIMECARD_LIB.TIMECARD(SCH_1):PAGE524',
 PACKAGE='0402',
 PHYS_PAGE='24',
 XY='(-12000,4700)',
 ROT='0',
 VER='1',
 CDS_LIB='passive',
 CDS_PART_NAME='RESISTOR-G155-133R0-01,33OHM,1%',
 NO_ASSY='TRUE',
 TOLERANCE='1%',
 CLS_PN='G155-133R0-01',
 VALUE='33OHM',
 PRIM_FILE='./archive_libs/passive/resistor/chips/chips.prt';

PART_NAME
 R449 'RESISTOR-G155-133R0-01,33OHM,1%':;

SECTION_NUMBER 1
 '@TIMECARD_LIB.TIMECARD(SCH_1):PAGE524_I424@PASSIVE.RESISTOR(CHIPS)':
 C_PATH='@timecard_lib.timecard(sch_1):page524_i424@passive.resistor(chips)',
 P_PATH='@timecard_lib.timecard(sch_1):page24_i424@passive.resistor(chips)',
 PATH='I424',
 DRAWING='@TIMECARD_LIB.TIMECARD(SCH_1):PAGE524',
 PACKAGE='0402',
 PHYS_PAGE='24',
 XY='(-12000,4600)',
 ROT='0',
 VER='1',
 CDS_LIB='passive',
 CDS_PART_NAME='RESISTOR-G155-133R0-01,33OHM,1%',
 TOLERANCE='1%',
 CLS_PN='G155-133R0-01',
 VALUE='33OHM',
 PRIM_FILE='./archive_libs/passive/resistor/chips/chips.prt';

PART_NAME
 R450 'RESISTOR-G155-14701-01,4.7KOHMA':;

SECTION_NUMBER 1
 '@TIMECARD_LIB.TIMECARD(SCH_1):PAGE524_I440@PASSIVE.RESISTOR(CHIPS)':
 C_PATH='@timecard_lib.timecard(sch_1):page524_i440@passive.resistor(chips)',
 P_PATH='@timecard_lib.timecard(sch_1):page24_i440@passive.resistor(chips)',
 PATH='I440',
 DRAWING='@TIMECARD_LIB.TIMECARD(SCH_1):PAGE524',
 PACKAGE='0402',
 PHYS_PAGE='24',
 XY='(-12000,4200)',
 ROT='1',
 VER='2',
 CDS_LIB='passive',
 CDS_PART_NAME='RESISTOR-G155-14701-01,4.7KOHMA',
 TOLERANCE='1%',
 CLS_PN='G155-14701-01',
 VALUE='4.7KOHM',
 PRIM_FILE='./archive_libs/passive/resistor/chips/chips.prt';

PART_NAME
 R451 'RESISTOR-G155-11001-01,1KOHM,1%':;

SECTION_NUMBER 1
 '@TIMECARD_LIB.TIMECARD(SCH_1):PAGE524_I441@PASSIVE.RESISTOR(CHIPS)':
 C_PATH='@timecard_lib.timecard(sch_1):page524_i441@passive.resistor(chips)',
 P_PATH='@timecard_lib.timecard(sch_1):page24_i441@passive.resistor(chips)',
 PATH='I441',
 DRAWING='@TIMECARD_LIB.TIMECARD(SCH_1):PAGE524',
 PACKAGE='0402',
 PHYS_PAGE='24',
 XY='(-12000,4100)',
 ROT='1',
 VER='2',
 CDS_LIB='passive',
 CDS_PART_NAME='RESISTOR-G155-11001-01,1KOHM,1%',
 NO_ASSY='TRUE',
 TOLERANCE='1%',
 CLS_PN='G155-11001-01',
 VALUE='1KOHM',
 PRIM_FILE='./archive_libs/passive/resistor/chips/chips.prt';

PART_NAME
 R452 'RESISTOR-G155-14701-01,4.7KOHMA':;

SECTION_NUMBER 1
 '@TIMECARD_LIB.TIMECARD(SCH_1):PAGE524_I443@PASSIVE.RESISTOR(CHIPS)':
 C_PATH='@timecard_lib.timecard(sch_1):page524_i443@passive.resistor(chips)',
 P_PATH='@timecard_lib.timecard(sch_1):page24_i443@passive.resistor(chips)',
 PATH='I443',
 DRAWING='@TIMECARD_LIB.TIMECARD(SCH_1):PAGE524',
 PACKAGE='0402',
 PHYS_PAGE='24',
 XY='(-12000,4000)',
 ROT='1',
 VER='2',
 CDS_LIB='passive',
 CDS_PART_NAME='RESISTOR-G155-14701-01,4.7KOHMA',
 TOLERANCE='1%',
 CLS_PN='G155-14701-01',
 VALUE='4.7KOHM',
 PRIM_FILE='./archive_libs/passive/resistor/chips/chips.prt';

PART_NAME
 R453 'RESISTOR-G155-11001-01,1KOHM,1%':;

SECTION_NUMBER 1
 '@TIMECARD_LIB.TIMECARD(SCH_1):PAGE524_I442@PASSIVE.RESISTOR(CHIPS)':
 C_PATH='@timecard_lib.timecard(sch_1):page524_i442@passive.resistor(chips)',
 P_PATH='@timecard_lib.timecard(sch_1):page24_i442@passive.resistor(chips)',
 PATH='I442',
 DRAWING='@TIMECARD_LIB.TIMECARD(SCH_1):PAGE524',
 PACKAGE='0402',
 PHYS_PAGE='24',
 XY='(-12000,3900)',
 ROT='1',
 VER='2',
 CDS_LIB='passive',
 CDS_PART_NAME='RESISTOR-G155-11001-01,1KOHM,1%',
 NO_ASSY='TRUE',
 TOLERANCE='1%',
 CLS_PN='G155-11001-01',
 VALUE='1KOHM',
 PRIM_FILE='./archive_libs/passive/resistor/chips/chips.prt';

PART_NAME
 R454 'RESISTOR-G155-12201-01,2.2KOHMA':;

SECTION_NUMBER 1
 '@TIMECARD_LIB.TIMECARD(SCH_1):PAGE524_I310@PASSIVE.RESISTOR(CHIPS)':
 C_PATH='@timecard_lib.timecard(sch_1):page524_i310@passive.resistor(chips)',
 P_PATH='@timecard_lib.timecard(sch_1):page24_i310@passive.resistor(chips)',
 PATH='I310',
 DRAWING='@TIMECARD_LIB.TIMECARD(SCH_1):PAGE524',
 PACKAGE='0402',
 PHYS_PAGE='24',
 XY='(-11950,6850)',
 ROT='2',
 VER='1',
 CDS_LIB='passive',
 CDS_PART_NAME='RESISTOR-G155-12201-01,2.2KOHMA',
 TOLERANCE='1%',
 CLS_PN='G155-12201-01',
 VALUE='2.2KOHM',
 PRIM_FILE='./archive_libs/passive/resistor/chips/chips.prt';

PART_NAME
 R455 'RESISTOR-G155-11004-01,1MOHM,1%':;

SECTION_NUMBER 1
 '@TIMECARD_LIB.TIMECARD(SCH_1):PAGE524_I287@PASSIVE.RESISTOR(CHIPS)':
 C_PATH='@timecard_lib.timecard(sch_1):page524_i287@passive.resistor(chips)',
 P_PATH='@timecard_lib.timecard(sch_1):page24_i287@passive.resistor(chips)',
 PATH='I287',
 DRAWING='@TIMECARD_LIB.TIMECARD(SCH_1):PAGE524',
 PACKAGE='0402',
 PHYS_PAGE='24',
 XY='(-10250,8450)',
 ROT='1',
 VER='2',
 CDS_LIB='passive',
 CDS_PART_NAME='RESISTOR-G155-11004-01,1MOHM,1%',
 NO_ASSY='TRUE',
 TOLERANCE='1%',
 CLS_PN='G155-11004-01',
 VALUE='1MOHM',
 PRIM_FILE='./archive_libs/passive/resistor/chips/chips.prt';

PART_NAME
 R456 'RESISTOR-G155-11000-01,100OHM,A':;

SECTION_NUMBER 1
 '@TIMECARD_LIB.TIMECARD(SCH_1):PAGE524_I368@PASSIVE.RESISTOR(CHIPS)':
 C_PATH='@timecard_lib.timecard(sch_1):page524_i368@passive.resistor(chips)',
 P_PATH='@timecard_lib.timecard(sch_1):page24_i368@passive.resistor(chips)',
 PATH='I368',
 DRAWING='@TIMECARD_LIB.TIMECARD(SCH_1):PAGE524',
 PACKAGE='0402',
 PHYS_PAGE='24',
 XY='(-9600,9500)',
 ROT='0',
 VER='1',
 CDS_LIB='passive',
 CDS_PART_NAME='RESISTOR-G155-11000-01,100OHM,A',
 TOLERANCE='1%',
 CLS_PN='G155-11000-01',
 VALUE='100OHM',
 PRIM_FILE='./archive_libs/passive/resistor/chips/chips.prt';

PART_NAME
 R457 'RESISTOR-G155-14701-01,4.7KOHMA':;

SECTION_NUMBER 1
 '@TIMECARD_LIB.TIMECARD(SCH_1):PAGE524_I431@PASSIVE.RESISTOR(CHIPS)':
 C_PATH='@timecard_lib.timecard(sch_1):page524_i431@passive.resistor(chips)',
 P_PATH='@timecard_lib.timecard(sch_1):page24_i431@passive.resistor(chips)',
 PATH='I431',
 DRAWING='@TIMECARD_LIB.TIMECARD(SCH_1):PAGE524',
 PACKAGE='0402',
 PHYS_PAGE='24',
 XY='(-8800,4200)',
 ROT='1',
 VER='2',
 CDS_LIB='passive',
 CDS_PART_NAME='RESISTOR-G155-14701-01,4.7KOHMA',
 NO_ASSY='TRUE',
 TOLERANCE='1%',
 CLS_PN='G155-14701-01',
 VALUE='4.7KOHM',
 PRIM_FILE='./archive_libs/passive/resistor/chips/chips.prt';

PART_NAME
 R458 'RESISTOR-G155-11001-01,1KOHM,1%':;

SECTION_NUMBER 1
 '@TIMECARD_LIB.TIMECARD(SCH_1):PAGE524_I430@PASSIVE.RESISTOR(CHIPS)':
 C_PATH='@timecard_lib.timecard(sch_1):page524_i430@passive.resistor(chips)',
 P_PATH='@timecard_lib.timecard(sch_1):page24_i430@passive.resistor(chips)',
 PATH='I430',
 DRAWING='@TIMECARD_LIB.TIMECARD(SCH_1):PAGE524',
 PACKAGE='0402',
 PHYS_PAGE='24',
 XY='(-8800,4100)',
 ROT='1',
 VER='2',
 CDS_LIB='passive',
 CDS_PART_NAME='RESISTOR-G155-11001-01,1KOHM,1%',
 TOLERANCE='1%',
 CLS_PN='G155-11001-01',
 VALUE='1KOHM',
 PRIM_FILE='./archive_libs/passive/resistor/chips/chips.prt';

PART_NAME
 R459 'RESISTOR-G155-11001-01,1KOHM,1%':;

SECTION_NUMBER 1
 '@TIMECARD_LIB.TIMECARD(SCH_1):PAGE524_I432@PASSIVE.RESISTOR(CHIPS)':
 C_PATH='@timecard_lib.timecard(sch_1):page524_i432@passive.resistor(chips)',
 P_PATH='@timecard_lib.timecard(sch_1):page24_i432@passive.resistor(chips)',
 PATH='I432',
 DRAWING='@TIMECARD_LIB.TIMECARD(SCH_1):PAGE524',
 PACKAGE='0402',
 PHYS_PAGE='24',
 XY='(-8800,4000)',
 ROT='1',
 VER='2',
 CDS_LIB='passive',
 CDS_PART_NAME='RESISTOR-G155-11001-01,1KOHM,1%',
 TOLERANCE='1%',
 CLS_PN='G155-11001-01',
 VALUE='1KOHM',
 PRIM_FILE='./archive_libs/passive/resistor/chips/chips.prt';

PART_NAME
 R460 'RESISTOR-G155-11001-01,1KOHM,1%':;

SECTION_NUMBER 1
 '@TIMECARD_LIB.TIMECARD(SCH_1):PAGE524_I121@PASSIVE.RESISTOR(CHIPS)':
 C_PATH='@timecard_lib.timecard(sch_1):page524_i121@passive.resistor(chips)',
 P_PATH='@timecard_lib.timecard(sch_1):page24_i121@passive.resistor(chips)',
 PATH='I121',
 DRAWING='@TIMECARD_LIB.TIMECARD(SCH_1):PAGE524',
 PACKAGE='0402',
 PHYS_PAGE='24',
 XY='(-8600,9350)',
 ROT='0',
 VER='1',
 CDS_LIB='passive',
 CDS_PART_NAME='RESISTOR-G155-11001-01,1KOHM,1%',
 TOLERANCE='1%',
 CLS_PN='G155-11001-01',
 VALUE='1KOHM',
 PRIM_FILE='./archive_libs/passive/resistor/chips/chips.prt';

PART_NAME
 R461 'RESISTOR-G155-133R0-01,33OHM,1%':;

SECTION_NUMBER 1
 '@TIMECARD_LIB.TIMECARD(SCH_1):PAGE524_I411@PASSIVE.RESISTOR(CHIPS)':
 C_PATH='@timecard_lib.timecard(sch_1):page524_i411@passive.resistor(chips)',
 P_PATH='@timecard_lib.timecard(sch_1):page24_i411@passive.resistor(chips)',
 PATH='I411',
 DRAWING='@TIMECARD_LIB.TIMECARD(SCH_1):PAGE524',
 PACKAGE='0402',
 PHYS_PAGE='24',
 XY='(-8550,4700)',
 ROT='0',
 VER='1',
 CDS_LIB='passive',
 CDS_PART_NAME='RESISTOR-G155-133R0-01,33OHM,1%',
 NO_ASSY='TRUE',
 TOLERANCE='1%',
 CLS_PN='G155-133R0-01',
 VALUE='33OHM',
 PRIM_FILE='./archive_libs/passive/resistor/chips/chips.prt';

PART_NAME
 R462 'RESISTOR-G155-133R0-01,33OHM,1%':;

SECTION_NUMBER 1
 '@TIMECARD_LIB.TIMECARD(SCH_1):PAGE524_I412@PASSIVE.RESISTOR(CHIPS)':
 C_PATH='@timecard_lib.timecard(sch_1):page524_i412@passive.resistor(chips)',
 P_PATH='@timecard_lib.timecard(sch_1):page24_i412@passive.resistor(chips)',
 PATH='I412',
 DRAWING='@TIMECARD_LIB.TIMECARD(SCH_1):PAGE524',
 PACKAGE='0402',
 PHYS_PAGE='24',
 XY='(-8550,4600)',
 ROT='0',
 VER='1',
 CDS_LIB='passive',
 CDS_PART_NAME='RESISTOR-G155-133R0-01,33OHM,1%',
 TOLERANCE='1%',
 CLS_PN='G155-133R0-01',
 VALUE='33OHM',
 PRIM_FILE='./archive_libs/passive/resistor/chips/chips.prt';

PART_NAME
 R463 'RESISTOR-G155-01202-01,12KOHM,A':;

SECTION_NUMBER 1
 '@TIMECARD_LIB.TIMECARD(SCH_1):PAGE524_I106@PASSIVE.RESISTOR(CHIPS)':
 C_PATH='@timecard_lib.timecard(sch_1):page524_i106@passive.resistor(chips)',
 P_PATH='@timecard_lib.timecard(sch_1):page24_i106@passive.resistor(chips)',
 PATH='I106',
 DRAWING='@TIMECARD_LIB.TIMECARD(SCH_1):PAGE524',
 PACKAGE='0402',
 PHYS_PAGE='24',
 XY='(-8350,8150)',
 ROT='0',
 VER='2',
 CDS_LIB='passive',
 CDS_PART_NAME='RESISTOR-G155-01202-01,12KOHM,A',
 TOLERANCE='1%',
 CLS_PN='G155-01202-01',
 VALUE='12KOHM',
 PRIM_FILE='./archive_libs/passive/resistor/chips/chips.prt';

PART_NAME
 R464 'RESISTOR-G155-100R0-J0,0OHM,-':;

SECTION_NUMBER 1
 '@TIMECARD_LIB.TIMECARD(SCH_1):PAGE524_I493@PASSIVE.RESISTOR(CHIPS)':
 C_PATH='@timecard_lib.timecard(sch_1):page524_i493@passive.resistor(chips)',
 P_PATH='@timecard_lib.timecard(sch_1):page24_i493@passive.resistor(chips)',
 PATH='I493',
 DRAWING='@TIMECARD_LIB.TIMECARD(SCH_1):PAGE524',
 PACKAGE='0402',
 PHYS_PAGE='24',
 XY='(-7450,3500)',
 ROT='0',
 VER='1',
 CDS_LIB='passive',
 CDS_PART_NAME='RESISTOR-G155-100R0-J0,0OHM,-',
 NO_ASSY='TRUE',
 TOLERANCE='-',
 CLS_PN='G155-100R0-J0',
 VALUE='0OHM',
 PRIM_FILE='./archive_libs/passive/resistor/chips/chips.prt';

PART_NAME
 R465 'RESISTOR-G155-100R0-J0,0OHM,-':;

SECTION_NUMBER 1
 '@TIMECARD_LIB.TIMECARD(SCH_1):PAGE524_I494@PASSIVE.RESISTOR(CHIPS)':
 C_PATH='@timecard_lib.timecard(sch_1):page524_i494@passive.resistor(chips)',
 P_PATH='@timecard_lib.timecard(sch_1):page24_i494@passive.resistor(chips)',
 PATH='I494',
 DRAWING='@TIMECARD_LIB.TIMECARD(SCH_1):PAGE524',
 PACKAGE='0402',
 PHYS_PAGE='24',
 XY='(-7450,2850)',
 ROT='0',
 VER='1',
 CDS_LIB='passive',
 CDS_PART_NAME='RESISTOR-G155-100R0-J0,0OHM,-',
 NO_ASSY='TRUE',
 TOLERANCE='-',
 CLS_PN='G155-100R0-J0',
 VALUE='0OHM',
 PRIM_FILE='./archive_libs/passive/resistor/chips/chips.prt';

PART_NAME
 R466 'RESISTOR-G155-11003-01,100KOHMA':;

SECTION_NUMBER 1
 '@TIMECARD_LIB.TIMECARD(SCH_1):PAGE524_I198@PASSIVE.RESISTOR(CHIPS)':
 C_PATH='@timecard_lib.timecard(sch_1):page524_i198@passive.resistor(chips)',
 P_PATH='@timecard_lib.timecard(sch_1):page24_i198@passive.resistor(chips)',
 PATH='I198',
 DRAWING='@TIMECARD_LIB.TIMECARD(SCH_1):PAGE524',
 PACKAGE='0402',
 PHYS_PAGE='24',
 XY='(-5300,11600)',
 ROT='1',
 VER='2',
 CDS_LIB='passive',
 CDS_PART_NAME='RESISTOR-G155-11003-01,100KOHMA',
 TOLERANCE='1%',
 CLS_PN='G155-11003-01',
 VALUE='100KOHM',
 PRIM_FILE='./archive_libs/passive/resistor/chips/chips.prt';

PART_NAME
 R467 'RESISTOR-G155-133R0-01,33OHM,1%':;

SECTION_NUMBER 1
 '@TIMECARD_LIB.TIMECARD(SCH_1):PAGE524_I141@PASSIVE.RESISTOR(CHIPS)':
 C_PATH='@timecard_lib.timecard(sch_1):page524_i141@passive.resistor(chips)',
 P_PATH='@timecard_lib.timecard(sch_1):page24_i141@passive.resistor(chips)',
 PATH='I141',
 DRAWING='@TIMECARD_LIB.TIMECARD(SCH_1):PAGE524',
 PACKAGE='0402',
 PHYS_PAGE='24',
 XY='(-5300,11450)',
 ROT='0',
 VER='1',
 CDS_LIB='passive',
 CDS_PART_NAME='RESISTOR-G155-133R0-01,33OHM,1%',
 TOLERANCE='1%',
 CLS_PN='G155-133R0-01',
 VALUE='33OHM',
 PRIM_FILE='./archive_libs/passive/resistor/chips/chips.prt';

PART_NAME
 R468 'RESISTOR-G155-133R0-01,33OHM,1%':;

SECTION_NUMBER 1
 '@TIMECARD_LIB.TIMECARD(SCH_1):PAGE524_I140@PASSIVE.RESISTOR(CHIPS)':
 C_PATH='@timecard_lib.timecard(sch_1):page524_i140@passive.resistor(chips)',
 P_PATH='@timecard_lib.timecard(sch_1):page24_i140@passive.resistor(chips)',
 PATH='I140',
 DRAWING='@TIMECARD_LIB.TIMECARD(SCH_1):PAGE524',
 PACKAGE='0402',
 PHYS_PAGE='24',
 XY='(-5300,11350)',
 ROT='0',
 VER='1',
 CDS_LIB='passive',
 CDS_PART_NAME='RESISTOR-G155-133R0-01,33OHM,1%',
 TOLERANCE='1%',
 CLS_PN='G155-133R0-01',
 VALUE='33OHM',
 PRIM_FILE='./archive_libs/passive/resistor/chips/chips.prt';

PART_NAME
 R469 'RESISTOR-G155-133R0-01,33OHM,1%':;

SECTION_NUMBER 1
 '@TIMECARD_LIB.TIMECARD(SCH_1):PAGE524_I142@PASSIVE.RESISTOR(CHIPS)':
 C_PATH='@timecard_lib.timecard(sch_1):page524_i142@passive.resistor(chips)',
 P_PATH='@timecard_lib.timecard(sch_1):page24_i142@passive.resistor(chips)',
 PATH='I142',
 DRAWING='@TIMECARD_LIB.TIMECARD(SCH_1):PAGE524',
 PACKAGE='0402',
 PHYS_PAGE='24',
 XY='(-5300,11250)',
 ROT='0',
 VER='1',
 CDS_LIB='passive',
 CDS_PART_NAME='RESISTOR-G155-133R0-01,33OHM,1%',
 TOLERANCE='1%',
 CLS_PN='G155-133R0-01',
 VALUE='33OHM',
 PRIM_FILE='./archive_libs/passive/resistor/chips/chips.prt';

PART_NAME
 R470 'RESISTOR-G155-133R0-01,33OHM,1%':;

SECTION_NUMBER 1
 '@TIMECARD_LIB.TIMECARD(SCH_1):PAGE524_I139@PASSIVE.RESISTOR(CHIPS)':
 C_PATH='@timecard_lib.timecard(sch_1):page524_i139@passive.resistor(chips)',
 P_PATH='@timecard_lib.timecard(sch_1):page24_i139@passive.resistor(chips)',
 PATH='I139',
 DRAWING='@TIMECARD_LIB.TIMECARD(SCH_1):PAGE524',
 PACKAGE='0402',
 PHYS_PAGE='24',
 XY='(-5300,11150)',
 ROT='0',
 VER='1',
 CDS_LIB='passive',
 CDS_PART_NAME='RESISTOR-G155-133R0-01,33OHM,1%',
 TOLERANCE='1%',
 CLS_PN='G155-133R0-01',
 VALUE='33OHM',
 PRIM_FILE='./archive_libs/passive/resistor/chips/chips.prt';

PART_NAME
 R471 'RESISTOR-G155-100R0-J0,0OHM,-':;

SECTION_NUMBER 1
 '@TIMECARD_LIB.TIMECARD(SCH_1):PAGE524_I169@PASSIVE.RESISTOR(CHIPS)':
 C_PATH='@timecard_lib.timecard(sch_1):page524_i169@passive.resistor(chips)',
 P_PATH='@timecard_lib.timecard(sch_1):page24_i169@passive.resistor(chips)',
 PATH='I169',
 DRAWING='@TIMECARD_LIB.TIMECARD(SCH_1):PAGE524',
 PACKAGE='0402',
 PHYS_PAGE='24',
 XY='(-5300,10550)',
 ROT='0',
 VER='1',
 CDS_LIB='passive',
 CDS_PART_NAME='RESISTOR-G155-100R0-J0,0OHM,-',
 TOLERANCE='-',
 CLS_PN='G155-100R0-J0',
 VALUE='0OHM',
 PRIM_FILE='./archive_libs/passive/resistor/chips/chips.prt';

PART_NAME
 R472 'RESISTOR-G155-100R0-J0,0OHM,-':;

SECTION_NUMBER 1
 '@TIMECARD_LIB.TIMECARD(SCH_1):PAGE524_I166@PASSIVE.RESISTOR(CHIPS)':
 C_PATH='@timecard_lib.timecard(sch_1):page524_i166@passive.resistor(chips)',
 P_PATH='@timecard_lib.timecard(sch_1):page24_i166@passive.resistor(chips)',
 PATH='I166',
 DRAWING='@TIMECARD_LIB.TIMECARD(SCH_1):PAGE524',
 PACKAGE='0402',
 PHYS_PAGE='24',
 XY='(-5300,10450)',
 ROT='0',
 VER='1',
 CDS_LIB='passive',
 CDS_PART_NAME='RESISTOR-G155-100R0-J0,0OHM,-',
 TOLERANCE='-',
 CLS_PN='G155-100R0-J0',
 VALUE='0OHM',
 PRIM_FILE='./archive_libs/passive/resistor/chips/chips.prt';

PART_NAME
 R473 'RESISTOR-G155-100R0-J0,0OHM,-':;

SECTION_NUMBER 1
 '@TIMECARD_LIB.TIMECARD(SCH_1):PAGE524_I170@PASSIVE.RESISTOR(CHIPS)':
 C_PATH='@timecard_lib.timecard(sch_1):page524_i170@passive.resistor(chips)',
 P_PATH='@timecard_lib.timecard(sch_1):page24_i170@passive.resistor(chips)',
 PATH='I170',
 DRAWING='@TIMECARD_LIB.TIMECARD(SCH_1):PAGE524',
 PACKAGE='0402',
 PHYS_PAGE='24',
 XY='(-5300,10350)',
 ROT='0',
 VER='1',
 CDS_LIB='passive',
 CDS_PART_NAME='RESISTOR-G155-100R0-J0,0OHM,-',
 TOLERANCE='-',
 CLS_PN='G155-100R0-J0',
 VALUE='0OHM',
 PRIM_FILE='./archive_libs/passive/resistor/chips/chips.prt';

PART_NAME
 R474 'RESISTOR-G155-11003-01,100KOHMA':;

SECTION_NUMBER 1
 '@TIMECARD_LIB.TIMECARD(SCH_1):PAGE524_I466@PASSIVE.RESISTOR(CHIPS)':
 C_PATH='@timecard_lib.timecard(sch_1):page524_i466@passive.resistor(chips)',
 P_PATH='@timecard_lib.timecard(sch_1):page24_i466@passive.resistor(chips)',
 PATH='I466',
 DRAWING='@TIMECARD_LIB.TIMECARD(SCH_1):PAGE524',
 PACKAGE='0402',
 PHYS_PAGE='24',
 XY='(-4500,5550)',
 ROT='1',
 VER='2',
 CDS_LIB='passive',
 CDS_PART_NAME='RESISTOR-G155-11003-01,100KOHMA',
 TOLERANCE='1%',
 CLS_PN='G155-11003-01',
 VALUE='100KOHM',
 PRIM_FILE='./archive_libs/passive/resistor/chips/chips.prt';

PART_NAME
 R475 'RESISTOR-G155-11003-01,100KOHMA':;

SECTION_NUMBER 1
 '@TIMECARD_LIB.TIMECARD(SCH_1):PAGE524_I467@PASSIVE.RESISTOR(CHIPS)':
 C_PATH='@timecard_lib.timecard(sch_1):page524_i467@passive.resistor(chips)',
 P_PATH='@timecard_lib.timecard(sch_1):page24_i467@passive.resistor(chips)',
 PATH='I467',
 DRAWING='@TIMECARD_LIB.TIMECARD(SCH_1):PAGE524',
 PACKAGE='0402',
 PHYS_PAGE='24',
 XY='(-4500,5250)',
 ROT='1',
 VER='2',
 CDS_LIB='passive',
 CDS_PART_NAME='RESISTOR-G155-11003-01,100KOHMA',
 TOLERANCE='1%',
 CLS_PN='G155-11003-01',
 VALUE='100KOHM',
 PRIM_FILE='./archive_libs/passive/resistor/chips/chips.prt';

PART_NAME
 R476 'RESISTOR-G155-11003-01,100KOHMA':;

SECTION_NUMBER 1
 '@TIMECARD_LIB.TIMECARD(SCH_1):PAGE524_I468@PASSIVE.RESISTOR(CHIPS)':
 C_PATH='@timecard_lib.timecard(sch_1):page524_i468@passive.resistor(chips)',
 P_PATH='@timecard_lib.timecard(sch_1):page24_i468@passive.resistor(chips)',
 PATH='I468',
 DRAWING='@TIMECARD_LIB.TIMECARD(SCH_1):PAGE524',
 PACKAGE='0402',
 PHYS_PAGE='24',
 XY='(-4500,4950)',
 ROT='1',
 VER='2',
 CDS_LIB='passive',
 CDS_PART_NAME='RESISTOR-G155-11003-01,100KOHMA',
 TOLERANCE='1%',
 CLS_PN='G155-11003-01',
 VALUE='100KOHM',
 PRIM_FILE='./archive_libs/passive/resistor/chips/chips.prt';

PART_NAME
 R477 'RESISTOR-G155-11003-01,100KOHMA':;

SECTION_NUMBER 1
 '@TIMECARD_LIB.TIMECARD(SCH_1):PAGE524_I469@PASSIVE.RESISTOR(CHIPS)':
 C_PATH='@timecard_lib.timecard(sch_1):page524_i469@passive.resistor(chips)',
 P_PATH='@timecard_lib.timecard(sch_1):page24_i469@passive.resistor(chips)',
 PATH='I469',
 DRAWING='@TIMECARD_LIB.TIMECARD(SCH_1):PAGE524',
 PACKAGE='0402',
 PHYS_PAGE='24',
 XY='(-4500,4650)',
 ROT='1',
 VER='2',
 CDS_LIB='passive',
 CDS_PART_NAME='RESISTOR-G155-11003-01,100KOHMA',
 TOLERANCE='1%',
 CLS_PN='G155-11003-01',
 VALUE='100KOHM',
 PRIM_FILE='./archive_libs/passive/resistor/chips/chips.prt';

PART_NAME
 R478 'RESISTOR-G155-11003-01,100KOHMA':;

SECTION_NUMBER 1
 '@TIMECARD_LIB.TIMECARD(SCH_1):PAGE524_I190@PASSIVE.RESISTOR(CHIPS)':
 C_PATH='@timecard_lib.timecard(sch_1):page524_i190@passive.resistor(chips)',
 P_PATH='@timecard_lib.timecard(sch_1):page24_i190@passive.resistor(chips)',
 PATH='I190',
 DRAWING='@TIMECARD_LIB.TIMECARD(SCH_1):PAGE524',
 PACKAGE='0402',
 PHYS_PAGE='24',
 XY='(-4200,10100)',
 ROT='1',
 VER='2',
 CDS_LIB='passive',
 CDS_PART_NAME='RESISTOR-G155-11003-01,100KOHMA',
 TOLERANCE='1%',
 CLS_PN='G155-11003-01',
 VALUE='100KOHM',
 PRIM_FILE='./archive_libs/passive/resistor/chips/chips.prt';

PART_NAME
 R479 'RESISTOR-G155-11003-01,100KOHMA':;

SECTION_NUMBER 1
 '@TIMECARD_LIB.TIMECARD(SCH_1):PAGE524_I191@PASSIVE.RESISTOR(CHIPS)':
 C_PATH='@timecard_lib.timecard(sch_1):page524_i191@passive.resistor(chips)',
 P_PATH='@timecard_lib.timecard(sch_1):page24_i191@passive.resistor(chips)',
 PATH='I191',
 DRAWING='@TIMECARD_LIB.TIMECARD(SCH_1):PAGE524',
 PACKAGE='0402',
 PHYS_PAGE='24',
 XY='(-4200,10000)',
 ROT='1',
 VER='2',
 CDS_LIB='passive',
 CDS_PART_NAME='RESISTOR-G155-11003-01,100KOHMA',
 TOLERANCE='1%',
 CLS_PN='G155-11003-01',
 VALUE='100KOHM',
 PRIM_FILE='./archive_libs/passive/resistor/chips/chips.prt';

PART_NAME
 R480 'RESISTOR-G155-11003-01,100KOHMA':;

SECTION_NUMBER 1
 '@TIMECARD_LIB.TIMECARD(SCH_1):PAGE524_I149@PASSIVE.RESISTOR(CHIPS)':
 C_PATH='@timecard_lib.timecard(sch_1):page524_i149@passive.resistor(chips)',
 P_PATH='@timecard_lib.timecard(sch_1):page24_i149@passive.resistor(chips)',
 PATH='I149',
 DRAWING='@TIMECARD_LIB.TIMECARD(SCH_1):PAGE524',
 PACKAGE='0402',
 PHYS_PAGE='24',
 XY='(-4200,9200)',
 ROT='1',
 VER='2',
 CDS_LIB='passive',
 CDS_PART_NAME='RESISTOR-G155-11003-01,100KOHMA',
 TOLERANCE='1%',
 CLS_PN='G155-11003-01',
 VALUE='100KOHM',
 PRIM_FILE='./archive_libs/passive/resistor/chips/chips.prt';

PART_NAME
 R481 'RESISTOR-G155-11003-01,100KOHMA':;

SECTION_NUMBER 1
 '@TIMECARD_LIB.TIMECARD(SCH_1):PAGE524_I150@PASSIVE.RESISTOR(CHIPS)':
 C_PATH='@timecard_lib.timecard(sch_1):page524_i150@passive.resistor(chips)',
 P_PATH='@timecard_lib.timecard(sch_1):page24_i150@passive.resistor(chips)',
 PATH='I150',
 DRAWING='@TIMECARD_LIB.TIMECARD(SCH_1):PAGE524',
 PACKAGE='0402',
 PHYS_PAGE='24',
 XY='(-4200,9100)',
 ROT='1',
 VER='2',
 CDS_LIB='passive',
 CDS_PART_NAME='RESISTOR-G155-11003-01,100KOHMA',
 TOLERANCE='1%',
 CLS_PN='G155-11003-01',
 VALUE='100KOHM',
 PRIM_FILE='./archive_libs/passive/resistor/chips/chips.prt';

PART_NAME
 R482 'RESISTOR-G155-14701-01,4.7KOHMA':;

SECTION_NUMBER 1
 '@TIMECARD_LIB.TIMECARD(SCH_1):PAGE524_I464@PASSIVE.RESISTOR(CHIPS)':
 C_PATH='@timecard_lib.timecard(sch_1):page524_i464@passive.resistor(chips)',
 P_PATH='@timecard_lib.timecard(sch_1):page24_i464@passive.resistor(chips)',
 PATH='I464',
 DRAWING='@TIMECARD_LIB.TIMECARD(SCH_1):PAGE524',
 PACKAGE='0402',
 PHYS_PAGE='24',
 XY='(-3150,3850)',
 ROT='1',
 VER='2',
 CDS_LIB='passive',
 CDS_PART_NAME='RESISTOR-G155-14701-01,4.7KOHMA',
 NO_ASSY='TRUE',
 TOLERANCE='1%',
 CLS_PN='G155-14701-01',
 VALUE='4.7KOHM',
 PRIM_FILE='./archive_libs/passive/resistor/chips/chips.prt';

PART_NAME
 R483 'RESISTOR-G155-11001-01,1KOHM,1%':;

SECTION_NUMBER 1
 '@TIMECARD_LIB.TIMECARD(SCH_1):PAGE524_I462@PASSIVE.RESISTOR(CHIPS)':
 C_PATH='@timecard_lib.timecard(sch_1):page524_i462@passive.resistor(chips)',
 P_PATH='@timecard_lib.timecard(sch_1):page24_i462@passive.resistor(chips)',
 PATH='I462',
 DRAWING='@TIMECARD_LIB.TIMECARD(SCH_1):PAGE524',
 PACKAGE='0402',
 PHYS_PAGE='24',
 XY='(-3150,3750)',
 ROT='1',
 VER='2',
 CDS_LIB='passive',
 CDS_PART_NAME='RESISTOR-G155-11001-01,1KOHM,1%',
 TOLERANCE='1%',
 CLS_PN='G155-11001-01',
 VALUE='1KOHM',
 PRIM_FILE='./archive_libs/passive/resistor/chips/chips.prt';

PART_NAME
 R484 'RESISTOR-G155-11001-01,1KOHM,1%':;

SECTION_NUMBER 1
 '@TIMECARD_LIB.TIMECARD(SCH_1):PAGE524_I463@PASSIVE.RESISTOR(CHIPS)':
 C_PATH='@timecard_lib.timecard(sch_1):page524_i463@passive.resistor(chips)',
 P_PATH='@timecard_lib.timecard(sch_1):page24_i463@passive.resistor(chips)',
 PATH='I463',
 DRAWING='@TIMECARD_LIB.TIMECARD(SCH_1):PAGE524',
 PACKAGE='0402',
 PHYS_PAGE='24',
 XY='(-3150,3650)',
 ROT='1',
 VER='2',
 CDS_LIB='passive',
 CDS_PART_NAME='RESISTOR-G155-11001-01,1KOHM,1%',
 TOLERANCE='1%',
 CLS_PN='G155-11001-01',
 VALUE='1KOHM',
 PRIM_FILE='./archive_libs/passive/resistor/chips/chips.prt';

PART_NAME
 R485 'RESISTOR-G155-133R0-01,33OHM,1%':;

SECTION_NUMBER 1
 '@TIMECARD_LIB.TIMECARD(SCH_1):PAGE524_I459@PASSIVE.RESISTOR(CHIPS)':
 C_PATH='@timecard_lib.timecard(sch_1):page524_i459@passive.resistor(chips)',
 P_PATH='@timecard_lib.timecard(sch_1):page24_i459@passive.resistor(chips)',
 PATH='I459',
 DRAWING='@TIMECARD_LIB.TIMECARD(SCH_1):PAGE524',
 PACKAGE='0402',
 PHYS_PAGE='24',
 XY='(-3000,4400)',
 ROT='0',
 VER='1',
 CDS_LIB='passive',
 CDS_PART_NAME='RESISTOR-G155-133R0-01,33OHM,1%',
 NO_ASSY='TRUE',
 TOLERANCE='1%',
 CLS_PN='G155-133R0-01',
 VALUE='33OHM',
 PRIM_FILE='./archive_libs/passive/resistor/chips/chips.prt';

PART_NAME
 R486 'RESISTOR-G155-133R0-01,33OHM,1%':;

SECTION_NUMBER 1
 '@TIMECARD_LIB.TIMECARD(SCH_1):PAGE524_I460@PASSIVE.RESISTOR(CHIPS)':
 C_PATH='@timecard_lib.timecard(sch_1):page524_i460@passive.resistor(chips)',
 P_PATH='@timecard_lib.timecard(sch_1):page24_i460@passive.resistor(chips)',
 PATH='I460',
 DRAWING='@TIMECARD_LIB.TIMECARD(SCH_1):PAGE524',
 PACKAGE='0402',
 PHYS_PAGE='24',
 XY='(-3000,4300)',
 ROT='0',
 VER='1',
 CDS_LIB='passive',
 CDS_PART_NAME='RESISTOR-G155-133R0-01,33OHM,1%',
 TOLERANCE='1%',
 CLS_PN='G155-133R0-01',
 VALUE='33OHM',
 PRIM_FILE='./archive_libs/passive/resistor/chips/chips.prt';

PART_NAME
 R487 'RESISTOR-G155-14701-01,4.7KOHMA':;

SECTION_NUMBER 1
 '@TIMECARD_LIB.TIMECARD(SCH_1):PAGE525_I65@PASSIVE.RESISTOR(CHIPS)':
 C_PATH='@timecard_lib.timecard(sch_1):page525_i65@passive.resistor(chips)',
 P_PATH='@timecard_lib.timecard(sch_1):page33_i65@passive.resistor(chips)',
 PATH='I65',
 DRAWING='@TIMECARD_LIB.TIMECARD(SCH_1):PAGE525',
 PACKAGE='0402',
 PHYS_PAGE='33',
 XY='(300,2900)',
 ROT='0',
 VER='2',
 CDS_LIB='passive',
 CDS_PART_NAME='RESISTOR-G155-14701-01,4.7KOHMA',
 TOLERANCE='1%',
 CLS_PN='G155-14701-01',
 VALUE='4.7KOHM',
 PRIM_FILE='./archive_libs/passive/resistor/chips/chips.prt';

PART_NAME
 R488 'RESISTOR-G155-11002-01,10KOHM,A':;

SECTION_NUMBER 1
 '@TIMECARD_LIB.TIMECARD(SCH_1):PAGE525_I13@PASSIVE.RESISTOR(CHIPS)':
 C_PATH='@timecard_lib.timecard(sch_1):page525_i13@passive.resistor(chips)',
 P_PATH='@timecard_lib.timecard(sch_1):page33_i13@passive.resistor(chips)',
 PATH='I13',
 DRAWING='@TIMECARD_LIB.TIMECARD(SCH_1):PAGE525',
 PACKAGE='0402',
 PHYS_PAGE='33',
 XY='(300,1950)',
 ROT='0',
 VER='2',
 CDS_LIB='passive',
 CDS_PART_NAME='RESISTOR-G155-11002-01,10KOHM,A',
 TOLERANCE='1%',
 CLS_PN='G155-11002-01',
 VALUE='10KOHM',
 PRIM_FILE='./archive_libs/passive/resistor/chips/chips.prt';

PART_NAME
 R489 'RESISTOR-G155-03921-01,3.92KOHA':;

SECTION_NUMBER 1
 '@TIMECARD_LIB.TIMECARD(SCH_1):PAGE525_I68@PASSIVE.RESISTOR(CHIPS)':
 C_PATH='@timecard_lib.timecard(sch_1):page525_i68@passive.resistor(chips)',
 P_PATH='@timecard_lib.timecard(sch_1):page33_i68@passive.resistor(chips)',
 PATH='I68',
 DRAWING='@TIMECARD_LIB.TIMECARD(SCH_1):PAGE525',
 PACKAGE='0402',
 PHYS_PAGE='33',
 XY='(4900,2250)',
 ROT='0',
 VER='2',
 CDS_LIB='passive',
 CDS_PART_NAME='RESISTOR-G155-03921-01,3.92KOHA',
 TOLERANCE='1%',
 CLS_PN='G155-03921-01',
 VALUE='3.92KOHM',
 PRIM_FILE='./archive_libs/passive/resistor/chips/chips.prt';

PART_NAME
 R490 'RESISTOR-G155-11002-01,10KOHM,A':;

SECTION_NUMBER 1
 '@TIMECARD_LIB.TIMECARD(SCH_1):PAGE525_I66@PASSIVE.RESISTOR(CHIPS)':
 C_PATH='@timecard_lib.timecard(sch_1):page525_i66@passive.resistor(chips)',
 P_PATH='@timecard_lib.timecard(sch_1):page33_i66@passive.resistor(chips)',
 PATH='I66',
 DRAWING='@TIMECARD_LIB.TIMECARD(SCH_1):PAGE525',
 PACKAGE='0402',
 PHYS_PAGE='33',
 XY='(5500,2950)',
 ROT='0',
 VER='2',
 CDS_LIB='passive',
 CDS_PART_NAME='RESISTOR-G155-11002-01,10KOHM,A',
 TOLERANCE='1%',
 CLS_PN='G155-11002-01',
 VALUE='10KOHM',
 PRIM_FILE='./archive_libs/passive/resistor/chips/chips.prt';

PART_NAME
 R491 'RESISTOR-G155-03241-01,3.24KOHA':;

SECTION_NUMBER 1
 '@TIMECARD_LIB.TIMECARD(SCH_1):PAGE525_I67@PASSIVE.RESISTOR(CHIPS)':
 C_PATH='@timecard_lib.timecard(sch_1):page525_i67@passive.resistor(chips)',
 P_PATH='@timecard_lib.timecard(sch_1):page33_i67@passive.resistor(chips)',
 PATH='I67',
 DRAWING='@TIMECARD_LIB.TIMECARD(SCH_1):PAGE525',
 PACKAGE='0402',
 PHYS_PAGE='33',
 XY='(5500,2250)',
 ROT='0',
 VER='2',
 CDS_LIB='passive',
 CDS_PART_NAME='RESISTOR-G155-03241-01,3.24KOHA',
 TOLERANCE='1%',
 CLS_PN='G155-03241-01',
 VALUE='3.24KOHM',
 PRIM_FILE='./archive_libs/passive/resistor/chips/chips.prt';

PART_NAME
 R492 'RESISTOR-G155-100R0-J0,0OHM,-':;

SECTION_NUMBER 1
 '@TIMECARD_LIB.TIMECARD(SCH_1):PAGE12_I319@PASSIVE.RESISTOR(CHIPS)':
 C_PATH='@timecard_lib.timecard(sch_1):page12_i319@passive.resistor(chips)',
 P_PATH='@timecard_lib.timecard(sch_1):page23_i319@passive.resistor(chips)',
 PATH='I319',
 DRAWING='@TIMECARD_LIB.TIMECARD(SCH_1):PAGE12',
 PACKAGE='0402',
 PHYS_PAGE='23',
 XY='(-10000,8600)',
 ROT='6',
 VER='2',
 CDS_LIB='passive',
 CDS_PART_NAME='RESISTOR-G155-100R0-J0,0OHM,-',
 TOLERANCE='-',
 CLS_PN='G155-100R0-J0',
 VALUE='0OHM',
 PRIM_FILE='./archive_libs/passive/resistor/chips/chips.prt';

PART_NAME
 R493 'RESISTOR-G155-100R0-J0,0OHM,-':;

SECTION_NUMBER 1
 '@TIMECARD_LIB.TIMECARD(SCH_1):PAGE12_I323@PASSIVE.RESISTOR(CHIPS)':
 C_PATH='@timecard_lib.timecard(sch_1):page12_i323@passive.resistor(chips)',
 P_PATH='@timecard_lib.timecard(sch_1):page23_i323@passive.resistor(chips)',
 PATH='I323',
 DRAWING='@TIMECARD_LIB.TIMECARD(SCH_1):PAGE12',
 PACKAGE='0402',
 PHYS_PAGE='23',
 XY='(-9950,6450)',
 ROT='6',
 VER='2',
 CDS_LIB='passive',
 CDS_PART_NAME='RESISTOR-G155-100R0-J0,0OHM,-',
 TOLERANCE='-',
 CLS_PN='G155-100R0-J0',
 VALUE='0OHM',
 PRIM_FILE='./archive_libs/passive/resistor/chips/chips.prt';

PART_NAME
 R494 'RESISTOR-G155-100R0-J0,0OHM,-':;

SECTION_NUMBER 1
 '@TIMECARD_LIB.TIMECARD(SCH_1):PAGE12_I326@PASSIVE.RESISTOR(CHIPS)':
 C_PATH='@timecard_lib.timecard(sch_1):page12_i326@passive.resistor(chips)',
 P_PATH='@timecard_lib.timecard(sch_1):page23_i326@passive.resistor(chips)',
 PATH='I326',
 DRAWING='@TIMECARD_LIB.TIMECARD(SCH_1):PAGE12',
 PACKAGE='0402',
 PHYS_PAGE='23',
 XY='(-9950,4300)',
 ROT='6',
 VER='2',
 CDS_LIB='passive',
 CDS_PART_NAME='RESISTOR-G155-100R0-J0,0OHM,-',
 TOLERANCE='-',
 CLS_PN='G155-100R0-J0',
 VALUE='0OHM',
 PRIM_FILE='./archive_libs/passive/resistor/chips/chips.prt';

PART_NAME
 R495 'RESISTOR-G155-100R0-J0,0OHM,-':;

SECTION_NUMBER 1
 '@TIMECARD_LIB.TIMECARD(SCH_1):PAGE12_I330@PASSIVE.RESISTOR(CHIPS)':
 C_PATH='@timecard_lib.timecard(sch_1):page12_i330@passive.resistor(chips)',
 P_PATH='@timecard_lib.timecard(sch_1):page23_i330@passive.resistor(chips)',
 PATH='I330',
 DRAWING='@TIMECARD_LIB.TIMECARD(SCH_1):PAGE12',
 PACKAGE='0402',
 PHYS_PAGE='23',
 XY='(-9900,2150)',
 ROT='6',
 VER='2',
 CDS_LIB='passive',
 CDS_PART_NAME='RESISTOR-G155-100R0-J0,0OHM,-',
 TOLERANCE='-',
 CLS_PN='G155-100R0-J0',
 VALUE='0OHM',
 PRIM_FILE='./archive_libs/passive/resistor/chips/chips.prt';

PART_NAME
 R496 'RESISTOR-G155-11004-01,1MOHM,1%':;

SECTION_NUMBER 1
 '@TIMECARD_LIB.TIMECARD(SCH_1):PAGE12_I320@PASSIVE.RESISTOR(CHIPS)':
 C_PATH='@timecard_lib.timecard(sch_1):page12_i320@passive.resistor(chips)',
 P_PATH='@timecard_lib.timecard(sch_1):page23_i320@passive.resistor(chips)',
 PATH='I320',
 DRAWING='@TIMECARD_LIB.TIMECARD(SCH_1):PAGE12',
 PACKAGE='0402',
 PHYS_PAGE='23',
 XY='(-9750,8350)',
 ROT='4',
 VER='2',
 CDS_LIB='passive',
 CDS_PART_NAME='RESISTOR-G155-11004-01,1MOHM,1%',
 TOLERANCE='1%',
 CLS_PN='G155-11004-01',
 VALUE='1MOHM',
 PRIM_FILE='./archive_libs/passive/resistor/chips/chips.prt';

PART_NAME
 R497 'RESISTOR-G155-11004-01,1MOHM,1%':;

SECTION_NUMBER 1
 '@TIMECARD_LIB.TIMECARD(SCH_1):PAGE12_I322@PASSIVE.RESISTOR(CHIPS)':
 C_PATH='@timecard_lib.timecard(sch_1):page12_i322@passive.resistor(chips)',
 P_PATH='@timecard_lib.timecard(sch_1):page23_i322@passive.resistor(chips)',
 PATH='I322',
 DRAWING='@TIMECARD_LIB.TIMECARD(SCH_1):PAGE12',
 PACKAGE='0402',
 PHYS_PAGE='23',
 XY='(-9700,6200)',
 ROT='4',
 VER='2',
 CDS_LIB='passive',
 CDS_PART_NAME='RESISTOR-G155-11004-01,1MOHM,1%',
 TOLERANCE='1%',
 CLS_PN='G155-11004-01',
 VALUE='1MOHM',
 PRIM_FILE='./archive_libs/passive/resistor/chips/chips.prt';

PART_NAME
 R498 'RESISTOR-G155-11004-01,1MOHM,1%':;

SECTION_NUMBER 1
 '@TIMECARD_LIB.TIMECARD(SCH_1):PAGE12_I327@PASSIVE.RESISTOR(CHIPS)':
 C_PATH='@timecard_lib.timecard(sch_1):page12_i327@passive.resistor(chips)',
 P_PATH='@timecard_lib.timecard(sch_1):page23_i327@passive.resistor(chips)',
 PATH='I327',
 DRAWING='@TIMECARD_LIB.TIMECARD(SCH_1):PAGE12',
 PACKAGE='0402',
 PHYS_PAGE='23',
 XY='(-9700,4050)',
 ROT='4',
 VER='2',
 CDS_LIB='passive',
 CDS_PART_NAME='RESISTOR-G155-11004-01,1MOHM,1%',
 TOLERANCE='1%',
 CLS_PN='G155-11004-01',
 VALUE='1MOHM',
 PRIM_FILE='./archive_libs/passive/resistor/chips/chips.prt';

PART_NAME
 R499 'RESISTOR-G155-11004-01,1MOHM,1%':;

SECTION_NUMBER 1
 '@TIMECARD_LIB.TIMECARD(SCH_1):PAGE12_I331@PASSIVE.RESISTOR(CHIPS)':
 C_PATH='@timecard_lib.timecard(sch_1):page12_i331@passive.resistor(chips)',
 P_PATH='@timecard_lib.timecard(sch_1):page23_i331@passive.resistor(chips)',
 PATH='I331',
 DRAWING='@TIMECARD_LIB.TIMECARD(SCH_1):PAGE12',
 PACKAGE='0402',
 PHYS_PAGE='23',
 XY='(-9650,1900)',
 ROT='4',
 VER='2',
 CDS_LIB='passive',
 CDS_PART_NAME='RESISTOR-G155-11004-01,1MOHM,1%',
 TOLERANCE='1%',
 CLS_PN='G155-11004-01',
 VALUE='1MOHM',
 PRIM_FILE='./archive_libs/passive/resistor/chips/chips.prt';

PART_NAME
 R500 'RESISTOR-G155-14701-01,4.7KOHMA':;

SECTION_NUMBER 1
 '@TIMECARD_LIB.TIMECARD(SCH_1):PAGE161_I242@PASSIVE.RESISTOR(CHIPS)':
 C_PATH='@timecard_lib.timecard(sch_1):page161_i242@passive.resistor(chips)',
 P_PATH='@timecard_lib.timecard(sch_1):page11_i242@passive.resistor(chips)',
 PATH='I242',
 DRAWING='@TIMECARD_LIB.TIMECARD(SCH_1):PAGE161',
 PACKAGE='0402',
 PHYS_PAGE='11',
 XY='(-12550,6300)',
 ROT='1',
 VER='2',
 CDS_LIB='passive',
 CDS_PART_NAME='RESISTOR-G155-14701-01,4.7KOHMA',
 NO_ASSY='TRUE',
 TOLERANCE='1%',
 CLS_PN='G155-14701-01',
 VALUE='4.7KOHM',
 PRIM_FILE='./archive_libs/passive/resistor/chips/chips.prt';

PART_NAME
 R501 'RESISTOR-G155-14701-01,4.7KOHMA':;

SECTION_NUMBER 1
 '@TIMECARD_LIB.TIMECARD(SCH_1):PAGE161_I241@PASSIVE.RESISTOR(CHIPS)':
 C_PATH='@timecard_lib.timecard(sch_1):page161_i241@passive.resistor(chips)',
 P_PATH='@timecard_lib.timecard(sch_1):page11_i241@passive.resistor(chips)',
 PATH='I241',
 DRAWING='@TIMECARD_LIB.TIMECARD(SCH_1):PAGE161',
 PACKAGE='0402',
 PHYS_PAGE='11',
 XY='(-12550,6200)',
 ROT='1',
 VER='2',
 CDS_LIB='passive',
 CDS_PART_NAME='RESISTOR-G155-14701-01,4.7KOHMA',
 NO_ASSY='TRUE',
 TOLERANCE='1%',
 CLS_PN='G155-14701-01',
 VALUE='4.7KOHM',
 PRIM_FILE='./archive_libs/passive/resistor/chips/chips.prt';

PART_NAME
 R502 'RESISTOR-G155-14701-01,4.7KOHMA':;

SECTION_NUMBER 1
 '@TIMECARD_LIB.TIMECARD(SCH_1):PAGE161_I247@PASSIVE.RESISTOR(CHIPS)':
 C_PATH='@timecard_lib.timecard(sch_1):page161_i247@passive.resistor(chips)',
 P_PATH='@timecard_lib.timecard(sch_1):page11_i247@passive.resistor(chips)',
 PATH='I247',
 DRAWING='@TIMECARD_LIB.TIMECARD(SCH_1):PAGE161',
 PACKAGE='0402',
 PHYS_PAGE='11',
 XY='(-12550,5900)',
 ROT='1',
 VER='2',
 CDS_LIB='passive',
 CDS_PART_NAME='RESISTOR-G155-14701-01,4.7KOHMA',
 TOLERANCE='1%',
 CLS_PN='G155-14701-01',
 VALUE='4.7KOHM',
 PRIM_FILE='./archive_libs/passive/resistor/chips/chips.prt';

PART_NAME
 R503 'RESISTOR-G155-14701-01,4.7KOHMA':;

SECTION_NUMBER 1
 '@TIMECARD_LIB.TIMECARD(SCH_1):PAGE161_I246@PASSIVE.RESISTOR(CHIPS)':
 C_PATH='@timecard_lib.timecard(sch_1):page161_i246@passive.resistor(chips)',
 P_PATH='@timecard_lib.timecard(sch_1):page11_i246@passive.resistor(chips)',
 PATH='I246',
 DRAWING='@TIMECARD_LIB.TIMECARD(SCH_1):PAGE161',
 PACKAGE='0402',
 PHYS_PAGE='11',
 XY='(-3850,6700)',
 ROT='1',
 VER='2',
 CDS_LIB='passive',
 CDS_PART_NAME='RESISTOR-G155-14701-01,4.7KOHMA',
 NO_ASSY='TRUE',
 TOLERANCE='1%',
 CLS_PN='G155-14701-01',
 VALUE='4.7KOHM',
 PRIM_FILE='./archive_libs/passive/resistor/chips/chips.prt';

PART_NAME
 R504 'RESISTOR-G155-14701-01,4.7KOHMA':;

SECTION_NUMBER 1
 '@TIMECARD_LIB.TIMECARD(SCH_1):PAGE161_I244@PASSIVE.RESISTOR(CHIPS)':
 C_PATH='@timecard_lib.timecard(sch_1):page161_i244@passive.resistor(chips)',
 P_PATH='@timecard_lib.timecard(sch_1):page11_i244@passive.resistor(chips)',
 PATH='I244',
 DRAWING='@TIMECARD_LIB.TIMECARD(SCH_1):PAGE161',
 PACKAGE='0402',
 PHYS_PAGE='11',
 XY='(-3850,6600)',
 ROT='1',
 VER='2',
 CDS_LIB='passive',
 CDS_PART_NAME='RESISTOR-G155-14701-01,4.7KOHMA',
 NO_ASSY='TRUE',
 TOLERANCE='1%',
 CLS_PN='G155-14701-01',
 VALUE='4.7KOHM',
 PRIM_FILE='./archive_libs/passive/resistor/chips/chips.prt';

PART_NAME
 R1991 'RESISTOR-G155-11002-01,10KOHM,A':;

SECTION_NUMBER 1
 '@TIMECARD_LIB.TIMECARD(SCH_1):PAGE5_I96@PASSIVE.RESISTOR(CHIPS)':
 C_PATH='@timecard_lib.timecard(sch_1):page5_i96@passive.resistor(chips)',
 P_PATH='@timecard_lib.timecard(sch_1):page16_i96@passive.resistor(chips)',
 PATH='I96',
 DRAWING='@TIMECARD_LIB.TIMECARD(SCH_1):PAGE5',
 PACKAGE='0402',
 PHYS_PAGE='16',
 XY='(-9250,6300)',
 ROT='0',
 VER='2',
 CDS_LIB='passive',
 CDS_PART_NAME='RESISTOR-G155-11002-01,10KOHM,A',
 TOLERANCE='1%',
 CLS_PN='G155-11002-01',
 VALUE='10KOHM',
 PRIM_FILE='./archive_libs/passive/resistor/chips/chips.prt';

PART_NAME
 R1992 'RESISTOR-G155-14701-01,4.7KOHMA':;

SECTION_NUMBER 1
 '@TIMECARD_LIB.TIMECARD(SCH_1):PAGE5_I94@PASSIVE.RESISTOR(CHIPS)':
 C_PATH='@timecard_lib.timecard(sch_1):page5_i94@passive.resistor(chips)',
 P_PATH='@timecard_lib.timecard(sch_1):page16_i94@passive.resistor(chips)',
 PATH='I94',
 DRAWING='@TIMECARD_LIB.TIMECARD(SCH_1):PAGE5',
 PACKAGE='0402',
 PHYS_PAGE='16',
 XY='(-9700,6300)',
 ROT='0',
 VER='2',
 CDS_LIB='passive',
 CDS_PART_NAME='RESISTOR-G155-14701-01,4.7KOHMA',
 TOLERANCE='1%',
 CLS_PN='G155-14701-01',
 VALUE='4.7KOHM',
 PRIM_FILE='./archive_libs/passive/resistor/chips/chips.prt';

PART_NAME
 SP1 'SOLDER_PREFORM-G380-10015-01':;

SECTION_NUMBER 1
 '@TIMECARD_LIB.TIMECARD(SCH_1):PAGE516_I24@MECH.SOLDER_PREFORM(CHIPS)':
 C_PATH='@timecard_lib.timecard(sch_1):page516_i24@mech.solder_preform(chips)',
 P_PATH='@timecard_lib.timecard(sch_1):page32_i24@mech.solder_preform(chips)',
 PATH='I24',
 DRAWING='@TIMECARD_LIB.TIMECARD(SCH_1):PAGE516',
 PHYS_PAGE='32',
 XY='(-7500,5150)',
 ROT='0',
 VER='1',
 CDS_LIB='mech',
 CDS_PART_NAME='SOLDER_PREFORM-G380-10015-01',
 CLS_PN='G380-10015-01',
 PRIM_FILE='./archive_libs/mech/solder_preform/chips/chips.prt';

PART_NAME
 SP2 'SOLDER_PREFORM-G380-10015-01':;

SECTION_NUMBER 1
 '@TIMECARD_LIB.TIMECARD(SCH_1):PAGE517_I24@MECH.SOLDER_PREFORM(CHIPS)':
 C_PATH='@timecard_lib.timecard(sch_1):page517_i24@mech.solder_preform(chips)',
 P_PATH='@timecard_lib.timecard(sch_1):page28_i24@mech.solder_preform(chips)',
 PATH='I24',
 DRAWING='@TIMECARD_LIB.TIMECARD(SCH_1):PAGE517',
 PHYS_PAGE='28',
 XY='(-7150,4350)',
 ROT='0',
 VER='1',
 CDS_LIB='mech',
 CDS_PART_NAME='SOLDER_PREFORM-G380-10015-01',
 CLS_PN='G380-10015-01',
 PRIM_FILE='./archive_libs/mech/solder_preform/chips/chips.prt';

PART_NAME
 SP3 'SOLDER_PREFORM-G380-10015-01':;

SECTION_NUMBER 1
 '@TIMECARD_LIB.TIMECARD(SCH_1):PAGE523_I39@MECH.SOLDER_PREFORM(CHIPS)':
 C_PATH='@timecard_lib.timecard(sch_1):page523_i39@mech.solder_preform(chips)',
 P_PATH='@timecard_lib.timecard(sch_1):page29_i39@mech.solder_preform(chips)',
 PATH='I39',
 DRAWING='@TIMECARD_LIB.TIMECARD(SCH_1):PAGE523',
 PHYS_PAGE='29',
 XY='(-6150,2700)',
 ROT='0',
 VER='1',
 CDS_LIB='mech',
 CDS_PART_NAME='SOLDER_PREFORM-G380-10015-01',
 CLS_PN='G380-10015-01',
 PRIM_FILE='./archive_libs/mech/solder_preform/chips/chips.prt';

PART_NAME
 SP4 'SOLDER_PREFORM-G380-10015-01':;

SECTION_NUMBER 1
 '@TIMECARD_LIB.TIMECARD(SCH_1):PAGE33_I130@MECH.SOLDER_PREFORM(CHIPS)':
 C_PATH='@timecard_lib.timecard(sch_1):page33_i130@mech.solder_preform(chips)',
 P_PATH='@timecard_lib.timecard(sch_1):page34_i130@mech.solder_preform(chips)',
 PATH='I130',
 DRAWING='@TIMECARD_LIB.TIMECARD(SCH_1):PAGE33',
 PHYS_PAGE='34',
 XY='(-12750,2100)',
 ROT='0',
 VER='1',
 LOCATION='SP4',
 CDS_LIB='mech',
 CDS_PART_NAME='SOLDER_PREFORM-G380-10015-01',
 CLS_PN='G380-10015-01',
 PRIM_FILE='./archive_libs/mech/solder_preform/chips/chips.prt';

PART_NAME
 SP5 'SOLDER_PREFORM-G380-10015-01':;

SECTION_NUMBER 1
 '@TIMECARD_LIB.TIMECARD(SCH_1):PAGE33_I131@MECH.SOLDER_PREFORM(CHIPS)':
 C_PATH='@timecard_lib.timecard(sch_1):page33_i131@mech.solder_preform(chips)',
 P_PATH='@timecard_lib.timecard(sch_1):page34_i131@mech.solder_preform(chips)',
 PATH='I131',
 DRAWING='@TIMECARD_LIB.TIMECARD(SCH_1):PAGE33',
 PHYS_PAGE='34',
 XY='(-11850,2100)',
 ROT='0',
 VER='1',
 LOCATION='SP5',
 CDS_LIB='mech',
 CDS_PART_NAME='SOLDER_PREFORM-G380-10015-01',
 CLS_PN='G380-10015-01',
 PRIM_FILE='./archive_libs/mech/solder_preform/chips/chips.prt';

PART_NAME
 SP6 'SOLDER_PREFORM-G380-10015-01':;

SECTION_NUMBER 1
 '@TIMECARD_LIB.TIMECARD(SCH_1):PAGE33_I133@MECH.SOLDER_PREFORM(CHIPS)':
 C_PATH='@timecard_lib.timecard(sch_1):page33_i133@mech.solder_preform(chips)',
 P_PATH='@timecard_lib.timecard(sch_1):page34_i133@mech.solder_preform(chips)',
 PATH='I133',
 DRAWING='@TIMECARD_LIB.TIMECARD(SCH_1):PAGE33',
 PHYS_PAGE='34',
 XY='(-11000,2100)',
 ROT='0',
 VER='1',
 LOCATION='SP6',
 CDS_LIB='mech',
 CDS_PART_NAME='SOLDER_PREFORM-G380-10015-01',
 CLS_PN='G380-10015-01',
 PRIM_FILE='./archive_libs/mech/solder_preform/chips/chips.prt';

PART_NAME
 SP7 'SOLDER_PREFORM-G380-10015-01':;

SECTION_NUMBER 1
 '@TIMECARD_LIB.TIMECARD(SCH_1):PAGE33_I132@MECH.SOLDER_PREFORM(CHIPS)':
 C_PATH='@timecard_lib.timecard(sch_1):page33_i132@mech.solder_preform(chips)',
 P_PATH='@timecard_lib.timecard(sch_1):page34_i132@mech.solder_preform(chips)',
 PATH='I132',
 DRAWING='@TIMECARD_LIB.TIMECARD(SCH_1):PAGE33',
 PHYS_PAGE='34',
 XY='(-10100,2100)',
 ROT='0',
 VER='1',
 LOCATION='SP7',
 CDS_LIB='mech',
 CDS_PART_NAME='SOLDER_PREFORM-G380-10015-01',
 CLS_PN='G380-10015-01',
 PRIM_FILE='./archive_libs/mech/solder_preform/chips/chips.prt';

PART_NAME
 SP8 'SOLDER_PREFORM-G380-10015-01':;

SECTION_NUMBER 1
 '@TIMECARD_LIB.TIMECARD(SCH_1):PAGE33_I134@MECH.SOLDER_PREFORM(CHIPS)':
 C_PATH='@timecard_lib.timecard(sch_1):page33_i134@mech.solder_preform(chips)',
 P_PATH='@timecard_lib.timecard(sch_1):page34_i134@mech.solder_preform(chips)',
 PATH='I134',
 DRAWING='@TIMECARD_LIB.TIMECARD(SCH_1):PAGE33',
 PHYS_PAGE='34',
 XY='(-9150,2100)',
 ROT='0',
 VER='1',
 LOCATION='SP8',
 CDS_LIB='mech',
 CDS_PART_NAME='SOLDER_PREFORM-G380-10015-01',
 CLS_PN='G380-10015-01',
 PRIM_FILE='./archive_libs/mech/solder_preform/chips/chips.prt';

PART_NAME
 SP9 'SOLDER_PREFORM-G380-10015-01':;

SECTION_NUMBER 1
 '@TIMECARD_LIB.TIMECARD(SCH_1):PAGE33_I135@MECH.SOLDER_PREFORM(CHIPS)':
 C_PATH='@timecard_lib.timecard(sch_1):page33_i135@mech.solder_preform(chips)',
 P_PATH='@timecard_lib.timecard(sch_1):page34_i135@mech.solder_preform(chips)',
 PATH='I135',
 DRAWING='@TIMECARD_LIB.TIMECARD(SCH_1):PAGE33',
 PHYS_PAGE='34',
 XY='(-8250,2100)',
 ROT='0',
 VER='1',
 LOCATION='SP9',
 CDS_LIB='mech',
 CDS_PART_NAME='SOLDER_PREFORM-G380-10015-01',
 CLS_PN='G380-10015-01',
 PRIM_FILE='./archive_libs/mech/solder_preform/chips/chips.prt';

PART_NAME
 SP10 'SOLDER_PREFORM-G380-10015-01':;

SECTION_NUMBER 1
 '@TIMECARD_LIB.TIMECARD(SCH_1):PAGE33_I137@MECH.SOLDER_PREFORM(CHIPS)':
 C_PATH='@timecard_lib.timecard(sch_1):page33_i137@mech.solder_preform(chips)',
 P_PATH='@timecard_lib.timecard(sch_1):page34_i137@mech.solder_preform(chips)',
 PATH='I137',
 DRAWING='@TIMECARD_LIB.TIMECARD(SCH_1):PAGE33',
 PHYS_PAGE='34',
 XY='(-7400,2100)',
 ROT='0',
 VER='1',
 LOCATION='SP10',
 CDS_LIB='mech',
 CDS_PART_NAME='SOLDER_PREFORM-G380-10015-01',
 CLS_PN='G380-10015-01',
 PRIM_FILE='./archive_libs/mech/solder_preform/chips/chips.prt';

PART_NAME
 SP11 'SOLDER_PREFORM-G380-10015-01':;

SECTION_NUMBER 1
 '@TIMECARD_LIB.TIMECARD(SCH_1):PAGE33_I136@MECH.SOLDER_PREFORM(CHIPS)':
 C_PATH='@timecard_lib.timecard(sch_1):page33_i136@mech.solder_preform(chips)',
 P_PATH='@timecard_lib.timecard(sch_1):page34_i136@mech.solder_preform(chips)',
 PATH='I136',
 DRAWING='@TIMECARD_LIB.TIMECARD(SCH_1):PAGE33',
 PHYS_PAGE='34',
 XY='(-6500,2100)',
 ROT='0',
 VER='1',
 LOCATION='SP11',
 CDS_LIB='mech',
 CDS_PART_NAME='SOLDER_PREFORM-G380-10015-01',
 CLS_PN='G380-10015-01',
 PRIM_FILE='./archive_libs/mech/solder_preform/chips/chips.prt';

PART_NAME
 SP12 'SOLDER_PREFORM-G380-10015-01':;

SECTION_NUMBER 1
 '@TIMECARD_LIB.TIMECARD(SCH_1):PAGE33_I141@MECH.SOLDER_PREFORM(CHIPS)':
 C_PATH='@timecard_lib.timecard(sch_1):page33_i141@mech.solder_preform(chips)',
 P_PATH='@timecard_lib.timecard(sch_1):page34_i141@mech.solder_preform(chips)',
 PATH='I141',
 DRAWING='@TIMECARD_LIB.TIMECARD(SCH_1):PAGE33',
 PHYS_PAGE='34',
 XY='(-5550,2100)',
 ROT='0',
 VER='1',
 LOCATION='SP12',
 CDS_LIB='mech',
 CDS_PART_NAME='SOLDER_PREFORM-G380-10015-01',
 CLS_PN='G380-10015-01',
 PRIM_FILE='./archive_libs/mech/solder_preform/chips/chips.prt';

PART_NAME
 SP13 'SOLDER_PREFORM-G380-10015-01':;

SECTION_NUMBER 1
 '@TIMECARD_LIB.TIMECARD(SCH_1):PAGE33_I140@MECH.SOLDER_PREFORM(CHIPS)':
 C_PATH='@timecard_lib.timecard(sch_1):page33_i140@mech.solder_preform(chips)',
 P_PATH='@timecard_lib.timecard(sch_1):page34_i140@mech.solder_preform(chips)',
 PATH='I140',
 DRAWING='@TIMECARD_LIB.TIMECARD(SCH_1):PAGE33',
 PHYS_PAGE='34',
 XY='(-4650,2100)',
 ROT='0',
 VER='1',
 LOCATION='SP13',
 CDS_LIB='mech',
 CDS_PART_NAME='SOLDER_PREFORM-G380-10015-01',
 CLS_PN='G380-10015-01',
 PRIM_FILE='./archive_libs/mech/solder_preform/chips/chips.prt';

PART_NAME
 SP14 'SOLDER_PREFORM-G380-10015-01':;

SECTION_NUMBER 1
 '@TIMECARD_LIB.TIMECARD(SCH_1):PAGE33_I139@MECH.SOLDER_PREFORM(CHIPS)':
 C_PATH='@timecard_lib.timecard(sch_1):page33_i139@mech.solder_preform(chips)',
 P_PATH='@timecard_lib.timecard(sch_1):page34_i139@mech.solder_preform(chips)',
 PATH='I139',
 DRAWING='@TIMECARD_LIB.TIMECARD(SCH_1):PAGE33',
 PHYS_PAGE='34',
 XY='(-3800,2100)',
 ROT='0',
 VER='1',
 LOCATION='SP14',
 CDS_LIB='mech',
 CDS_PART_NAME='SOLDER_PREFORM-G380-10015-01',
 CLS_PN='G380-10015-01',
 PRIM_FILE='./archive_libs/mech/solder_preform/chips/chips.prt';

PART_NAME
 SP15 'SOLDER_PREFORM-G380-10015-01':;

SECTION_NUMBER 1
 '@TIMECARD_LIB.TIMECARD(SCH_1):PAGE33_I138@MECH.SOLDER_PREFORM(CHIPS)':
 C_PATH='@timecard_lib.timecard(sch_1):page33_i138@mech.solder_preform(chips)',
 P_PATH='@timecard_lib.timecard(sch_1):page34_i138@mech.solder_preform(chips)',
 PATH='I138',
 DRAWING='@TIMECARD_LIB.TIMECARD(SCH_1):PAGE33',
 PHYS_PAGE='34',
 XY='(-2900,2100)',
 ROT='0',
 VER='1',
 LOCATION='SP15',
 CDS_LIB='mech',
 CDS_PART_NAME='SOLDER_PREFORM-G380-10015-01',
 CLS_PN='G380-10015-01',
 PRIM_FILE='./archive_libs/mech/solder_preform/chips/chips.prt';

PART_NAME
 SP16 'SOLDER_PREFORM-G380-10015-01':;

SECTION_NUMBER 1
 '@TIMECARD_LIB.TIMECARD(SCH_1):PAGE33_I153@MECH.SOLDER_PREFORM(CHIPS)':
 C_PATH='@timecard_lib.timecard(sch_1):page33_i153@mech.solder_preform(chips)',
 P_PATH='@timecard_lib.timecard(sch_1):page34_i153@mech.solder_preform(chips)',
 PATH='I153',
 DRAWING='@TIMECARD_LIB.TIMECARD(SCH_1):PAGE33',
 PHYS_PAGE='34',
 XY='(-12750,1600)',
 ROT='0',
 VER='1',
 LOCATION='SP16',
 CDS_LIB='mech',
 CDS_PART_NAME='SOLDER_PREFORM-G380-10015-01',
 CLS_PN='G380-10015-01',
 PRIM_FILE='./archive_libs/mech/solder_preform/chips/chips.prt';

PART_NAME
 SP17 'SOLDER_PREFORM-G380-10015-01':;

SECTION_NUMBER 1
 '@TIMECARD_LIB.TIMECARD(SCH_1):PAGE33_I142@MECH.SOLDER_PREFORM(CHIPS)':
 C_PATH='@timecard_lib.timecard(sch_1):page33_i142@mech.solder_preform(chips)',
 P_PATH='@timecard_lib.timecard(sch_1):page34_i142@mech.solder_preform(chips)',
 PATH='I142',
 DRAWING='@TIMECARD_LIB.TIMECARD(SCH_1):PAGE33',
 PHYS_PAGE='34',
 XY='(-11850,1600)',
 ROT='0',
 VER='1',
 LOCATION='SP17',
 CDS_LIB='mech',
 CDS_PART_NAME='SOLDER_PREFORM-G380-10015-01',
 CLS_PN='G380-10015-01',
 PRIM_FILE='./archive_libs/mech/solder_preform/chips/chips.prt';

PART_NAME
 SP18 'SOLDER_PREFORM-G380-10015-01':;

SECTION_NUMBER 1
 '@TIMECARD_LIB.TIMECARD(SCH_1):PAGE33_I152@MECH.SOLDER_PREFORM(CHIPS)':
 C_PATH='@timecard_lib.timecard(sch_1):page33_i152@mech.solder_preform(chips)',
 P_PATH='@timecard_lib.timecard(sch_1):page34_i152@mech.solder_preform(chips)',
 PATH='I152',
 DRAWING='@TIMECARD_LIB.TIMECARD(SCH_1):PAGE33',
 PHYS_PAGE='34',
 XY='(-11000,1600)',
 ROT='0',
 VER='1',
 LOCATION='SP18',
 CDS_LIB='mech',
 CDS_PART_NAME='SOLDER_PREFORM-G380-10015-01',
 CLS_PN='G380-10015-01',
 PRIM_FILE='./archive_libs/mech/solder_preform/chips/chips.prt';

PART_NAME
 SP19 'SOLDER_PREFORM-G380-10015-01':;

SECTION_NUMBER 1
 '@TIMECARD_LIB.TIMECARD(SCH_1):PAGE33_I151@MECH.SOLDER_PREFORM(CHIPS)':
 C_PATH='@timecard_lib.timecard(sch_1):page33_i151@mech.solder_preform(chips)',
 P_PATH='@timecard_lib.timecard(sch_1):page34_i151@mech.solder_preform(chips)',
 PATH='I151',
 DRAWING='@TIMECARD_LIB.TIMECARD(SCH_1):PAGE33',
 PHYS_PAGE='34',
 XY='(-10100,1600)',
 ROT='0',
 VER='1',
 LOCATION='SP19',
 CDS_LIB='mech',
 CDS_PART_NAME='SOLDER_PREFORM-G380-10015-01',
 CLS_PN='G380-10015-01',
 PRIM_FILE='./archive_libs/mech/solder_preform/chips/chips.prt';

PART_NAME
 SP20 'SOLDER_PREFORM-G380-10015-01':;

SECTION_NUMBER 1
 '@TIMECARD_LIB.TIMECARD(SCH_1):PAGE33_I149@MECH.SOLDER_PREFORM(CHIPS)':
 C_PATH='@timecard_lib.timecard(sch_1):page33_i149@mech.solder_preform(chips)',
 P_PATH='@timecard_lib.timecard(sch_1):page34_i149@mech.solder_preform(chips)',
 PATH='I149',
 DRAWING='@TIMECARD_LIB.TIMECARD(SCH_1):PAGE33',
 PHYS_PAGE='34',
 XY='(-9150,1600)',
 ROT='0',
 VER='1',
 LOCATION='SP20',
 CDS_LIB='mech',
 CDS_PART_NAME='SOLDER_PREFORM-G380-10015-01',
 CLS_PN='G380-10015-01',
 PRIM_FILE='./archive_libs/mech/solder_preform/chips/chips.prt';

PART_NAME
 SP21 'SOLDER_PREFORM-G380-10015-01':;

SECTION_NUMBER 1
 '@TIMECARD_LIB.TIMECARD(SCH_1):PAGE33_I150@MECH.SOLDER_PREFORM(CHIPS)':
 C_PATH='@timecard_lib.timecard(sch_1):page33_i150@mech.solder_preform(chips)',
 P_PATH='@timecard_lib.timecard(sch_1):page34_i150@mech.solder_preform(chips)',
 PATH='I150',
 DRAWING='@TIMECARD_LIB.TIMECARD(SCH_1):PAGE33',
 PHYS_PAGE='34',
 XY='(-8250,1600)',
 ROT='0',
 VER='1',
 LOCATION='SP21',
 CDS_LIB='mech',
 CDS_PART_NAME='SOLDER_PREFORM-G380-10015-01',
 CLS_PN='G380-10015-01',
 PRIM_FILE='./archive_libs/mech/solder_preform/chips/chips.prt';

PART_NAME
 SP22 'SOLDER_PREFORM-G380-10015-01':;

SECTION_NUMBER 1
 '@TIMECARD_LIB.TIMECARD(SCH_1):PAGE33_I148@MECH.SOLDER_PREFORM(CHIPS)':
 C_PATH='@timecard_lib.timecard(sch_1):page33_i148@mech.solder_preform(chips)',
 P_PATH='@timecard_lib.timecard(sch_1):page34_i148@mech.solder_preform(chips)',
 PATH='I148',
 DRAWING='@TIMECARD_LIB.TIMECARD(SCH_1):PAGE33',
 PHYS_PAGE='34',
 XY='(-7400,1600)',
 ROT='0',
 VER='1',
 LOCATION='SP22',
 CDS_LIB='mech',
 CDS_PART_NAME='SOLDER_PREFORM-G380-10015-01',
 CLS_PN='G380-10015-01',
 PRIM_FILE='./archive_libs/mech/solder_preform/chips/chips.prt';

PART_NAME
 SP23 'SOLDER_PREFORM-G380-10015-01':;

SECTION_NUMBER 1
 '@TIMECARD_LIB.TIMECARD(SCH_1):PAGE33_I147@MECH.SOLDER_PREFORM(CHIPS)':
 C_PATH='@timecard_lib.timecard(sch_1):page33_i147@mech.solder_preform(chips)',
 P_PATH='@timecard_lib.timecard(sch_1):page34_i147@mech.solder_preform(chips)',
 PATH='I147',
 DRAWING='@TIMECARD_LIB.TIMECARD(SCH_1):PAGE33',
 PHYS_PAGE='34',
 XY='(-6500,1600)',
 ROT='0',
 VER='1',
 LOCATION='SP23',
 CDS_LIB='mech',
 CDS_PART_NAME='SOLDER_PREFORM-G380-10015-01',
 CLS_PN='G380-10015-01',
 PRIM_FILE='./archive_libs/mech/solder_preform/chips/chips.prt';

PART_NAME
 SP24 'SOLDER_PREFORM-G380-10015-01':;

SECTION_NUMBER 1
 '@TIMECARD_LIB.TIMECARD(SCH_1):PAGE33_I146@MECH.SOLDER_PREFORM(CHIPS)':
 C_PATH='@timecard_lib.timecard(sch_1):page33_i146@mech.solder_preform(chips)',
 P_PATH='@timecard_lib.timecard(sch_1):page34_i146@mech.solder_preform(chips)',
 PATH='I146',
 DRAWING='@TIMECARD_LIB.TIMECARD(SCH_1):PAGE33',
 PHYS_PAGE='34',
 XY='(-5550,1600)',
 ROT='0',
 VER='1',
 LOCATION='SP24',
 CDS_LIB='mech',
 CDS_PART_NAME='SOLDER_PREFORM-G380-10015-01',
 CLS_PN='G380-10015-01',
 PRIM_FILE='./archive_libs/mech/solder_preform/chips/chips.prt';

PART_NAME
 SP25 'SOLDER_PREFORM-G380-10015-01':;

SECTION_NUMBER 1
 '@TIMECARD_LIB.TIMECARD(SCH_1):PAGE33_I145@MECH.SOLDER_PREFORM(CHIPS)':
 C_PATH='@timecard_lib.timecard(sch_1):page33_i145@mech.solder_preform(chips)',
 P_PATH='@timecard_lib.timecard(sch_1):page34_i145@mech.solder_preform(chips)',
 PATH='I145',
 DRAWING='@TIMECARD_LIB.TIMECARD(SCH_1):PAGE33',
 PHYS_PAGE='34',
 XY='(-4650,1600)',
 ROT='0',
 VER='1',
 LOCATION='SP25',
 CDS_LIB='mech',
 CDS_PART_NAME='SOLDER_PREFORM-G380-10015-01',
 CLS_PN='G380-10015-01',
 PRIM_FILE='./archive_libs/mech/solder_preform/chips/chips.prt';

PART_NAME
 SP26 'SOLDER_PREFORM-G380-10015-01':;

SECTION_NUMBER 1
 '@TIMECARD_LIB.TIMECARD(SCH_1):PAGE33_I144@MECH.SOLDER_PREFORM(CHIPS)':
 C_PATH='@timecard_lib.timecard(sch_1):page33_i144@mech.solder_preform(chips)',
 P_PATH='@timecard_lib.timecard(sch_1):page34_i144@mech.solder_preform(chips)',
 PATH='I144',
 DRAWING='@TIMECARD_LIB.TIMECARD(SCH_1):PAGE33',
 PHYS_PAGE='34',
 XY='(-3800,1600)',
 ROT='0',
 VER='1',
 LOCATION='SP26',
 CDS_LIB='mech',
 CDS_PART_NAME='SOLDER_PREFORM-G380-10015-01',
 CLS_PN='G380-10015-01',
 PRIM_FILE='./archive_libs/mech/solder_preform/chips/chips.prt';

PART_NAME
 SP27 'SOLDER_PREFORM-G380-10015-01':;

SECTION_NUMBER 1
 '@TIMECARD_LIB.TIMECARD(SCH_1):PAGE33_I143@MECH.SOLDER_PREFORM(CHIPS)':
 C_PATH='@timecard_lib.timecard(sch_1):page33_i143@mech.solder_preform(chips)',
 P_PATH='@timecard_lib.timecard(sch_1):page34_i143@mech.solder_preform(chips)',
 PATH='I143',
 DRAWING='@TIMECARD_LIB.TIMECARD(SCH_1):PAGE33',
 PHYS_PAGE='34',
 XY='(-2900,1600)',
 ROT='0',
 VER='1',
 LOCATION='SP27',
 CDS_LIB='mech',
 CDS_PART_NAME='SOLDER_PREFORM-G380-10015-01',
 CLS_PN='G380-10015-01',
 PRIM_FILE='./archive_libs/mech/solder_preform/chips/chips.prt';

PART_NAME
 SP28 'SOLDER_PREFORM-G380-10015-01':;

SECTION_NUMBER 1
 '@TIMECARD_LIB.TIMECARD(SCH_1):PAGE33_I175@MECH.SOLDER_PREFORM(CHIPS)':
 C_PATH='@timecard_lib.timecard(sch_1):page33_i175@mech.solder_preform(chips)',
 P_PATH='@timecard_lib.timecard(sch_1):page34_i175@mech.solder_preform(chips)',
 PATH='I175',
 DRAWING='@TIMECARD_LIB.TIMECARD(SCH_1):PAGE33',
 PHYS_PAGE='34',
 XY='(-12750,1100)',
 ROT='0',
 VER='1',
 LOCATION='SP28',
 CDS_LIB='mech',
 CDS_PART_NAME='SOLDER_PREFORM-G380-10015-01',
 CLS_PN='G380-10015-01',
 PRIM_FILE='./archive_libs/mech/solder_preform/chips/chips.prt';

PART_NAME
 SP29 'SOLDER_PREFORM-G380-10015-01':;

SECTION_NUMBER 1
 '@TIMECARD_LIB.TIMECARD(SCH_1):PAGE33_I174@MECH.SOLDER_PREFORM(CHIPS)':
 C_PATH='@timecard_lib.timecard(sch_1):page33_i174@mech.solder_preform(chips)',
 P_PATH='@timecard_lib.timecard(sch_1):page34_i174@mech.solder_preform(chips)',
 PATH='I174',
 DRAWING='@TIMECARD_LIB.TIMECARD(SCH_1):PAGE33',
 PHYS_PAGE='34',
 XY='(-11900,1100)',
 ROT='0',
 VER='1',
 LOCATION='SP29',
 CDS_LIB='mech',
 CDS_PART_NAME='SOLDER_PREFORM-G380-10015-01',
 CLS_PN='G380-10015-01',
 PRIM_FILE='./archive_libs/mech/solder_preform/chips/chips.prt';

PART_NAME
 SP30 'SOLDER_PREFORM-G380-10015-01':;

SECTION_NUMBER 1
 '@TIMECARD_LIB.TIMECARD(SCH_1):PAGE33_I173@MECH.SOLDER_PREFORM(CHIPS)':
 C_PATH='@timecard_lib.timecard(sch_1):page33_i173@mech.solder_preform(chips)',
 P_PATH='@timecard_lib.timecard(sch_1):page34_i173@mech.solder_preform(chips)',
 PATH='I173',
 DRAWING='@TIMECARD_LIB.TIMECARD(SCH_1):PAGE33',
 PHYS_PAGE='34',
 XY='(-11000,1100)',
 ROT='0',
 VER='1',
 LOCATION='SP30',
 CDS_LIB='mech',
 CDS_PART_NAME='SOLDER_PREFORM-G380-10015-01',
 CLS_PN='G380-10015-01',
 PRIM_FILE='./archive_libs/mech/solder_preform/chips/chips.prt';

PART_NAME
 SP31 'SOLDER_PREFORM-G380-10015-01':;

SECTION_NUMBER 1
 '@TIMECARD_LIB.TIMECARD(SCH_1):PAGE33_I172@MECH.SOLDER_PREFORM(CHIPS)':
 C_PATH='@timecard_lib.timecard(sch_1):page33_i172@mech.solder_preform(chips)',
 P_PATH='@timecard_lib.timecard(sch_1):page34_i172@mech.solder_preform(chips)',
 PATH='I172',
 DRAWING='@TIMECARD_LIB.TIMECARD(SCH_1):PAGE33',
 PHYS_PAGE='34',
 XY='(-10050,1100)',
 ROT='0',
 VER='1',
 LOCATION='SP31',
 CDS_LIB='mech',
 CDS_PART_NAME='SOLDER_PREFORM-G380-10015-01',
 CLS_PN='G380-10015-01',
 PRIM_FILE='./archive_libs/mech/solder_preform/chips/chips.prt';

PART_NAME
 SP32 'SOLDER_PREFORM-G380-10015-01':;

SECTION_NUMBER 1
 '@TIMECARD_LIB.TIMECARD(SCH_1):PAGE33_I171@MECH.SOLDER_PREFORM(CHIPS)':
 C_PATH='@timecard_lib.timecard(sch_1):page33_i171@mech.solder_preform(chips)',
 P_PATH='@timecard_lib.timecard(sch_1):page34_i171@mech.solder_preform(chips)',
 PATH='I171',
 DRAWING='@TIMECARD_LIB.TIMECARD(SCH_1):PAGE33',
 PHYS_PAGE='34',
 XY='(-9150,1100)',
 ROT='0',
 VER='1',
 LOCATION='SP32',
 CDS_LIB='mech',
 CDS_PART_NAME='SOLDER_PREFORM-G380-10015-01',
 CLS_PN='G380-10015-01',
 PRIM_FILE='./archive_libs/mech/solder_preform/chips/chips.prt';

PART_NAME
 SP33 'SOLDER_PREFORM-G380-10015-01':;

SECTION_NUMBER 1
 '@TIMECARD_LIB.TIMECARD(SCH_1):PAGE33_I169@MECH.SOLDER_PREFORM(CHIPS)':
 C_PATH='@timecard_lib.timecard(sch_1):page33_i169@mech.solder_preform(chips)',
 P_PATH='@timecard_lib.timecard(sch_1):page34_i169@mech.solder_preform(chips)',
 PATH='I169',
 DRAWING='@TIMECARD_LIB.TIMECARD(SCH_1):PAGE33',
 PHYS_PAGE='34',
 XY='(-8300,1100)',
 ROT='0',
 VER='1',
 LOCATION='SP33',
 CDS_LIB='mech',
 CDS_PART_NAME='SOLDER_PREFORM-G380-10015-01',
 CLS_PN='G380-10015-01',
 PRIM_FILE='./archive_libs/mech/solder_preform/chips/chips.prt';

PART_NAME
 SP34 'SOLDER_PREFORM-G380-10015-01':;

SECTION_NUMBER 1
 '@TIMECARD_LIB.TIMECARD(SCH_1):PAGE33_I167@MECH.SOLDER_PREFORM(CHIPS)':
 C_PATH='@timecard_lib.timecard(sch_1):page33_i167@mech.solder_preform(chips)',
 P_PATH='@timecard_lib.timecard(sch_1):page34_i167@mech.solder_preform(chips)',
 PATH='I167',
 DRAWING='@TIMECARD_LIB.TIMECARD(SCH_1):PAGE33',
 PHYS_PAGE='34',
 XY='(-7400,1100)',
 ROT='0',
 VER='1',
 LOCATION='SP34',
 CDS_LIB='mech',
 CDS_PART_NAME='SOLDER_PREFORM-G380-10015-01',
 CLS_PN='G380-10015-01',
 PRIM_FILE='./archive_libs/mech/solder_preform/chips/chips.prt';

PART_NAME
 SP35 'SOLDER_PREFORM-G380-10015-01':;

SECTION_NUMBER 1
 '@TIMECARD_LIB.TIMECARD(SCH_1):PAGE33_I165@MECH.SOLDER_PREFORM(CHIPS)':
 C_PATH='@timecard_lib.timecard(sch_1):page33_i165@mech.solder_preform(chips)',
 P_PATH='@timecard_lib.timecard(sch_1):page34_i165@mech.solder_preform(chips)',
 PATH='I165',
 DRAWING='@TIMECARD_LIB.TIMECARD(SCH_1):PAGE33',
 PHYS_PAGE='34',
 XY='(-6450,1100)',
 ROT='0',
 VER='1',
 LOCATION='SP35',
 CDS_LIB='mech',
 CDS_PART_NAME='SOLDER_PREFORM-G380-10015-01',
 CLS_PN='G380-10015-01',
 PRIM_FILE='./archive_libs/mech/solder_preform/chips/chips.prt';

PART_NAME
 SP36 'SOLDER_PREFORM-G380-10015-01':;

SECTION_NUMBER 1
 '@TIMECARD_LIB.TIMECARD(SCH_1):PAGE33_I163@MECH.SOLDER_PREFORM(CHIPS)':
 C_PATH='@timecard_lib.timecard(sch_1):page33_i163@mech.solder_preform(chips)',
 P_PATH='@timecard_lib.timecard(sch_1):page34_i163@mech.solder_preform(chips)',
 PATH='I163',
 DRAWING='@TIMECARD_LIB.TIMECARD(SCH_1):PAGE33',
 PHYS_PAGE='34',
 XY='(-5550,1100)',
 ROT='0',
 VER='1',
 LOCATION='SP36',
 CDS_LIB='mech',
 CDS_PART_NAME='SOLDER_PREFORM-G380-10015-01',
 CLS_PN='G380-10015-01',
 PRIM_FILE='./archive_libs/mech/solder_preform/chips/chips.prt';

PART_NAME
 SP37 'SOLDER_PREFORM-G380-10015-01':;

SECTION_NUMBER 1
 '@TIMECARD_LIB.TIMECARD(SCH_1):PAGE33_I161@MECH.SOLDER_PREFORM(CHIPS)':
 C_PATH='@timecard_lib.timecard(sch_1):page33_i161@mech.solder_preform(chips)',
 P_PATH='@timecard_lib.timecard(sch_1):page34_i161@mech.solder_preform(chips)',
 PATH='I161',
 DRAWING='@TIMECARD_LIB.TIMECARD(SCH_1):PAGE33',
 PHYS_PAGE='34',
 XY='(-4700,1100)',
 ROT='0',
 VER='1',
 LOCATION='SP37',
 CDS_LIB='mech',
 CDS_PART_NAME='SOLDER_PREFORM-G380-10015-01',
 CLS_PN='G380-10015-01',
 PRIM_FILE='./archive_libs/mech/solder_preform/chips/chips.prt';

PART_NAME
 SP38 'SOLDER_PREFORM-G380-10015-01':;

SECTION_NUMBER 1
 '@TIMECARD_LIB.TIMECARD(SCH_1):PAGE33_I159@MECH.SOLDER_PREFORM(CHIPS)':
 C_PATH='@timecard_lib.timecard(sch_1):page33_i159@mech.solder_preform(chips)',
 P_PATH='@timecard_lib.timecard(sch_1):page34_i159@mech.solder_preform(chips)',
 PATH='I159',
 DRAWING='@TIMECARD_LIB.TIMECARD(SCH_1):PAGE33',
 PHYS_PAGE='34',
 XY='(-3800,1100)',
 ROT='0',
 VER='1',
 LOCATION='SP38',
 CDS_LIB='mech',
 CDS_PART_NAME='SOLDER_PREFORM-G380-10015-01',
 CLS_PN='G380-10015-01',
 PRIM_FILE='./archive_libs/mech/solder_preform/chips/chips.prt';

PART_NAME
 SP39 'SOLDER_PREFORM-G380-10015-01':;

SECTION_NUMBER 1
 '@TIMECARD_LIB.TIMECARD(SCH_1):PAGE33_I177@MECH.SOLDER_PREFORM(CHIPS)':
 C_PATH='@timecard_lib.timecard(sch_1):page33_i177@mech.solder_preform(chips)',
 P_PATH='@timecard_lib.timecard(sch_1):page34_i177@mech.solder_preform(chips)',
 PATH='I177',
 DRAWING='@TIMECARD_LIB.TIMECARD(SCH_1):PAGE33',
 PHYS_PAGE='34',
 XY='(-2900,1100)',
 ROT='0',
 VER='1',
 LOCATION='SP39',
 CDS_LIB='mech',
 CDS_PART_NAME='SOLDER_PREFORM-G380-10015-01',
 CLS_PN='G380-10015-01',
 PRIM_FILE='./archive_libs/mech/solder_preform/chips/chips.prt';

PART_NAME
 SP40 'SOLDER_PREFORM-G380-10015-01':;

SECTION_NUMBER 1
 '@TIMECARD_LIB.TIMECARD(SCH_1):PAGE33_I176@MECH.SOLDER_PREFORM(CHIPS)':
 C_PATH='@timecard_lib.timecard(sch_1):page33_i176@mech.solder_preform(chips)',
 P_PATH='@timecard_lib.timecard(sch_1):page34_i176@mech.solder_preform(chips)',
 PATH='I176',
 DRAWING='@TIMECARD_LIB.TIMECARD(SCH_1):PAGE33',
 PHYS_PAGE='34',
 XY='(-12750,550)',
 ROT='0',
 VER='1',
 LOCATION='SP40',
 CDS_LIB='mech',
 CDS_PART_NAME='SOLDER_PREFORM-G380-10015-01',
 CLS_PN='G380-10015-01',
 PRIM_FILE='./archive_libs/mech/solder_preform/chips/chips.prt';

PART_NAME
 SP41 'SOLDER_PREFORM-G380-10015-01':;

SECTION_NUMBER 1
 '@TIMECARD_LIB.TIMECARD(SCH_1):PAGE33_I155@MECH.SOLDER_PREFORM(CHIPS)':
 C_PATH='@timecard_lib.timecard(sch_1):page33_i155@mech.solder_preform(chips)',
 P_PATH='@timecard_lib.timecard(sch_1):page34_i155@mech.solder_preform(chips)',
 PATH='I155',
 DRAWING='@TIMECARD_LIB.TIMECARD(SCH_1):PAGE33',
 PHYS_PAGE='34',
 XY='(-11900,550)',
 ROT='0',
 VER='1',
 LOCATION='SP41',
 CDS_LIB='mech',
 CDS_PART_NAME='SOLDER_PREFORM-G380-10015-01',
 CLS_PN='G380-10015-01',
 PRIM_FILE='./archive_libs/mech/solder_preform/chips/chips.prt';

PART_NAME
 SP42 'NULL-G380-10013-01':;

SECTION_NUMBER -1
 '@TIMECARD_LIB.TIMECARD(SCH_1):PAGE33_I70@MECH.NULL(CHIPS)':
 C_PATH='@timecard_lib.timecard(sch_1):page33_i70@mech.\null\(chips)',
 P_PATH='@timecard_lib.timecard(sch_1):page34_i70@mech.\null\(chips)',
 PATH='I70',
 DRAWING='@TIMECARD_LIB.TIMECARD(SCH_1):PAGE33',
 PHYS_PAGE='34',
 XY='(-12750,4400)',
 ROT='0',
 VER='1',
 LOCATION='SP42',
 CDS_LIB='mech',
 CDS_PART_NAME='NULL-G380-10013-01',
 CLS_PN='G380-10013-01',
 PRIM_FILE='./archive_libs/mech/null/chips/chips.prt';

PART_NAME
 SP43 'NULL-G380-10013-01':;

SECTION_NUMBER -1
 '@TIMECARD_LIB.TIMECARD(SCH_1):PAGE33_I69@MECH.NULL(CHIPS)':
 C_PATH='@timecard_lib.timecard(sch_1):page33_i69@mech.\null\(chips)',
 P_PATH='@timecard_lib.timecard(sch_1):page34_i69@mech.\null\(chips)',
 PATH='I69',
 DRAWING='@TIMECARD_LIB.TIMECARD(SCH_1):PAGE33',
 PHYS_PAGE='34',
 XY='(-11800,4400)',
 ROT='0',
 VER='1',
 LOCATION='SP43',
 CDS_LIB='mech',
 CDS_PART_NAME='NULL-G380-10013-01',
 CLS_PN='G380-10013-01',
 PRIM_FILE='./archive_libs/mech/null/chips/chips.prt';

PART_NAME
 SP44 'NULL-G380-10013-01':;

SECTION_NUMBER -1
 '@TIMECARD_LIB.TIMECARD(SCH_1):PAGE33_I68@MECH.NULL(CHIPS)':
 C_PATH='@timecard_lib.timecard(sch_1):page33_i68@mech.\null\(chips)',
 P_PATH='@timecard_lib.timecard(sch_1):page34_i68@mech.\null\(chips)',
 PATH='I68',
 DRAWING='@TIMECARD_LIB.TIMECARD(SCH_1):PAGE33',
 PHYS_PAGE='34',
 XY='(-10850,4400)',
 ROT='0',
 VER='1',
 LOCATION='SP44',
 CDS_LIB='mech',
 CDS_PART_NAME='NULL-G380-10013-01',
 CLS_PN='G380-10013-01',
 PRIM_FILE='./archive_libs/mech/null/chips/chips.prt';

PART_NAME
 SP45 'NULL-G380-10013-01':;

SECTION_NUMBER -1
 '@TIMECARD_LIB.TIMECARD(SCH_1):PAGE33_I67@MECH.NULL(CHIPS)':
 C_PATH='@timecard_lib.timecard(sch_1):page33_i67@mech.\null\(chips)',
 P_PATH='@timecard_lib.timecard(sch_1):page34_i67@mech.\null\(chips)',
 PATH='I67',
 DRAWING='@TIMECARD_LIB.TIMECARD(SCH_1):PAGE33',
 PHYS_PAGE='34',
 XY='(-9900,4400)',
 ROT='0',
 VER='1',
 LOCATION='SP45',
 CDS_LIB='mech',
 CDS_PART_NAME='NULL-G380-10013-01',
 CLS_PN='G380-10013-01',
 PRIM_FILE='./archive_libs/mech/null/chips/chips.prt';

PART_NAME
 SP46 'NULL-G380-10013-01':;

SECTION_NUMBER -1
 '@TIMECARD_LIB.TIMECARD(SCH_1):PAGE33_I66@MECH.NULL(CHIPS)':
 C_PATH='@timecard_lib.timecard(sch_1):page33_i66@mech.\null\(chips)',
 P_PATH='@timecard_lib.timecard(sch_1):page34_i66@mech.\null\(chips)',
 PATH='I66',
 DRAWING='@TIMECARD_LIB.TIMECARD(SCH_1):PAGE33',
 PHYS_PAGE='34',
 XY='(-8950,4400)',
 ROT='0',
 VER='1',
 LOCATION='SP46',
 CDS_LIB='mech',
 CDS_PART_NAME='NULL-G380-10013-01',
 CLS_PN='G380-10013-01',
 PRIM_FILE='./archive_libs/mech/null/chips/chips.prt';

PART_NAME
 SP47 'NULL-G380-10013-01':;

SECTION_NUMBER -1
 '@TIMECARD_LIB.TIMECARD(SCH_1):PAGE33_I59@MECH.NULL(CHIPS)':
 C_PATH='@timecard_lib.timecard(sch_1):page33_i59@mech.\null\(chips)',
 P_PATH='@timecard_lib.timecard(sch_1):page34_i59@mech.\null\(chips)',
 PATH='I59',
 DRAWING='@TIMECARD_LIB.TIMECARD(SCH_1):PAGE33',
 PHYS_PAGE='34',
 XY='(-8000,4400)',
 ROT='0',
 VER='1',
 LOCATION='SP47',
 CDS_LIB='mech',
 CDS_PART_NAME='NULL-G380-10013-01',
 CLS_PN='G380-10013-01',
 PRIM_FILE='./archive_libs/mech/null/chips/chips.prt';

PART_NAME
 SP48 'NULL-G380-10013-01':;

SECTION_NUMBER -1
 '@TIMECARD_LIB.TIMECARD(SCH_1):PAGE33_I60@MECH.NULL(CHIPS)':
 C_PATH='@timecard_lib.timecard(sch_1):page33_i60@mech.\null\(chips)',
 P_PATH='@timecard_lib.timecard(sch_1):page34_i60@mech.\null\(chips)',
 PATH='I60',
 DRAWING='@TIMECARD_LIB.TIMECARD(SCH_1):PAGE33',
 PHYS_PAGE='34',
 XY='(-7050,4400)',
 ROT='0',
 VER='1',
 LOCATION='SP48',
 CDS_LIB='mech',
 CDS_PART_NAME='NULL-G380-10013-01',
 CLS_PN='G380-10013-01',
 PRIM_FILE='./archive_libs/mech/null/chips/chips.prt';

PART_NAME
 SP49 'NULL-G380-10013-01':;

SECTION_NUMBER -1
 '@TIMECARD_LIB.TIMECARD(SCH_1):PAGE33_I65@MECH.NULL(CHIPS)':
 C_PATH='@timecard_lib.timecard(sch_1):page33_i65@mech.\null\(chips)',
 P_PATH='@timecard_lib.timecard(sch_1):page34_i65@mech.\null\(chips)',
 PATH='I65',
 DRAWING='@TIMECARD_LIB.TIMECARD(SCH_1):PAGE33',
 PHYS_PAGE='34',
 XY='(-6100,4400)',
 ROT='0',
 VER='1',
 LOCATION='SP49',
 CDS_LIB='mech',
 CDS_PART_NAME='NULL-G380-10013-01',
 CLS_PN='G380-10013-01',
 PRIM_FILE='./archive_libs/mech/null/chips/chips.prt';

PART_NAME
 SP50 'NULL-G380-10013-01':;

SECTION_NUMBER -1
 '@TIMECARD_LIB.TIMECARD(SCH_1):PAGE33_I64@MECH.NULL(CHIPS)':
 C_PATH='@timecard_lib.timecard(sch_1):page33_i64@mech.\null\(chips)',
 P_PATH='@timecard_lib.timecard(sch_1):page34_i64@mech.\null\(chips)',
 PATH='I64',
 DRAWING='@TIMECARD_LIB.TIMECARD(SCH_1):PAGE33',
 PHYS_PAGE='34',
 XY='(-5150,4400)',
 ROT='0',
 VER='1',
 LOCATION='SP50',
 CDS_LIB='mech',
 CDS_PART_NAME='NULL-G380-10013-01',
 CLS_PN='G380-10013-01',
 PRIM_FILE='./archive_libs/mech/null/chips/chips.prt';

PART_NAME
 SP51 'NULL-G380-10013-01':;

SECTION_NUMBER -1
 '@TIMECARD_LIB.TIMECARD(SCH_1):PAGE33_I63@MECH.NULL(CHIPS)':
 C_PATH='@timecard_lib.timecard(sch_1):page33_i63@mech.\null\(chips)',
 P_PATH='@timecard_lib.timecard(sch_1):page34_i63@mech.\null\(chips)',
 PATH='I63',
 DRAWING='@TIMECARD_LIB.TIMECARD(SCH_1):PAGE33',
 PHYS_PAGE='34',
 XY='(-4200,4400)',
 ROT='0',
 VER='1',
 LOCATION='SP51',
 CDS_LIB='mech',
 CDS_PART_NAME='NULL-G380-10013-01',
 CLS_PN='G380-10013-01',
 PRIM_FILE='./archive_libs/mech/null/chips/chips.prt';

PART_NAME
 SP52 'NULL-G380-10013-01':;

SECTION_NUMBER -1
 '@TIMECARD_LIB.TIMECARD(SCH_1):PAGE33_I62@MECH.NULL(CHIPS)':
 C_PATH='@timecard_lib.timecard(sch_1):page33_i62@mech.\null\(chips)',
 P_PATH='@timecard_lib.timecard(sch_1):page34_i62@mech.\null\(chips)',
 PATH='I62',
 DRAWING='@TIMECARD_LIB.TIMECARD(SCH_1):PAGE33',
 PHYS_PAGE='34',
 XY='(-3250,4400)',
 ROT='0',
 VER='1',
 LOCATION='SP52',
 CDS_LIB='mech',
 CDS_PART_NAME='NULL-G380-10013-01',
 CLS_PN='G380-10013-01',
 PRIM_FILE='./archive_libs/mech/null/chips/chips.prt';

PART_NAME
 SP53 'NULL-G380-10013-01':;

SECTION_NUMBER -1
 '@TIMECARD_LIB.TIMECARD(SCH_1):PAGE33_I61@MECH.NULL(CHIPS)':
 C_PATH='@timecard_lib.timecard(sch_1):page33_i61@mech.\null\(chips)',
 P_PATH='@timecard_lib.timecard(sch_1):page34_i61@mech.\null\(chips)',
 PATH='I61',
 DRAWING='@TIMECARD_LIB.TIMECARD(SCH_1):PAGE33',
 PHYS_PAGE='34',
 XY='(-2300,4400)',
 ROT='0',
 VER='1',
 LOCATION='SP53',
 CDS_LIB='mech',
 CDS_PART_NAME='NULL-G380-10013-01',
 CLS_PN='G380-10013-01',
 PRIM_FILE='./archive_libs/mech/null/chips/chips.prt';

PART_NAME
 SP54 'NULL-G380-10013-01':;

SECTION_NUMBER -1
 '@TIMECARD_LIB.TIMECARD(SCH_1):PAGE33_I47@MECH.NULL(CHIPS)':
 C_PATH='@timecard_lib.timecard(sch_1):page33_i47@mech.\null\(chips)',
 P_PATH='@timecard_lib.timecard(sch_1):page34_i47@mech.\null\(chips)',
 PATH='I47',
 DRAWING='@TIMECARD_LIB.TIMECARD(SCH_1):PAGE33',
 PHYS_PAGE='34',
 XY='(-12750,3850)',
 ROT='0',
 VER='1',
 LOCATION='SP54',
 CDS_LIB='mech',
 CDS_PART_NAME='NULL-G380-10013-01',
 CLS_PN='G380-10013-01',
 PRIM_FILE='./archive_libs/mech/null/chips/chips.prt';

PART_NAME
 SP55 'NULL-G380-10013-01':;

SECTION_NUMBER -1
 '@TIMECARD_LIB.TIMECARD(SCH_1):PAGE33_I48@MECH.NULL(CHIPS)':
 C_PATH='@timecard_lib.timecard(sch_1):page33_i48@mech.\null\(chips)',
 P_PATH='@timecard_lib.timecard(sch_1):page34_i48@mech.\null\(chips)',
 PATH='I48',
 DRAWING='@TIMECARD_LIB.TIMECARD(SCH_1):PAGE33',
 PHYS_PAGE='34',
 XY='(-11800,3850)',
 ROT='0',
 VER='1',
 LOCATION='SP55',
 CDS_LIB='mech',
 CDS_PART_NAME='NULL-G380-10013-01',
 CLS_PN='G380-10013-01',
 PRIM_FILE='./archive_libs/mech/null/chips/chips.prt';

PART_NAME
 SP56 'NULL-G380-10013-01':;

SECTION_NUMBER -1
 '@TIMECARD_LIB.TIMECARD(SCH_1):PAGE33_I50@MECH.NULL(CHIPS)':
 C_PATH='@timecard_lib.timecard(sch_1):page33_i50@mech.\null\(chips)',
 P_PATH='@timecard_lib.timecard(sch_1):page34_i50@mech.\null\(chips)',
 PATH='I50',
 DRAWING='@TIMECARD_LIB.TIMECARD(SCH_1):PAGE33',
 PHYS_PAGE='34',
 XY='(-10850,3850)',
 ROT='0',
 VER='1',
 LOCATION='SP56',
 CDS_LIB='mech',
 CDS_PART_NAME='NULL-G380-10013-01',
 CLS_PN='G380-10013-01',
 PRIM_FILE='./archive_libs/mech/null/chips/chips.prt';

PART_NAME
 SP57 'NULL-G380-10013-01':;

SECTION_NUMBER -1
 '@TIMECARD_LIB.TIMECARD(SCH_1):PAGE33_I49@MECH.NULL(CHIPS)':
 C_PATH='@timecard_lib.timecard(sch_1):page33_i49@mech.\null\(chips)',
 P_PATH='@timecard_lib.timecard(sch_1):page34_i49@mech.\null\(chips)',
 PATH='I49',
 DRAWING='@TIMECARD_LIB.TIMECARD(SCH_1):PAGE33',
 PHYS_PAGE='34',
 XY='(-9900,3850)',
 ROT='0',
 VER='1',
 LOCATION='SP57',
 CDS_LIB='mech',
 CDS_PART_NAME='NULL-G380-10013-01',
 CLS_PN='G380-10013-01',
 PRIM_FILE='./archive_libs/mech/null/chips/chips.prt';

PART_NAME
 SP58 'NULL-G380-10013-01':;

SECTION_NUMBER -1
 '@TIMECARD_LIB.TIMECARD(SCH_1):PAGE33_I54@MECH.NULL(CHIPS)':
 C_PATH='@timecard_lib.timecard(sch_1):page33_i54@mech.\null\(chips)',
 P_PATH='@timecard_lib.timecard(sch_1):page34_i54@mech.\null\(chips)',
 PATH='I54',
 DRAWING='@TIMECARD_LIB.TIMECARD(SCH_1):PAGE33',
 PHYS_PAGE='34',
 XY='(-8950,3850)',
 ROT='0',
 VER='1',
 LOCATION='SP58',
 CDS_LIB='mech',
 CDS_PART_NAME='NULL-G380-10013-01',
 CLS_PN='G380-10013-01',
 PRIM_FILE='./archive_libs/mech/null/chips/chips.prt';

PART_NAME
 SP59 'NULL-G380-10013-01':;

SECTION_NUMBER -1
 '@TIMECARD_LIB.TIMECARD(SCH_1):PAGE33_I53@MECH.NULL(CHIPS)':
 C_PATH='@timecard_lib.timecard(sch_1):page33_i53@mech.\null\(chips)',
 P_PATH='@timecard_lib.timecard(sch_1):page34_i53@mech.\null\(chips)',
 PATH='I53',
 DRAWING='@TIMECARD_LIB.TIMECARD(SCH_1):PAGE33',
 PHYS_PAGE='34',
 XY='(-8000,3850)',
 ROT='0',
 VER='1',
 LOCATION='SP59',
 CDS_LIB='mech',
 CDS_PART_NAME='NULL-G380-10013-01',
 CLS_PN='G380-10013-01',
 PRIM_FILE='./archive_libs/mech/null/chips/chips.prt';

PART_NAME
 SP60 'NULL-G380-10013-01':;

SECTION_NUMBER -1
 '@TIMECARD_LIB.TIMECARD(SCH_1):PAGE33_I52@MECH.NULL(CHIPS)':
 C_PATH='@timecard_lib.timecard(sch_1):page33_i52@mech.\null\(chips)',
 P_PATH='@timecard_lib.timecard(sch_1):page34_i52@mech.\null\(chips)',
 PATH='I52',
 DRAWING='@TIMECARD_LIB.TIMECARD(SCH_1):PAGE33',
 PHYS_PAGE='34',
 XY='(-7050,3850)',
 ROT='0',
 VER='1',
 LOCATION='SP60',
 CDS_LIB='mech',
 CDS_PART_NAME='NULL-G380-10013-01',
 CLS_PN='G380-10013-01',
 PRIM_FILE='./archive_libs/mech/null/chips/chips.prt';

PART_NAME
 SP61 'NULL-G380-10013-01':;

SECTION_NUMBER -1
 '@TIMECARD_LIB.TIMECARD(SCH_1):PAGE33_I51@MECH.NULL(CHIPS)':
 C_PATH='@timecard_lib.timecard(sch_1):page33_i51@mech.\null\(chips)',
 P_PATH='@timecard_lib.timecard(sch_1):page34_i51@mech.\null\(chips)',
 PATH='I51',
 DRAWING='@TIMECARD_LIB.TIMECARD(SCH_1):PAGE33',
 PHYS_PAGE='34',
 XY='(-6100,3850)',
 ROT='0',
 VER='1',
 LOCATION='SP61',
 CDS_LIB='mech',
 CDS_PART_NAME='NULL-G380-10013-01',
 CLS_PN='G380-10013-01',
 PRIM_FILE='./archive_libs/mech/null/chips/chips.prt';

PART_NAME
 SP62 'NULL-G380-10013-01':;

SECTION_NUMBER -1
 '@TIMECARD_LIB.TIMECARD(SCH_1):PAGE33_I55@MECH.NULL(CHIPS)':
 C_PATH='@timecard_lib.timecard(sch_1):page33_i55@mech.\null\(chips)',
 P_PATH='@timecard_lib.timecard(sch_1):page34_i55@mech.\null\(chips)',
 PATH='I55',
 DRAWING='@TIMECARD_LIB.TIMECARD(SCH_1):PAGE33',
 PHYS_PAGE='34',
 XY='(-5150,3850)',
 ROT='0',
 VER='1',
 LOCATION='SP62',
 CDS_LIB='mech',
 CDS_PART_NAME='NULL-G380-10013-01',
 CLS_PN='G380-10013-01',
 PRIM_FILE='./archive_libs/mech/null/chips/chips.prt';

PART_NAME
 SP63 'NULL-G380-10013-01':;

SECTION_NUMBER -1
 '@TIMECARD_LIB.TIMECARD(SCH_1):PAGE33_I56@MECH.NULL(CHIPS)':
 C_PATH='@timecard_lib.timecard(sch_1):page33_i56@mech.\null\(chips)',
 P_PATH='@timecard_lib.timecard(sch_1):page34_i56@mech.\null\(chips)',
 PATH='I56',
 DRAWING='@TIMECARD_LIB.TIMECARD(SCH_1):PAGE33',
 PHYS_PAGE='34',
 XY='(-4200,3850)',
 ROT='0',
 VER='1',
 LOCATION='SP63',
 CDS_LIB='mech',
 CDS_PART_NAME='NULL-G380-10013-01',
 CLS_PN='G380-10013-01',
 PRIM_FILE='./archive_libs/mech/null/chips/chips.prt';

PART_NAME
 SP64 'NULL-G380-10013-01':;

SECTION_NUMBER -1
 '@TIMECARD_LIB.TIMECARD(SCH_1):PAGE33_I57@MECH.NULL(CHIPS)':
 C_PATH='@timecard_lib.timecard(sch_1):page33_i57@mech.\null\(chips)',
 P_PATH='@timecard_lib.timecard(sch_1):page34_i57@mech.\null\(chips)',
 PATH='I57',
 DRAWING='@TIMECARD_LIB.TIMECARD(SCH_1):PAGE33',
 PHYS_PAGE='34',
 XY='(-3250,3850)',
 ROT='0',
 VER='1',
 LOCATION='SP64',
 CDS_LIB='mech',
 CDS_PART_NAME='NULL-G380-10013-01',
 CLS_PN='G380-10013-01',
 PRIM_FILE='./archive_libs/mech/null/chips/chips.prt';

PART_NAME
 SP65 'NULL-G380-10013-01':;

SECTION_NUMBER -1
 '@TIMECARD_LIB.TIMECARD(SCH_1):PAGE33_I58@MECH.NULL(CHIPS)':
 C_PATH='@timecard_lib.timecard(sch_1):page33_i58@mech.\null\(chips)',
 P_PATH='@timecard_lib.timecard(sch_1):page34_i58@mech.\null\(chips)',
 PATH='I58',
 DRAWING='@TIMECARD_LIB.TIMECARD(SCH_1):PAGE33',
 PHYS_PAGE='34',
 XY='(-2300,3850)',
 ROT='0',
 VER='1',
 LOCATION='SP65',
 CDS_LIB='mech',
 CDS_PART_NAME='NULL-G380-10013-01',
 CLS_PN='G380-10013-01',
 PRIM_FILE='./archive_libs/mech/null/chips/chips.prt';

PART_NAME
 SP66 'NULL-G380-10013-01':;

SECTION_NUMBER -1
 '@TIMECARD_LIB.TIMECARD(SCH_1):PAGE33_I93@MECH.NULL(CHIPS)':
 C_PATH='@timecard_lib.timecard(sch_1):page33_i93@mech.\null\(chips)',
 P_PATH='@timecard_lib.timecard(sch_1):page34_i93@mech.\null\(chips)',
 PATH='I93',
 DRAWING='@TIMECARD_LIB.TIMECARD(SCH_1):PAGE33',
 PHYS_PAGE='34',
 XY='(-12750,3300)',
 ROT='0',
 VER='1',
 LOCATION='SP66',
 CDS_LIB='mech',
 CDS_PART_NAME='NULL-G380-10013-01',
 CLS_PN='G380-10013-01',
 PRIM_FILE='./archive_libs/mech/null/chips/chips.prt';

PART_NAME
 SP67 'NULL-G380-10013-01':;

SECTION_NUMBER -1
 '@TIMECARD_LIB.TIMECARD(SCH_1):PAGE33_I90@MECH.NULL(CHIPS)':
 C_PATH='@timecard_lib.timecard(sch_1):page33_i90@mech.\null\(chips)',
 P_PATH='@timecard_lib.timecard(sch_1):page34_i90@mech.\null\(chips)',
 PATH='I90',
 DRAWING='@TIMECARD_LIB.TIMECARD(SCH_1):PAGE33',
 PHYS_PAGE='34',
 XY='(-11800,3300)',
 ROT='0',
 VER='1',
 LOCATION='SP67',
 CDS_LIB='mech',
 CDS_PART_NAME='NULL-G380-10013-01',
 CLS_PN='G380-10013-01',
 PRIM_FILE='./archive_libs/mech/null/chips/chips.prt';

PART_NAME
 SP68 'NULL-G380-10013-01':;

SECTION_NUMBER -1
 '@TIMECARD_LIB.TIMECARD(SCH_1):PAGE33_I89@MECH.NULL(CHIPS)':
 C_PATH='@timecard_lib.timecard(sch_1):page33_i89@mech.\null\(chips)',
 P_PATH='@timecard_lib.timecard(sch_1):page34_i89@mech.\null\(chips)',
 PATH='I89',
 DRAWING='@TIMECARD_LIB.TIMECARD(SCH_1):PAGE33',
 PHYS_PAGE='34',
 XY='(-10850,3300)',
 ROT='0',
 VER='1',
 LOCATION='SP68',
 CDS_LIB='mech',
 CDS_PART_NAME='NULL-G380-10013-01',
 CLS_PN='G380-10013-01',
 PRIM_FILE='./archive_libs/mech/null/chips/chips.prt';

PART_NAME
 SP69 'NULL-G380-10013-01':;

SECTION_NUMBER -1
 '@TIMECARD_LIB.TIMECARD(SCH_1):PAGE33_I85@MECH.NULL(CHIPS)':
 C_PATH='@timecard_lib.timecard(sch_1):page33_i85@mech.\null\(chips)',
 P_PATH='@timecard_lib.timecard(sch_1):page34_i85@mech.\null\(chips)',
 PATH='I85',
 DRAWING='@TIMECARD_LIB.TIMECARD(SCH_1):PAGE33',
 PHYS_PAGE='34',
 XY='(-9900,3300)',
 ROT='0',
 VER='1',
 LOCATION='SP69',
 CDS_LIB='mech',
 CDS_PART_NAME='NULL-G380-10013-01',
 CLS_PN='G380-10013-01',
 PRIM_FILE='./archive_libs/mech/null/chips/chips.prt';

PART_NAME
 SP70 'NULL-G380-10013-01':;

SECTION_NUMBER -1
 '@TIMECARD_LIB.TIMECARD(SCH_1):PAGE33_I84@MECH.NULL(CHIPS)':
 C_PATH='@timecard_lib.timecard(sch_1):page33_i84@mech.\null\(chips)',
 P_PATH='@timecard_lib.timecard(sch_1):page34_i84@mech.\null\(chips)',
 PATH='I84',
 DRAWING='@TIMECARD_LIB.TIMECARD(SCH_1):PAGE33',
 PHYS_PAGE='34',
 XY='(-8950,3300)',
 ROT='0',
 VER='1',
 LOCATION='SP70',
 CDS_LIB='mech',
 CDS_PART_NAME='NULL-G380-10013-01',
 CLS_PN='G380-10013-01',
 PRIM_FILE='./archive_libs/mech/null/chips/chips.prt';

PART_NAME
 SP71 'NULL-G380-10013-01':;

SECTION_NUMBER -1
 '@TIMECARD_LIB.TIMECARD(SCH_1):PAGE33_I83@MECH.NULL(CHIPS)':
 C_PATH='@timecard_lib.timecard(sch_1):page33_i83@mech.\null\(chips)',
 P_PATH='@timecard_lib.timecard(sch_1):page34_i83@mech.\null\(chips)',
 PATH='I83',
 DRAWING='@TIMECARD_LIB.TIMECARD(SCH_1):PAGE33',
 PHYS_PAGE='34',
 XY='(-8000,3300)',
 ROT='0',
 VER='1',
 LOCATION='SP71',
 CDS_LIB='mech',
 CDS_PART_NAME='NULL-G380-10013-01',
 CLS_PN='G380-10013-01',
 PRIM_FILE='./archive_libs/mech/null/chips/chips.prt';

PART_NAME
 TP1 'TP_PIONT-TP010CT020B030_PTH-TPA':;

SECTION_NUMBER 1
 '@TIMECARD_LIB.TIMECARD(SCH_1):PAGE9_I71@CLS.TP_PIONT(CHIPS)':
 C_PATH='@timecard_lib.timecard(sch_1):page9_i71@cls.tp_piont(chips)',
 P_PATH='@timecard_lib.timecard(sch_1):page20_i71@cls.tp_piont(chips)',
 PATH='I71',
 DRAWING='@TIMECARD_LIB.TIMECARD(SCH_1):PAGE9',
 PHYS_PAGE='20',
 XY='(-1550,8350)',
 ROT='0',
 VER='1',
 JEDEC_TYPE='TP010CT020B030_PTH',
 CDS_LIB='cls',
 CDS_PART_NAME='TP_PIONT-TP010CT020B030_PTH-TPA',
 BOM_IGNORE='TRUE',
 PRIM_FILE='./archive_libs/cls/tp_piont/chips/chips.prt';

PART_NAME
 TP2 'TP_PIONT-TP010CT020B030_PTH-TPA':;

SECTION_NUMBER 1
 '@TIMECARD_LIB.TIMECARD(SCH_1):PAGE9_I72@CLS.TP_PIONT(CHIPS)':
 C_PATH='@timecard_lib.timecard(sch_1):page9_i72@cls.tp_piont(chips)',
 P_PATH='@timecard_lib.timecard(sch_1):page20_i72@cls.tp_piont(chips)',
 PATH='I72',
 DRAWING='@TIMECARD_LIB.TIMECARD(SCH_1):PAGE9',
 PHYS_PAGE='20',
 XY='(-1550,8250)',
 ROT='0',
 VER='1',
 JEDEC_TYPE='TP010CT020B030_PTH',
 CDS_LIB='cls',
 CDS_PART_NAME='TP_PIONT-TP010CT020B030_PTH-TPA',
 BOM_IGNORE='TRUE',
 PRIM_FILE='./archive_libs/cls/tp_piont/chips/chips.prt';

PART_NAME
 TP3 'TP_PIONT-TP010CT020B030_PTH-TPA':;

SECTION_NUMBER 1
 '@TIMECARD_LIB.TIMECARD(SCH_1):PAGE16_I1610@CLS.TP_PIONT(CHIPS)':
 C_PATH='@timecard_lib.timecard(sch_1):page16_i1610@cls.tp_piont(chips)',
 P_PATH='@timecard_lib.timecard(sch_1):page25_i1610@cls.tp_piont(chips)',
 PATH='I1610',
 DRAWING='@TIMECARD_LIB.TIMECARD(SCH_1):PAGE16',
 PHYS_PAGE='25',
 XY='(-3300,7800)',
 ROT='0',
 VER='1',
 JEDEC_TYPE='TP010CT020B030_PTH',
 CDS_LIB='cls',
 CDS_PART_NAME='TP_PIONT-TP010CT020B030_PTH-TPA',
 BOM_IGNORE='TRUE',
 PRIM_FILE='./archive_libs/cls/tp_piont/chips/chips.prt';

PART_NAME
 TP4 'TP_PIONT-TP010CT020B030_PTH-TPA':;

SECTION_NUMBER 1
 '@TIMECARD_LIB.TIMECARD(SCH_1):PAGE16_I1612@CLS.TP_PIONT(CHIPS)':
 C_PATH='@timecard_lib.timecard(sch_1):page16_i1612@cls.tp_piont(chips)',
 P_PATH='@timecard_lib.timecard(sch_1):page25_i1612@cls.tp_piont(chips)',
 PATH='I1612',
 DRAWING='@TIMECARD_LIB.TIMECARD(SCH_1):PAGE16',
 PHYS_PAGE='25',
 XY='(-3300,7350)',
 ROT='0',
 VER='1',
 JEDEC_TYPE='TP010CT020B030_PTH',
 CDS_LIB='cls',
 CDS_PART_NAME='TP_PIONT-TP010CT020B030_PTH-TPA',
 BOM_IGNORE='TRUE',
 PRIM_FILE='./archive_libs/cls/tp_piont/chips/chips.prt';

PART_NAME
 TP5 'TP_PIONT-TP010CT020B030_PTH-TPA':;

SECTION_NUMBER 1
 '@TIMECARD_LIB.TIMECARD(SCH_1):PAGE524_I311@CLS.TP_PIONT(CHIPS)':
 C_PATH='@timecard_lib.timecard(sch_1):page524_i311@cls.tp_piont(chips)',
 P_PATH='@timecard_lib.timecard(sch_1):page24_i311@cls.tp_piont(chips)',
 PATH='I311',
 DRAWING='@TIMECARD_LIB.TIMECARD(SCH_1):PAGE524',
 PHYS_PAGE='24',
 XY='(-6250,10750)',
 ROT='0',
 VER='1',
 JEDEC_TYPE='TP010CT020B030_PTH',
 CDS_LIB='cls',
 CDS_PART_NAME='TP_PIONT-TP010CT020B030_PTH-TPA',
 BOM_IGNORE='TRUE',
 PRIM_FILE='./archive_libs/cls/tp_piont/chips/chips.prt';

PART_NAME
 TP6 'TP_PIONT-TP010CT020B030_PTH-TPA':;

SECTION_NUMBER 1
 '@TIMECARD_LIB.TIMECARD(SCH_1):PAGE524_I312@CLS.TP_PIONT(CHIPS)':
 C_PATH='@timecard_lib.timecard(sch_1):page524_i312@cls.tp_piont(chips)',
 P_PATH='@timecard_lib.timecard(sch_1):page24_i312@cls.tp_piont(chips)',
 PATH='I312',
 DRAWING='@TIMECARD_LIB.TIMECARD(SCH_1):PAGE524',
 PHYS_PAGE='24',
 XY='(-6250,10250)',
 ROT='0',
 VER='1',
 JEDEC_TYPE='TP010CT020B030_PTH',
 CDS_LIB='cls',
 CDS_PART_NAME='TP_PIONT-TP010CT020B030_PTH-TPA',
 BOM_IGNORE='TRUE',
 PRIM_FILE='./archive_libs/cls/tp_piont/chips/chips.prt';

PART_NAME
 TP7 'TP_PIONT-TP010CT020B030_PTH-TPA':;

SECTION_NUMBER 1
 '@TIMECARD_LIB.TIMECARD(SCH_1):PAGE524_I313@CLS.TP_PIONT(CHIPS)':
 C_PATH='@timecard_lib.timecard(sch_1):page524_i313@cls.tp_piont(chips)',
 P_PATH='@timecard_lib.timecard(sch_1):page24_i313@cls.tp_piont(chips)',
 PATH='I313',
 DRAWING='@TIMECARD_LIB.TIMECARD(SCH_1):PAGE524',
 PHYS_PAGE='24',
 XY='(-6250,10150)',
 ROT='0',
 VER='1',
 JEDEC_TYPE='TP010CT020B030_PTH',
 CDS_LIB='cls',
 CDS_PART_NAME='TP_PIONT-TP010CT020B030_PTH-TPA',
 BOM_IGNORE='TRUE',
 PRIM_FILE='./archive_libs/cls/tp_piont/chips/chips.prt';

PART_NAME
 TP8 'TP_PIONT-TP010CT020B030_PTH-TPA':;

SECTION_NUMBER 1
 '@TIMECARD_LIB.TIMECARD(SCH_1):PAGE524_I315@CLS.TP_PIONT(CHIPS)':
 C_PATH='@timecard_lib.timecard(sch_1):page524_i315@cls.tp_piont(chips)',
 P_PATH='@timecard_lib.timecard(sch_1):page24_i315@cls.tp_piont(chips)',
 PATH='I315',
 DRAWING='@TIMECARD_LIB.TIMECARD(SCH_1):PAGE524',
 PHYS_PAGE='24',
 XY='(-6250,10050)',
 ROT='0',
 VER='1',
 JEDEC_TYPE='TP010CT020B030_PTH',
 CDS_LIB='cls',
 CDS_PART_NAME='TP_PIONT-TP010CT020B030_PTH-TPA',
 BOM_IGNORE='TRUE',
 PRIM_FILE='./archive_libs/cls/tp_piont/chips/chips.prt';

PART_NAME
 TP9 'TP_PIONT-TP010CT020B030_PTH-TPA':;

SECTION_NUMBER 1
 '@TIMECARD_LIB.TIMECARD(SCH_1):PAGE524_I314@CLS.TP_PIONT(CHIPS)':
 C_PATH='@timecard_lib.timecard(sch_1):page524_i314@cls.tp_piont(chips)',
 P_PATH='@timecard_lib.timecard(sch_1):page24_i314@cls.tp_piont(chips)',
 PATH='I314',
 DRAWING='@TIMECARD_LIB.TIMECARD(SCH_1):PAGE524',
 PHYS_PAGE='24',
 XY='(-6250,9950)',
 ROT='0',
 VER='1',
 JEDEC_TYPE='TP010CT020B030_PTH',
 CDS_LIB='cls',
 CDS_PART_NAME='TP_PIONT-TP010CT020B030_PTH-TPA',
 BOM_IGNORE='TRUE',
 PRIM_FILE='./archive_libs/cls/tp_piont/chips/chips.prt';

PART_NAME
 TP10 'TP_PIONT-TP010CT020B030_PTH-TPA':;

SECTION_NUMBER 1
 '@TIMECARD_LIB.TIMECARD(SCH_1):PAGE524_I316@CLS.TP_PIONT(CHIPS)':
 C_PATH='@timecard_lib.timecard(sch_1):page524_i316@cls.tp_piont(chips)',
 P_PATH='@timecard_lib.timecard(sch_1):page24_i316@cls.tp_piont(chips)',
 PATH='I316',
 DRAWING='@TIMECARD_LIB.TIMECARD(SCH_1):PAGE524',
 PHYS_PAGE='24',
 XY='(-6250,9850)',
 ROT='0',
 VER='1',
 JEDEC_TYPE='TP010CT020B030_PTH',
 CDS_LIB='cls',
 CDS_PART_NAME='TP_PIONT-TP010CT020B030_PTH-TPA',
 BOM_IGNORE='TRUE',
 PRIM_FILE='./archive_libs/cls/tp_piont/chips/chips.prt';

PART_NAME
 TP11 'TP_PIONT-TP010CT020B030_PTH-TPA':;

SECTION_NUMBER 1
 '@TIMECARD_LIB.TIMECARD(SCH_1):PAGE16_I1626@CLS.TP_PIONT(CHIPS)':
 C_PATH='@timecard_lib.timecard(sch_1):page16_i1626@cls.tp_piont(chips)',
 P_PATH='@timecard_lib.timecard(sch_1):page25_i1626@cls.tp_piont(chips)',
 PATH='I1626',
 DRAWING='@TIMECARD_LIB.TIMECARD(SCH_1):PAGE16',
 PHYS_PAGE='25',
 XY='(-10950,9500)',
 ROT='2',
 VER='1',
 JEDEC_TYPE='TP010CT020B030_PTH',
 CDS_LIB='cls',
 CDS_PART_NAME='TP_PIONT-TP010CT020B030_PTH-TPA',
 BOM_IGNORE='TRUE',
 PRIM_FILE='./archive_libs/cls/tp_piont/chips/chips.prt';

PART_NAME
 TP12 'TP_PIONT-TP010CT020B030_PTH-TPA':;

SECTION_NUMBER 1
 '@TIMECARD_LIB.TIMECARD(SCH_1):PAGE16_I1627@CLS.TP_PIONT(CHIPS)':
 C_PATH='@timecard_lib.timecard(sch_1):page16_i1627@cls.tp_piont(chips)',
 P_PATH='@timecard_lib.timecard(sch_1):page25_i1627@cls.tp_piont(chips)',
 PATH='I1627',
 DRAWING='@TIMECARD_LIB.TIMECARD(SCH_1):PAGE16',
 PHYS_PAGE='25',
 XY='(-10950,9400)',
 ROT='2',
 VER='1',
 JEDEC_TYPE='TP010CT020B030_PTH',
 CDS_LIB='cls',
 CDS_PART_NAME='TP_PIONT-TP010CT020B030_PTH-TPA',
 BOM_IGNORE='TRUE',
 PRIM_FILE='./archive_libs/cls/tp_piont/chips/chips.prt';

PART_NAME
 TP13 'TP_PIONT-TP010CT020B030_PTH-TPA':;

SECTION_NUMBER 1
 '@TIMECARD_LIB.TIMECARD(SCH_1):PAGE16_I1628@CLS.TP_PIONT(CHIPS)':
 C_PATH='@timecard_lib.timecard(sch_1):page16_i1628@cls.tp_piont(chips)',
 P_PATH='@timecard_lib.timecard(sch_1):page25_i1628@cls.tp_piont(chips)',
 PATH='I1628',
 DRAWING='@TIMECARD_LIB.TIMECARD(SCH_1):PAGE16',
 PHYS_PAGE='25',
 XY='(-10950,9300)',
 ROT='2',
 VER='1',
 JEDEC_TYPE='TP010CT020B030_PTH',
 CDS_LIB='cls',
 CDS_PART_NAME='TP_PIONT-TP010CT020B030_PTH-TPA',
 BOM_IGNORE='TRUE',
 PRIM_FILE='./archive_libs/cls/tp_piont/chips/chips.prt';

PART_NAME
 TP14 'TP_PIONT-TP010CT020B030_PTH-TPA':;

SECTION_NUMBER 1
 '@TIMECARD_LIB.TIMECARD(SCH_1):PAGE16_I1629@CLS.TP_PIONT(CHIPS)':
 C_PATH='@timecard_lib.timecard(sch_1):page16_i1629@cls.tp_piont(chips)',
 P_PATH='@timecard_lib.timecard(sch_1):page25_i1629@cls.tp_piont(chips)',
 PATH='I1629',
 DRAWING='@TIMECARD_LIB.TIMECARD(SCH_1):PAGE16',
 PHYS_PAGE='25',
 XY='(-10950,9200)',
 ROT='2',
 VER='1',
 JEDEC_TYPE='TP010CT020B030_PTH',
 CDS_LIB='cls',
 CDS_PART_NAME='TP_PIONT-TP010CT020B030_PTH-TPA',
 BOM_IGNORE='TRUE',
 PRIM_FILE='./archive_libs/cls/tp_piont/chips/chips.prt';

PART_NAME
 TP15 'TP_PIONT-TP010CT020B030_PTH-TPA':;

SECTION_NUMBER 1
 '@TIMECARD_LIB.TIMECARD(SCH_1):PAGE16_I1630@CLS.TP_PIONT(CHIPS)':
 C_PATH='@timecard_lib.timecard(sch_1):page16_i1630@cls.tp_piont(chips)',
 P_PATH='@timecard_lib.timecard(sch_1):page25_i1630@cls.tp_piont(chips)',
 PATH='I1630',
 DRAWING='@TIMECARD_LIB.TIMECARD(SCH_1):PAGE16',
 PHYS_PAGE='25',
 XY='(-10950,9050)',
 ROT='2',
 VER='1',
 JEDEC_TYPE='TP010CT020B030_PTH',
 CDS_LIB='cls',
 CDS_PART_NAME='TP_PIONT-TP010CT020B030_PTH-TPA',
 BOM_IGNORE='TRUE',
 PRIM_FILE='./archive_libs/cls/tp_piont/chips/chips.prt';

PART_NAME
 TP16 'TP_PIONT-TP010CT020B030_PTH-TPA':;

SECTION_NUMBER 1
 '@TIMECARD_LIB.TIMECARD(SCH_1):PAGE16_I1631@CLS.TP_PIONT(CHIPS)':
 C_PATH='@timecard_lib.timecard(sch_1):page16_i1631@cls.tp_piont(chips)',
 P_PATH='@timecard_lib.timecard(sch_1):page25_i1631@cls.tp_piont(chips)',
 PATH='I1631',
 DRAWING='@TIMECARD_LIB.TIMECARD(SCH_1):PAGE16',
 PHYS_PAGE='25',
 XY='(-10950,8950)',
 ROT='2',
 VER='1',
 JEDEC_TYPE='TP010CT020B030_PTH',
 CDS_LIB='cls',
 CDS_PART_NAME='TP_PIONT-TP010CT020B030_PTH-TPA',
 BOM_IGNORE='TRUE',
 PRIM_FILE='./archive_libs/cls/tp_piont/chips/chips.prt';

PART_NAME
 TP17 'TP_PIONT-TP010CT020B030_PTH-TPA':;

SECTION_NUMBER 1
 '@TIMECARD_LIB.TIMECARD(SCH_1):PAGE16_I1632@CLS.TP_PIONT(CHIPS)':
 C_PATH='@timecard_lib.timecard(sch_1):page16_i1632@cls.tp_piont(chips)',
 P_PATH='@timecard_lib.timecard(sch_1):page25_i1632@cls.tp_piont(chips)',
 PATH='I1632',
 DRAWING='@TIMECARD_LIB.TIMECARD(SCH_1):PAGE16',
 PHYS_PAGE='25',
 XY='(-10950,8850)',
 ROT='2',
 VER='1',
 JEDEC_TYPE='TP010CT020B030_PTH',
 CDS_LIB='cls',
 CDS_PART_NAME='TP_PIONT-TP010CT020B030_PTH-TPA',
 BOM_IGNORE='TRUE',
 PRIM_FILE='./archive_libs/cls/tp_piont/chips/chips.prt';

PART_NAME
 TP18 'TP_PIONT-TP010CT020B030_PTH-TPA':;

SECTION_NUMBER 1
 '@TIMECARD_LIB.TIMECARD(SCH_1):PAGE16_I1633@CLS.TP_PIONT(CHIPS)':
 C_PATH='@timecard_lib.timecard(sch_1):page16_i1633@cls.tp_piont(chips)',
 P_PATH='@timecard_lib.timecard(sch_1):page25_i1633@cls.tp_piont(chips)',
 PATH='I1633',
 DRAWING='@TIMECARD_LIB.TIMECARD(SCH_1):PAGE16',
 PHYS_PAGE='25',
 XY='(-10950,8750)',
 ROT='2',
 VER='1',
 JEDEC_TYPE='TP010CT020B030_PTH',
 CDS_LIB='cls',
 CDS_PART_NAME='TP_PIONT-TP010CT020B030_PTH-TPA',
 BOM_IGNORE='TRUE',
 PRIM_FILE='./archive_libs/cls/tp_piont/chips/chips.prt';

PART_NAME
 TP19 'TP_PIONT-TP010CT020B030_PTH-TPA':;

SECTION_NUMBER 1
 '@TIMECARD_LIB.TIMECARD(SCH_1):PAGE16_I1634@CLS.TP_PIONT(CHIPS)':
 C_PATH='@timecard_lib.timecard(sch_1):page16_i1634@cls.tp_piont(chips)',
 P_PATH='@timecard_lib.timecard(sch_1):page25_i1634@cls.tp_piont(chips)',
 PATH='I1634',
 DRAWING='@TIMECARD_LIB.TIMECARD(SCH_1):PAGE16',
 PHYS_PAGE='25',
 XY='(-10950,8650)',
 ROT='2',
 VER='1',
 JEDEC_TYPE='TP010CT020B030_PTH',
 CDS_LIB='cls',
 CDS_PART_NAME='TP_PIONT-TP010CT020B030_PTH-TPA',
 BOM_IGNORE='TRUE',
 PRIM_FILE='./archive_libs/cls/tp_piont/chips/chips.prt';

PART_NAME
 TP20 'TP_PIONT-TP010CT020B030_PTH-TPA':;

SECTION_NUMBER 1
 '@TIMECARD_LIB.TIMECARD(SCH_1):PAGE16_I1615@CLS.TP_PIONT(CHIPS)':
 C_PATH='@timecard_lib.timecard(sch_1):page16_i1615@cls.tp_piont(chips)',
 P_PATH='@timecard_lib.timecard(sch_1):page25_i1615@cls.tp_piont(chips)',
 PATH='I1615',
 DRAWING='@TIMECARD_LIB.TIMECARD(SCH_1):PAGE16',
 PHYS_PAGE='25',
 XY='(-10950,8550)',
 ROT='2',
 VER='1',
 JEDEC_TYPE='TP010CT020B030_PTH',
 CDS_LIB='cls',
 CDS_PART_NAME='TP_PIONT-TP010CT020B030_PTH-TPA',
 BOM_IGNORE='TRUE',
 PRIM_FILE='./archive_libs/cls/tp_piont/chips/chips.prt';

PART_NAME
 TP21 'TP_PIONT-TP010CT020B030_PTH-TPA':;

SECTION_NUMBER 1
 '@TIMECARD_LIB.TIMECARD(SCH_1):PAGE16_I1645@CLS.TP_PIONT(CHIPS)':
 C_PATH='@timecard_lib.timecard(sch_1):page16_i1645@cls.tp_piont(chips)',
 P_PATH='@timecard_lib.timecard(sch_1):page25_i1645@cls.tp_piont(chips)',
 PATH='I1645',
 DRAWING='@TIMECARD_LIB.TIMECARD(SCH_1):PAGE16',
 PHYS_PAGE='25',
 XY='(-10950,8350)',
 ROT='2',
 VER='1',
 JEDEC_TYPE='TP010CT020B030_PTH',
 CDS_LIB='cls',
 CDS_PART_NAME='TP_PIONT-TP010CT020B030_PTH-TPA',
 BOM_IGNORE='TRUE',
 PRIM_FILE='./archive_libs/cls/tp_piont/chips/chips.prt';

PART_NAME
 TP22 'TP_PIONT-TP010CT020B030_PTH-TPA':;

SECTION_NUMBER 1
 '@TIMECARD_LIB.TIMECARD(SCH_1):PAGE16_I1646@CLS.TP_PIONT(CHIPS)':
 C_PATH='@timecard_lib.timecard(sch_1):page16_i1646@cls.tp_piont(chips)',
 P_PATH='@timecard_lib.timecard(sch_1):page25_i1646@cls.tp_piont(chips)',
 PATH='I1646',
 DRAWING='@TIMECARD_LIB.TIMECARD(SCH_1):PAGE16',
 PHYS_PAGE='25',
 XY='(-10950,8250)',
 ROT='2',
 VER='1',
 JEDEC_TYPE='TP010CT020B030_PTH',
 CDS_LIB='cls',
 CDS_PART_NAME='TP_PIONT-TP010CT020B030_PTH-TPA',
 BOM_IGNORE='TRUE',
 PRIM_FILE='./archive_libs/cls/tp_piont/chips/chips.prt';

PART_NAME
 TP23 'TP_PIONT-TP010CT020B030_PTH-TPA':;

SECTION_NUMBER 1
 '@TIMECARD_LIB.TIMECARD(SCH_1):PAGE16_I1647@CLS.TP_PIONT(CHIPS)':
 C_PATH='@timecard_lib.timecard(sch_1):page16_i1647@cls.tp_piont(chips)',
 P_PATH='@timecard_lib.timecard(sch_1):page25_i1647@cls.tp_piont(chips)',
 PATH='I1647',
 DRAWING='@TIMECARD_LIB.TIMECARD(SCH_1):PAGE16',
 PHYS_PAGE='25',
 XY='(-10950,8150)',
 ROT='2',
 VER='1',
 JEDEC_TYPE='TP010CT020B030_PTH',
 CDS_LIB='cls',
 CDS_PART_NAME='TP_PIONT-TP010CT020B030_PTH-TPA',
 BOM_IGNORE='TRUE',
 PRIM_FILE='./archive_libs/cls/tp_piont/chips/chips.prt';

PART_NAME
 TP24 'TP_PIONT-TP010CT020B030_PTH-TPA':;

SECTION_NUMBER 1
 '@TIMECARD_LIB.TIMECARD(SCH_1):PAGE16_I1648@CLS.TP_PIONT(CHIPS)':
 C_PATH='@timecard_lib.timecard(sch_1):page16_i1648@cls.tp_piont(chips)',
 P_PATH='@timecard_lib.timecard(sch_1):page25_i1648@cls.tp_piont(chips)',
 PATH='I1648',
 DRAWING='@TIMECARD_LIB.TIMECARD(SCH_1):PAGE16',
 PHYS_PAGE='25',
 XY='(-10950,8050)',
 ROT='2',
 VER='1',
 JEDEC_TYPE='TP010CT020B030_PTH',
 CDS_LIB='cls',
 CDS_PART_NAME='TP_PIONT-TP010CT020B030_PTH-TPA',
 BOM_IGNORE='TRUE',
 PRIM_FILE='./archive_libs/cls/tp_piont/chips/chips.prt';

PART_NAME
 TP25 'TP_PIONT-TP010CT020B030_PTH-TPA':;

SECTION_NUMBER 1
 '@TIMECARD_LIB.TIMECARD(SCH_1):PAGE16_I1649@CLS.TP_PIONT(CHIPS)':
 C_PATH='@timecard_lib.timecard(sch_1):page16_i1649@cls.tp_piont(chips)',
 P_PATH='@timecard_lib.timecard(sch_1):page25_i1649@cls.tp_piont(chips)',
 PATH='I1649',
 DRAWING='@TIMECARD_LIB.TIMECARD(SCH_1):PAGE16',
 PHYS_PAGE='25',
 XY='(-10950,7900)',
 ROT='2',
 VER='1',
 JEDEC_TYPE='TP010CT020B030_PTH',
 CDS_LIB='cls',
 CDS_PART_NAME='TP_PIONT-TP010CT020B030_PTH-TPA',
 BOM_IGNORE='TRUE',
 PRIM_FILE='./archive_libs/cls/tp_piont/chips/chips.prt';

PART_NAME
 TP26 'TP_PIONT-TP010CT020B030_PTH-TPA':;

SECTION_NUMBER 1
 '@TIMECARD_LIB.TIMECARD(SCH_1):PAGE16_I1660@CLS.TP_PIONT(CHIPS)':
 C_PATH='@timecard_lib.timecard(sch_1):page16_i1660@cls.tp_piont(chips)',
 P_PATH='@timecard_lib.timecard(sch_1):page25_i1660@cls.tp_piont(chips)',
 PATH='I1660',
 DRAWING='@TIMECARD_LIB.TIMECARD(SCH_1):PAGE16',
 PHYS_PAGE='25',
 XY='(-10950,7700)',
 ROT='2',
 VER='1',
 JEDEC_TYPE='TP010CT020B030_PTH',
 CDS_LIB='cls',
 CDS_PART_NAME='TP_PIONT-TP010CT020B030_PTH-TPA',
 BOM_IGNORE='TRUE',
 PRIM_FILE='./archive_libs/cls/tp_piont/chips/chips.prt';

PART_NAME
 TP27 'TP_PIONT-TP010CT020B030_PTH-TPA':;

SECTION_NUMBER 1
 '@TIMECARD_LIB.TIMECARD(SCH_1):PAGE16_I1661@CLS.TP_PIONT(CHIPS)':
 C_PATH='@timecard_lib.timecard(sch_1):page16_i1661@cls.tp_piont(chips)',
 P_PATH='@timecard_lib.timecard(sch_1):page25_i1661@cls.tp_piont(chips)',
 PATH='I1661',
 DRAWING='@TIMECARD_LIB.TIMECARD(SCH_1):PAGE16',
 PHYS_PAGE='25',
 XY='(-10950,7600)',
 ROT='2',
 VER='1',
 JEDEC_TYPE='TP010CT020B030_PTH',
 CDS_LIB='cls',
 CDS_PART_NAME='TP_PIONT-TP010CT020B030_PTH-TPA',
 BOM_IGNORE='TRUE',
 PRIM_FILE='./archive_libs/cls/tp_piont/chips/chips.prt';

PART_NAME
 TP28 'TP_PIONT-TP010CT020B030_PTH-TPA':;

SECTION_NUMBER 1
 '@TIMECARD_LIB.TIMECARD(SCH_1):PAGE16_I1667@CLS.TP_PIONT(CHIPS)':
 C_PATH='@timecard_lib.timecard(sch_1):page16_i1667@cls.tp_piont(chips)',
 P_PATH='@timecard_lib.timecard(sch_1):page25_i1667@cls.tp_piont(chips)',
 PATH='I1667',
 DRAWING='@TIMECARD_LIB.TIMECARD(SCH_1):PAGE16',
 PHYS_PAGE='25',
 XY='(-10950,7450)',
 ROT='2',
 VER='1',
 JEDEC_TYPE='TP010CT020B030_PTH',
 CDS_LIB='cls',
 CDS_PART_NAME='TP_PIONT-TP010CT020B030_PTH-TPA',
 BOM_IGNORE='TRUE',
 PRIM_FILE='./archive_libs/cls/tp_piont/chips/chips.prt';

PART_NAME
 TP29 'TP_PIONT-TP010CT020B030_PTH-TPA':;

SECTION_NUMBER 1
 '@TIMECARD_LIB.TIMECARD(SCH_1):PAGE16_I1672@CLS.TP_PIONT(CHIPS)':
 C_PATH='@timecard_lib.timecard(sch_1):page16_i1672@cls.tp_piont(chips)',
 P_PATH='@timecard_lib.timecard(sch_1):page25_i1672@cls.tp_piont(chips)',
 PATH='I1672',
 DRAWING='@TIMECARD_LIB.TIMECARD(SCH_1):PAGE16',
 PHYS_PAGE='25',
 XY='(-10950,7350)',
 ROT='2',
 VER='1',
 JEDEC_TYPE='TP010CT020B030_PTH',
 CDS_LIB='cls',
 CDS_PART_NAME='TP_PIONT-TP010CT020B030_PTH-TPA',
 BOM_IGNORE='TRUE',
 PRIM_FILE='./archive_libs/cls/tp_piont/chips/chips.prt';

PART_NAME
 TP30 'TP_PIONT-TP010CT020B030_PTH-TPA':;

SECTION_NUMBER 1
 '@TIMECARD_LIB.TIMECARD(SCH_1):PAGE16_I1678@CLS.TP_PIONT(CHIPS)':
 C_PATH='@timecard_lib.timecard(sch_1):page16_i1678@cls.tp_piont(chips)',
 P_PATH='@timecard_lib.timecard(sch_1):page25_i1678@cls.tp_piont(chips)',
 PATH='I1678',
 DRAWING='@TIMECARD_LIB.TIMECARD(SCH_1):PAGE16',
 PHYS_PAGE='25',
 XY='(-10950,7250)',
 ROT='2',
 VER='1',
 JEDEC_TYPE='TP010CT020B030_PTH',
 CDS_LIB='cls',
 CDS_PART_NAME='TP_PIONT-TP010CT020B030_PTH-TPA',
 BOM_IGNORE='TRUE',
 PRIM_FILE='./archive_libs/cls/tp_piont/chips/chips.prt';

PART_NAME
 TP31 'TP_PIONT-TP010CT020B030_PTH-TPA':;

SECTION_NUMBER 1
 '@TIMECARD_LIB.TIMECARD(SCH_1):PAGE16_I1679@CLS.TP_PIONT(CHIPS)':
 C_PATH='@timecard_lib.timecard(sch_1):page16_i1679@cls.tp_piont(chips)',
 P_PATH='@timecard_lib.timecard(sch_1):page25_i1679@cls.tp_piont(chips)',
 PATH='I1679',
 DRAWING='@TIMECARD_LIB.TIMECARD(SCH_1):PAGE16',
 PHYS_PAGE='25',
 XY='(-10950,7150)',
 ROT='2',
 VER='1',
 JEDEC_TYPE='TP010CT020B030_PTH',
 CDS_LIB='cls',
 CDS_PART_NAME='TP_PIONT-TP010CT020B030_PTH-TPA',
 BOM_IGNORE='TRUE',
 PRIM_FILE='./archive_libs/cls/tp_piont/chips/chips.prt';

PART_NAME
 TP32 'TP_PIONT-TP010CT020B030_PTH-TPA':;

SECTION_NUMBER 1
 '@TIMECARD_LIB.TIMECARD(SCH_1):PAGE16_I1662@CLS.TP_PIONT(CHIPS)':
 C_PATH='@timecard_lib.timecard(sch_1):page16_i1662@cls.tp_piont(chips)',
 P_PATH='@timecard_lib.timecard(sch_1):page25_i1662@cls.tp_piont(chips)',
 PATH='I1662',
 DRAWING='@TIMECARD_LIB.TIMECARD(SCH_1):PAGE16',
 PHYS_PAGE='25',
 XY='(-10950,7000)',
 ROT='2',
 VER='1',
 JEDEC_TYPE='TP010CT020B030_PTH',
 CDS_LIB='cls',
 CDS_PART_NAME='TP_PIONT-TP010CT020B030_PTH-TPA',
 BOM_IGNORE='TRUE',
 PRIM_FILE='./archive_libs/cls/tp_piont/chips/chips.prt';

PART_NAME
 TP33 'TP_PIONT-TP010CT020B030_PTH-TPA':;

SECTION_NUMBER 1
 '@TIMECARD_LIB.TIMECARD(SCH_1):PAGE16_I1669@CLS.TP_PIONT(CHIPS)':
 C_PATH='@timecard_lib.timecard(sch_1):page16_i1669@cls.tp_piont(chips)',
 P_PATH='@timecard_lib.timecard(sch_1):page25_i1669@cls.tp_piont(chips)',
 PATH='I1669',
 DRAWING='@TIMECARD_LIB.TIMECARD(SCH_1):PAGE16',
 PHYS_PAGE='25',
 XY='(-10950,6900)',
 ROT='2',
 VER='1',
 JEDEC_TYPE='TP010CT020B030_PTH',
 CDS_LIB='cls',
 CDS_PART_NAME='TP_PIONT-TP010CT020B030_PTH-TPA',
 BOM_IGNORE='TRUE',
 PRIM_FILE='./archive_libs/cls/tp_piont/chips/chips.prt';

PART_NAME
 TP34 'TP_PIONT-TP010CT020B030_PTH-TPA':;

SECTION_NUMBER 1
 '@TIMECARD_LIB.TIMECARD(SCH_1):PAGE16_I1673@CLS.TP_PIONT(CHIPS)':
 C_PATH='@timecard_lib.timecard(sch_1):page16_i1673@cls.tp_piont(chips)',
 P_PATH='@timecard_lib.timecard(sch_1):page25_i1673@cls.tp_piont(chips)',
 PATH='I1673',
 DRAWING='@TIMECARD_LIB.TIMECARD(SCH_1):PAGE16',
 PHYS_PAGE='25',
 XY='(-10950,6800)',
 ROT='2',
 VER='1',
 JEDEC_TYPE='TP010CT020B030_PTH',
 CDS_LIB='cls',
 CDS_PART_NAME='TP_PIONT-TP010CT020B030_PTH-TPA',
 BOM_IGNORE='TRUE',
 PRIM_FILE='./archive_libs/cls/tp_piont/chips/chips.prt';

PART_NAME
 TP35 'TP_PIONT-TP010CT020B030_PTH-TPA':;

SECTION_NUMBER 1
 '@TIMECARD_LIB.TIMECARD(SCH_1):PAGE16_I1675@CLS.TP_PIONT(CHIPS)':
 C_PATH='@timecard_lib.timecard(sch_1):page16_i1675@cls.tp_piont(chips)',
 P_PATH='@timecard_lib.timecard(sch_1):page25_i1675@cls.tp_piont(chips)',
 PATH='I1675',
 DRAWING='@TIMECARD_LIB.TIMECARD(SCH_1):PAGE16',
 PHYS_PAGE='25',
 XY='(-10950,6700)',
 ROT='2',
 VER='1',
 JEDEC_TYPE='TP010CT020B030_PTH',
 CDS_LIB='cls',
 CDS_PART_NAME='TP_PIONT-TP010CT020B030_PTH-TPA',
 BOM_IGNORE='TRUE',
 PRIM_FILE='./archive_libs/cls/tp_piont/chips/chips.prt';

PART_NAME
 TP36 'TP_PIONT-TP010CT020B030_PTH-TPA':;

SECTION_NUMBER 1
 '@TIMECARD_LIB.TIMECARD(SCH_1):PAGE16_I1650@CLS.TP_PIONT(CHIPS)':
 C_PATH='@timecard_lib.timecard(sch_1):page16_i1650@cls.tp_piont(chips)',
 P_PATH='@timecard_lib.timecard(sch_1):page25_i1650@cls.tp_piont(chips)',
 PATH='I1650',
 DRAWING='@TIMECARD_LIB.TIMECARD(SCH_1):PAGE16',
 PHYS_PAGE='25',
 XY='(-10950,6400)',
 ROT='2',
 VER='1',
 JEDEC_TYPE='TP010CT020B030_PTH',
 CDS_LIB='cls',
 CDS_PART_NAME='TP_PIONT-TP010CT020B030_PTH-TPA',
 BOM_IGNORE='TRUE',
 PRIM_FILE='./archive_libs/cls/tp_piont/chips/chips.prt';

PART_NAME
 TP37 'TP_PIONT-TP010CT020B030_PTH-TPA':;

SECTION_NUMBER 1
 '@TIMECARD_LIB.TIMECARD(SCH_1):PAGE16_I1682@CLS.TP_PIONT(CHIPS)':
 C_PATH='@timecard_lib.timecard(sch_1):page16_i1682@cls.tp_piont(chips)',
 P_PATH='@timecard_lib.timecard(sch_1):page25_i1682@cls.tp_piont(chips)',
 PATH='I1682',
 DRAWING='@TIMECARD_LIB.TIMECARD(SCH_1):PAGE16',
 PHYS_PAGE='25',
 XY='(-10950,6300)',
 ROT='2',
 VER='1',
 JEDEC_TYPE='TP010CT020B030_PTH',
 CDS_LIB='cls',
 CDS_PART_NAME='TP_PIONT-TP010CT020B030_PTH-TPA',
 BOM_IGNORE='TRUE',
 PRIM_FILE='./archive_libs/cls/tp_piont/chips/chips.prt';

PART_NAME
 TP38 'TP_PIONT-TP010CT020B030_PTH-TPA':;

SECTION_NUMBER 1
 '@TIMECARD_LIB.TIMECARD(SCH_1):PAGE16_I1651@CLS.TP_PIONT(CHIPS)':
 C_PATH='@timecard_lib.timecard(sch_1):page16_i1651@cls.tp_piont(chips)',
 P_PATH='@timecard_lib.timecard(sch_1):page25_i1651@cls.tp_piont(chips)',
 PATH='I1651',
 DRAWING='@TIMECARD_LIB.TIMECARD(SCH_1):PAGE16',
 PHYS_PAGE='25',
 XY='(-10950,6100)',
 ROT='2',
 VER='1',
 JEDEC_TYPE='TP010CT020B030_PTH',
 CDS_LIB='cls',
 CDS_PART_NAME='TP_PIONT-TP010CT020B030_PTH-TPA',
 BOM_IGNORE='TRUE',
 PRIM_FILE='./archive_libs/cls/tp_piont/chips/chips.prt';

PART_NAME
 TP39 'TP_PIONT-TP010CT020B030_PTH-TPA':;

SECTION_NUMBER 1
 '@TIMECARD_LIB.TIMECARD(SCH_1):PAGE16_I1652@CLS.TP_PIONT(CHIPS)':
 C_PATH='@timecard_lib.timecard(sch_1):page16_i1652@cls.tp_piont(chips)',
 P_PATH='@timecard_lib.timecard(sch_1):page25_i1652@cls.tp_piont(chips)',
 PATH='I1652',
 DRAWING='@TIMECARD_LIB.TIMECARD(SCH_1):PAGE16',
 PHYS_PAGE='25',
 XY='(-10950,6000)',
 ROT='2',
 VER='1',
 JEDEC_TYPE='TP010CT020B030_PTH',
 CDS_LIB='cls',
 CDS_PART_NAME='TP_PIONT-TP010CT020B030_PTH-TPA',
 BOM_IGNORE='TRUE',
 PRIM_FILE='./archive_libs/cls/tp_piont/chips/chips.prt';

PART_NAME
 TP40 'TP_PIONT-TP010CT020B030_PTH-TPA':;

SECTION_NUMBER 1
 '@TIMECARD_LIB.TIMECARD(SCH_1):PAGE16_I1653@CLS.TP_PIONT(CHIPS)':
 C_PATH='@timecard_lib.timecard(sch_1):page16_i1653@cls.tp_piont(chips)',
 P_PATH='@timecard_lib.timecard(sch_1):page25_i1653@cls.tp_piont(chips)',
 PATH='I1653',
 DRAWING='@TIMECARD_LIB.TIMECARD(SCH_1):PAGE16',
 PHYS_PAGE='25',
 XY='(-10950,5900)',
 ROT='2',
 VER='1',
 JEDEC_TYPE='TP010CT020B030_PTH',
 CDS_LIB='cls',
 CDS_PART_NAME='TP_PIONT-TP010CT020B030_PTH-TPA',
 BOM_IGNORE='TRUE',
 PRIM_FILE='./archive_libs/cls/tp_piont/chips/chips.prt';

PART_NAME
 TP41 'TP_PIONT-TP010CT020B030_PTH-TPA':;

SECTION_NUMBER 1
 '@TIMECARD_LIB.TIMECARD(SCH_1):PAGE16_I1654@CLS.TP_PIONT(CHIPS)':
 C_PATH='@timecard_lib.timecard(sch_1):page16_i1654@cls.tp_piont(chips)',
 P_PATH='@timecard_lib.timecard(sch_1):page25_i1654@cls.tp_piont(chips)',
 PATH='I1654',
 DRAWING='@TIMECARD_LIB.TIMECARD(SCH_1):PAGE16',
 PHYS_PAGE='25',
 XY='(-10950,5800)',
 ROT='2',
 VER='1',
 JEDEC_TYPE='TP010CT020B030_PTH',
 CDS_LIB='cls',
 CDS_PART_NAME='TP_PIONT-TP010CT020B030_PTH-TPA',
 BOM_IGNORE='TRUE',
 PRIM_FILE='./archive_libs/cls/tp_piont/chips/chips.prt';

PART_NAME
 TP42 'TP_PIONT-TP010CT020B030_PTH-TPA':;

SECTION_NUMBER 1
 '@TIMECARD_LIB.TIMECARD(SCH_1):PAGE16_I1665@CLS.TP_PIONT(CHIPS)':
 C_PATH='@timecard_lib.timecard(sch_1):page16_i1665@cls.tp_piont(chips)',
 P_PATH='@timecard_lib.timecard(sch_1):page25_i1665@cls.tp_piont(chips)',
 PATH='I1665',
 DRAWING='@TIMECARD_LIB.TIMECARD(SCH_1):PAGE16',
 PHYS_PAGE='25',
 XY='(-1000,9200)',
 ROT='0',
 VER='1',
 JEDEC_TYPE='TP010CT020B030_PTH',
 CDS_LIB='cls',
 CDS_PART_NAME='TP_PIONT-TP010CT020B030_PTH-TPA',
 BOM_IGNORE='TRUE',
 PRIM_FILE='./archive_libs/cls/tp_piont/chips/chips.prt';

PART_NAME
 TP43 'TP_PIONT-TP010CT020B030_PTH-TPA':;

SECTION_NUMBER 1
 '@TIMECARD_LIB.TIMECARD(SCH_1):PAGE16_I1691@CLS.TP_PIONT(CHIPS)':
 C_PATH='@timecard_lib.timecard(sch_1):page16_i1691@cls.tp_piont(chips)',
 P_PATH='@timecard_lib.timecard(sch_1):page25_i1691@cls.tp_piont(chips)',
 PATH='I1691',
 DRAWING='@TIMECARD_LIB.TIMECARD(SCH_1):PAGE16',
 PHYS_PAGE='25',
 XY='(-10950,6500)',
 ROT='2',
 VER='1',
 JEDEC_TYPE='TP010CT020B030_PTH',
 CDS_LIB='cls',
 CDS_PART_NAME='TP_PIONT-TP010CT020B030_PTH-TPA',
 BOM_IGNORE='TRUE',
 PRIM_FILE='./archive_libs/cls/tp_piont/chips/chips.prt';

PART_NAME
 TP44 'TP_PIONT-TP010CT020B030_PTH-TPA':;

SECTION_NUMBER 1
 '@TIMECARD_LIB.TIMECARD(SCH_1):PAGE16_I1689@CLS.TP_PIONT(CHIPS)':
 C_PATH='@timecard_lib.timecard(sch_1):page16_i1689@cls.tp_piont(chips)',
 P_PATH='@timecard_lib.timecard(sch_1):page25_i1689@cls.tp_piont(chips)',
 PATH='I1689',
 DRAWING='@TIMECARD_LIB.TIMECARD(SCH_1):PAGE16',
 PHYS_PAGE='25',
 XY='(-8250,9500)',
 ROT='2',
 VER='1',
 JEDEC_TYPE='TP010CT020B030_PTH',
 CDS_LIB='cls',
 CDS_PART_NAME='TP_PIONT-TP010CT020B030_PTH-TPA',
 BOM_IGNORE='TRUE',
 PRIM_FILE='./archive_libs/cls/tp_piont/chips/chips.prt';

PART_NAME
 TP45 'TP_PIONT-TP010CT020B030_PTH-TPA':;

SECTION_NUMBER 1
 '@TIMECARD_LIB.TIMECARD(SCH_1):PAGE16_I1690@CLS.TP_PIONT(CHIPS)':
 C_PATH='@timecard_lib.timecard(sch_1):page16_i1690@cls.tp_piont(chips)',
 P_PATH='@timecard_lib.timecard(sch_1):page25_i1690@cls.tp_piont(chips)',
 PATH='I1690',
 DRAWING='@TIMECARD_LIB.TIMECARD(SCH_1):PAGE16',
 PHYS_PAGE='25',
 XY='(-8250,9400)',
 ROT='2',
 VER='1',
 JEDEC_TYPE='TP010CT020B030_PTH',
 CDS_LIB='cls',
 CDS_PART_NAME='TP_PIONT-TP010CT020B030_PTH-TPA',
 BOM_IGNORE='TRUE',
 PRIM_FILE='./archive_libs/cls/tp_piont/chips/chips.prt';

PART_NAME
 TP46 'TP_PIONT-TP010CT020B030_PTH-TPA':;

SECTION_NUMBER 1
 '@TIMECARD_LIB.TIMECARD(SCH_1):PAGE16_I1684@CLS.TP_PIONT(CHIPS)':
 C_PATH='@timecard_lib.timecard(sch_1):page16_i1684@cls.tp_piont(chips)',
 P_PATH='@timecard_lib.timecard(sch_1):page25_i1684@cls.tp_piont(chips)',
 PATH='I1684',
 DRAWING='@TIMECARD_LIB.TIMECARD(SCH_1):PAGE16',
 PHYS_PAGE='25',
 XY='(-8250,9300)',
 ROT='2',
 VER='1',
 JEDEC_TYPE='TP010CT020B030_PTH',
 CDS_LIB='cls',
 CDS_PART_NAME='TP_PIONT-TP010CT020B030_PTH-TPA',
 BOM_IGNORE='TRUE',
 PRIM_FILE='./archive_libs/cls/tp_piont/chips/chips.prt';

PART_NAME
 TP47 'TP_PIONT-TP010CT020B030_PTH-TPA':;

SECTION_NUMBER 1
 '@TIMECARD_LIB.TIMECARD(SCH_1):PAGE16_I1693@CLS.TP_PIONT(CHIPS)':
 C_PATH='@timecard_lib.timecard(sch_1):page16_i1693@cls.tp_piont(chips)',
 P_PATH='@timecard_lib.timecard(sch_1):page25_i1693@cls.tp_piont(chips)',
 PATH='I1693',
 DRAWING='@TIMECARD_LIB.TIMECARD(SCH_1):PAGE16',
 PHYS_PAGE='25',
 XY='(-8250,9200)',
 ROT='2',
 VER='1',
 JEDEC_TYPE='TP010CT020B030_PTH',
 CDS_LIB='cls',
 CDS_PART_NAME='TP_PIONT-TP010CT020B030_PTH-TPA',
 BOM_IGNORE='TRUE',
 PRIM_FILE='./archive_libs/cls/tp_piont/chips/chips.prt';

PART_NAME
 TP48 'TP_PIONT-TP010CT020B030_PTH-TPA':;

SECTION_NUMBER 1
 '@TIMECARD_LIB.TIMECARD(SCH_1):PAGE16_I1695@CLS.TP_PIONT(CHIPS)':
 C_PATH='@timecard_lib.timecard(sch_1):page16_i1695@cls.tp_piont(chips)',
 P_PATH='@timecard_lib.timecard(sch_1):page25_i1695@cls.tp_piont(chips)',
 PATH='I1695',
 DRAWING='@TIMECARD_LIB.TIMECARD(SCH_1):PAGE16',
 PHYS_PAGE='25',
 XY='(-8250,9000)',
 ROT='2',
 VER='1',
 JEDEC_TYPE='TP010CT020B030_PTH',
 CDS_LIB='cls',
 CDS_PART_NAME='TP_PIONT-TP010CT020B030_PTH-TPA',
 BOM_IGNORE='TRUE',
 PRIM_FILE='./archive_libs/cls/tp_piont/chips/chips.prt';

PART_NAME
 TP49 'TP_PIONT-TP010CT020B030_PTH-TPA':;

SECTION_NUMBER 1
 '@TIMECARD_LIB.TIMECARD(SCH_1):PAGE16_I1699@CLS.TP_PIONT(CHIPS)':
 C_PATH='@timecard_lib.timecard(sch_1):page16_i1699@cls.tp_piont(chips)',
 P_PATH='@timecard_lib.timecard(sch_1):page25_i1699@cls.tp_piont(chips)',
 PATH='I1699',
 DRAWING='@TIMECARD_LIB.TIMECARD(SCH_1):PAGE16',
 PHYS_PAGE='25',
 XY='(-8250,8850)',
 ROT='2',
 VER='1',
 JEDEC_TYPE='TP010CT020B030_PTH',
 CDS_LIB='cls',
 CDS_PART_NAME='TP_PIONT-TP010CT020B030_PTH-TPA',
 BOM_IGNORE='TRUE',
 PRIM_FILE='./archive_libs/cls/tp_piont/chips/chips.prt';

PART_NAME
 TP50 'TP_PIONT-TP010CT020B030_PTH-TPA':;

SECTION_NUMBER 1
 '@TIMECARD_LIB.TIMECARD(SCH_1):PAGE16_I1701@CLS.TP_PIONT(CHIPS)':
 C_PATH='@timecard_lib.timecard(sch_1):page16_i1701@cls.tp_piont(chips)',
 P_PATH='@timecard_lib.timecard(sch_1):page25_i1701@cls.tp_piont(chips)',
 PATH='I1701',
 DRAWING='@TIMECARD_LIB.TIMECARD(SCH_1):PAGE16',
 PHYS_PAGE='25',
 XY='(-8250,8750)',
 ROT='2',
 VER='1',
 JEDEC_TYPE='TP010CT020B030_PTH',
 CDS_LIB='cls',
 CDS_PART_NAME='TP_PIONT-TP010CT020B030_PTH-TPA',
 BOM_IGNORE='TRUE',
 PRIM_FILE='./archive_libs/cls/tp_piont/chips/chips.prt';

PART_NAME
 TP51 'TP_PIONT-TP010CT020B030_PTH-TPA':;

SECTION_NUMBER 1
 '@TIMECARD_LIB.TIMECARD(SCH_1):PAGE16_I1704@CLS.TP_PIONT(CHIPS)':
 C_PATH='@timecard_lib.timecard(sch_1):page16_i1704@cls.tp_piont(chips)',
 P_PATH='@timecard_lib.timecard(sch_1):page25_i1704@cls.tp_piont(chips)',
 PATH='I1704',
 DRAWING='@TIMECARD_LIB.TIMECARD(SCH_1):PAGE16',
 PHYS_PAGE='25',
 XY='(-8250,8500)',
 ROT='2',
 VER='1',
 JEDEC_TYPE='TP010CT020B030_PTH',
 CDS_LIB='cls',
 CDS_PART_NAME='TP_PIONT-TP010CT020B030_PTH-TPA',
 BOM_IGNORE='TRUE',
 PRIM_FILE='./archive_libs/cls/tp_piont/chips/chips.prt';

PART_NAME
 TP52 'TP_PIONT-TP010CT020B030_PTH-TPA':;

SECTION_NUMBER 1
 '@TIMECARD_LIB.TIMECARD(SCH_1):PAGE16_I1206@CLS.TP_PIONT(CHIPS)':
 C_PATH='@timecard_lib.timecard(sch_1):page16_i1206@cls.tp_piont(chips)',
 P_PATH='@timecard_lib.timecard(sch_1):page25_i1206@cls.tp_piont(chips)',
 PATH='I1206',
 DRAWING='@TIMECARD_LIB.TIMECARD(SCH_1):PAGE16',
 PHYS_PAGE='25',
 XY='(-1000,8800)',
 ROT='0',
 VER='1',
 JEDEC_TYPE='TP010CT020B030_PTH',
 CDS_LIB='cls',
 CDS_PART_NAME='TP_PIONT-TP010CT020B030_PTH-TPA',
 BOM_IGNORE='TRUE',
 PRIM_FILE='./archive_libs/cls/tp_piont/chips/chips.prt';

PART_NAME
 TP53 'TP_PIONT-TP010CT020B030_PTH-TPA':;

SECTION_NUMBER 1
 '@TIMECARD_LIB.TIMECARD(SCH_1):PAGE16_I1208@CLS.TP_PIONT(CHIPS)':
 C_PATH='@timecard_lib.timecard(sch_1):page16_i1208@cls.tp_piont(chips)',
 P_PATH='@timecard_lib.timecard(sch_1):page25_i1208@cls.tp_piont(chips)',
 PATH='I1208',
 DRAWING='@TIMECARD_LIB.TIMECARD(SCH_1):PAGE16',
 PHYS_PAGE='25',
 XY='(-1000,8350)',
 ROT='0',
 VER='1',
 JEDEC_TYPE='TP010CT020B030_PTH',
 CDS_LIB='cls',
 CDS_PART_NAME='TP_PIONT-TP010CT020B030_PTH-TPA',
 BOM_IGNORE='TRUE',
 PRIM_FILE='./archive_libs/cls/tp_piont/chips/chips.prt';

PART_NAME
 TP54 'TP_PIONT-TP010CT020B030_PTH-TPA':;

SECTION_NUMBER 1
 '@TIMECARD_LIB.TIMECARD(SCH_1):PAGE16_I1210@CLS.TP_PIONT(CHIPS)':
 C_PATH='@timecard_lib.timecard(sch_1):page16_i1210@cls.tp_piont(chips)',
 P_PATH='@timecard_lib.timecard(sch_1):page25_i1210@cls.tp_piont(chips)',
 PATH='I1210',
 DRAWING='@TIMECARD_LIB.TIMECARD(SCH_1):PAGE16',
 PHYS_PAGE='25',
 XY='(-1000,7900)',
 ROT='0',
 VER='1',
 JEDEC_TYPE='TP010CT020B030_PTH',
 CDS_LIB='cls',
 CDS_PART_NAME='TP_PIONT-TP010CT020B030_PTH-TPA',
 BOM_IGNORE='TRUE',
 PRIM_FILE='./archive_libs/cls/tp_piont/chips/chips.prt';

PART_NAME
 TP55 'TP_PIONT-TP010CT020B030_PTH-TPA':;

SECTION_NUMBER 1
 '@TIMECARD_LIB.TIMECARD(SCH_1):PAGE16_I1212@CLS.TP_PIONT(CHIPS)':
 C_PATH='@timecard_lib.timecard(sch_1):page16_i1212@cls.tp_piont(chips)',
 P_PATH='@timecard_lib.timecard(sch_1):page25_i1212@cls.tp_piont(chips)',
 PATH='I1212',
 DRAWING='@TIMECARD_LIB.TIMECARD(SCH_1):PAGE16',
 PHYS_PAGE='25',
 XY='(-1000,7450)',
 ROT='0',
 VER='1',
 JEDEC_TYPE='TP010CT020B030_PTH',
 CDS_LIB='cls',
 CDS_PART_NAME='TP_PIONT-TP010CT020B030_PTH-TPA',
 BOM_IGNORE='TRUE',
 PRIM_FILE='./archive_libs/cls/tp_piont/chips/chips.prt';

PART_NAME
 TP56 'TP_PIONT-TP010CT020B030_PTH-TPA':;

SECTION_NUMBER 1
 '@TIMECARD_LIB.TIMECARD(SCH_1):PAGE16_I1215@CLS.TP_PIONT(CHIPS)':
 C_PATH='@timecard_lib.timecard(sch_1):page16_i1215@cls.tp_piont(chips)',
 P_PATH='@timecard_lib.timecard(sch_1):page25_i1215@cls.tp_piont(chips)',
 PATH='I1215',
 DRAWING='@TIMECARD_LIB.TIMECARD(SCH_1):PAGE16',
 PHYS_PAGE='25',
 XY='(-1000,7000)',
 ROT='0',
 VER='1',
 JEDEC_TYPE='TP010CT020B030_PTH',
 CDS_LIB='cls',
 CDS_PART_NAME='TP_PIONT-TP010CT020B030_PTH-TPA',
 BOM_IGNORE='TRUE',
 PRIM_FILE='./archive_libs/cls/tp_piont/chips/chips.prt';

PART_NAME
 TP57 'TP_PIONT-TP010CT020B030_PTH-TPA':;

SECTION_NUMBER 1
 '@TIMECARD_LIB.TIMECARD(SCH_1):PAGE16_I1217@CLS.TP_PIONT(CHIPS)':
 C_PATH='@timecard_lib.timecard(sch_1):page16_i1217@cls.tp_piont(chips)',
 P_PATH='@timecard_lib.timecard(sch_1):page25_i1217@cls.tp_piont(chips)',
 PATH='I1217',
 DRAWING='@TIMECARD_LIB.TIMECARD(SCH_1):PAGE16',
 PHYS_PAGE='25',
 XY='(-3300,9150)',
 ROT='0',
 VER='1',
 JEDEC_TYPE='TP010CT020B030_PTH',
 CDS_LIB='cls',
 CDS_PART_NAME='TP_PIONT-TP010CT020B030_PTH-TPA',
 BOM_IGNORE='TRUE',
 PRIM_FILE='./archive_libs/cls/tp_piont/chips/chips.prt';

PART_NAME
 TP58 'TP_PIONT-TP010CT020B030_PTH-TPA':;

SECTION_NUMBER 1
 '@TIMECARD_LIB.TIMECARD(SCH_1):PAGE16_I1219@CLS.TP_PIONT(CHIPS)':
 C_PATH='@timecard_lib.timecard(sch_1):page16_i1219@cls.tp_piont(chips)',
 P_PATH='@timecard_lib.timecard(sch_1):page25_i1219@cls.tp_piont(chips)',
 PATH='I1219',
 DRAWING='@TIMECARD_LIB.TIMECARD(SCH_1):PAGE16',
 PHYS_PAGE='25',
 XY='(-3300,8700)',
 ROT='0',
 VER='1',
 JEDEC_TYPE='TP010CT020B030_PTH',
 CDS_LIB='cls',
 CDS_PART_NAME='TP_PIONT-TP010CT020B030_PTH-TPA',
 BOM_IGNORE='TRUE',
 PRIM_FILE='./archive_libs/cls/tp_piont/chips/chips.prt';

PART_NAME
 TP59 'TP_PIONT-TP010CT020B030_PTH-TPA':;

SECTION_NUMBER 1
 '@TIMECARD_LIB.TIMECARD(SCH_1):PAGE16_I1663@CLS.TP_PIONT(CHIPS)':
 C_PATH='@timecard_lib.timecard(sch_1):page16_i1663@cls.tp_piont(chips)',
 P_PATH='@timecard_lib.timecard(sch_1):page25_i1663@cls.tp_piont(chips)',
 PATH='I1663',
 DRAWING='@TIMECARD_LIB.TIMECARD(SCH_1):PAGE16',
 PHYS_PAGE='25',
 XY='(-10950,6200)',
 ROT='2',
 VER='1',
 JEDEC_TYPE='TP010CT020B030_PTH',
 CDS_LIB='cls',
 CDS_PART_NAME='TP_PIONT-TP010CT020B030_PTH-TPA',
 BOM_IGNORE='TRUE',
 PRIM_FILE='./archive_libs/cls/tp_piont/chips/chips.prt';

PART_NAME
 TP60 'TP_PIONT-TP010CT020B030_PTH-TPA':;

SECTION_NUMBER 1
 '@TIMECARD_LIB.TIMECARD(SCH_1):PAGE16_I1233@CLS.TP_PIONT(CHIPS)':
 C_PATH='@timecard_lib.timecard(sch_1):page16_i1233@cls.tp_piont(chips)',
 P_PATH='@timecard_lib.timecard(sch_1):page25_i1233@cls.tp_piont(chips)',
 PATH='I1233',
 DRAWING='@TIMECARD_LIB.TIMECARD(SCH_1):PAGE16',
 PHYS_PAGE='25',
 XY='(-3300,8250)',
 ROT='0',
 VER='1',
 JEDEC_TYPE='TP010CT020B030_PTH',
 CDS_LIB='cls',
 CDS_PART_NAME='TP_PIONT-TP010CT020B030_PTH-TPA',
 BOM_IGNORE='TRUE',
 PRIM_FILE='./archive_libs/cls/tp_piont/chips/chips.prt';

PART_NAME
 TP61 'TP_PIONT-TP010CT020B030_PTH-TPA':;

SECTION_NUMBER 1
 '@TIMECARD_LIB.TIMECARD(SCH_1):PAGE9_I63@CLS.TP_PIONT(CHIPS)':
 C_PATH='@timecard_lib.timecard(sch_1):page9_i63@cls.tp_piont(chips)',
 P_PATH='@timecard_lib.timecard(sch_1):page20_i63@cls.tp_piont(chips)',
 PATH='I63',
 DRAWING='@TIMECARD_LIB.TIMECARD(SCH_1):PAGE9',
 PHYS_PAGE='20',
 XY='(-7850,9200)',
 ROT='2',
 VER='1',
 JEDEC_TYPE='TP010CT020B030_PTH',
 CDS_LIB='cls',
 CDS_PART_NAME='TP_PIONT-TP010CT020B030_PTH-TPA',
 BOM_IGNORE='TRUE',
 PRIM_FILE='./archive_libs/cls/tp_piont/chips/chips.prt';

PART_NAME
 TP62 'TP_PIONT-TP010CT020B030_PTH-TPA':;

SECTION_NUMBER 1
 '@TIMECARD_LIB.TIMECARD(SCH_1):PAGE16_I1705@CLS.TP_PIONT(CHIPS)':
 C_PATH='@timecard_lib.timecard(sch_1):page16_i1705@cls.tp_piont(chips)',
 P_PATH='@timecard_lib.timecard(sch_1):page25_i1705@cls.tp_piont(chips)',
 PATH='I1705',
 DRAWING='@TIMECARD_LIB.TIMECARD(SCH_1):PAGE16',
 PHYS_PAGE='25',
 XY='(-8250,8400)',
 ROT='2',
 VER='1',
 JEDEC_TYPE='TP010CT020B030_PTH',
 CDS_LIB='cls',
 CDS_PART_NAME='TP_PIONT-TP010CT020B030_PTH-TPA',
 BOM_IGNORE='TRUE',
 PRIM_FILE='./archive_libs/cls/tp_piont/chips/chips.prt';

PART_NAME
 TP78 'TP_PIONT-TP010CT020B030_PTH-TPA':;

SECTION_NUMBER 1
 '@TIMECARD_LIB.TIMECARD(SCH_1):PAGE16_I1516@CLS.TP_PIONT(CHIPS)':
 C_PATH='@timecard_lib.timecard(sch_1):page16_i1516@cls.tp_piont(chips)',
 P_PATH='@timecard_lib.timecard(sch_1):page25_i1516@cls.tp_piont(chips)',
 PATH='I1516',
 DRAWING='@TIMECARD_LIB.TIMECARD(SCH_1):PAGE16',
 PHYS_PAGE='25',
 XY='(-13300,9500)',
 ROT='2',
 VER='1',
 JEDEC_TYPE='TP010CT020B030_PTH',
 CDS_LIB='cls',
 CDS_PART_NAME='TP_PIONT-TP010CT020B030_PTH-TPA',
 BOM_IGNORE='TRUE',
 PRIM_FILE='./archive_libs/cls/tp_piont/chips/chips.prt';

PART_NAME
 TP132 'TP_PIONT-TP010CT020B030_PTH-TPA':;

SECTION_NUMBER 1
 '@TIMECARD_LIB.TIMECARD(SCH_1):PAGE16_I1014@CLS.TP_PIONT(CHIPS)':
 C_PATH='@timecard_lib.timecard(sch_1):page16_i1014@cls.tp_piont(chips)',
 P_PATH='@timecard_lib.timecard(sch_1):page25_i1014@cls.tp_piont(chips)',
 PATH='I1014',
 DRAWING='@TIMECARD_LIB.TIMECARD(SCH_1):PAGE16',
 PHYS_PAGE='25',
 XY='(-13300,8300)',
 ROT='2',
 VER='1',
 JEDEC_TYPE='TP010CT020B030_PTH',
 CDS_LIB='cls',
 CDS_PART_NAME='TP_PIONT-TP010CT020B030_PTH-TPA',
 BOM_IGNORE='TRUE',
 PRIM_FILE='./archive_libs/cls/tp_piont/chips/chips.prt';

PART_NAME
 TP133 'TP_PIONT-TP010CT020B030_PTH-TPA':;

SECTION_NUMBER 1
 '@TIMECARD_LIB.TIMECARD(SCH_1):PAGE16_I1015@CLS.TP_PIONT(CHIPS)':
 C_PATH='@timecard_lib.timecard(sch_1):page16_i1015@cls.tp_piont(chips)',
 P_PATH='@timecard_lib.timecard(sch_1):page25_i1015@cls.tp_piont(chips)',
 PATH='I1015',
 DRAWING='@TIMECARD_LIB.TIMECARD(SCH_1):PAGE16',
 PHYS_PAGE='25',
 XY='(-13300,8200)',
 ROT='2',
 VER='1',
 JEDEC_TYPE='TP010CT020B030_PTH',
 CDS_LIB='cls',
 CDS_PART_NAME='TP_PIONT-TP010CT020B030_PTH-TPA',
 BOM_IGNORE='TRUE',
 PRIM_FILE='./archive_libs/cls/tp_piont/chips/chips.prt';

PART_NAME
 TP134 'TP_PIONT-TP010CT020B030_PTH-TPA':;

SECTION_NUMBER 1
 '@TIMECARD_LIB.TIMECARD(SCH_1):PAGE16_I1016@CLS.TP_PIONT(CHIPS)':
 C_PATH='@timecard_lib.timecard(sch_1):page16_i1016@cls.tp_piont(chips)',
 P_PATH='@timecard_lib.timecard(sch_1):page25_i1016@cls.tp_piont(chips)',
 PATH='I1016',
 DRAWING='@TIMECARD_LIB.TIMECARD(SCH_1):PAGE16',
 PHYS_PAGE='25',
 XY='(-13300,8100)',
 ROT='2',
 VER='1',
 JEDEC_TYPE='TP010CT020B030_PTH',
 CDS_LIB='cls',
 CDS_PART_NAME='TP_PIONT-TP010CT020B030_PTH-TPA',
 BOM_IGNORE='TRUE',
 PRIM_FILE='./archive_libs/cls/tp_piont/chips/chips.prt';

PART_NAME
 TP135 'TP_PIONT-TP010CT020B030_PTH-TPA':;

SECTION_NUMBER 1
 '@TIMECARD_LIB.TIMECARD(SCH_1):PAGE16_I1017@CLS.TP_PIONT(CHIPS)':
 C_PATH='@timecard_lib.timecard(sch_1):page16_i1017@cls.tp_piont(chips)',
 P_PATH='@timecard_lib.timecard(sch_1):page25_i1017@cls.tp_piont(chips)',
 PATH='I1017',
 DRAWING='@TIMECARD_LIB.TIMECARD(SCH_1):PAGE16',
 PHYS_PAGE='25',
 XY='(-13300,8000)',
 ROT='2',
 VER='1',
 JEDEC_TYPE='TP010CT020B030_PTH',
 CDS_LIB='cls',
 CDS_PART_NAME='TP_PIONT-TP010CT020B030_PTH-TPA',
 BOM_IGNORE='TRUE',
 PRIM_FILE='./archive_libs/cls/tp_piont/chips/chips.prt';

PART_NAME
 TP136 'TP_PIONT-TP010CT020B030_PTH-TPA':;

SECTION_NUMBER 1
 '@TIMECARD_LIB.TIMECARD(SCH_1):PAGE16_I1018@CLS.TP_PIONT(CHIPS)':
 C_PATH='@timecard_lib.timecard(sch_1):page16_i1018@cls.tp_piont(chips)',
 P_PATH='@timecard_lib.timecard(sch_1):page25_i1018@cls.tp_piont(chips)',
 PATH='I1018',
 DRAWING='@TIMECARD_LIB.TIMECARD(SCH_1):PAGE16',
 PHYS_PAGE='25',
 XY='(-13300,7900)',
 ROT='2',
 VER='1',
 JEDEC_TYPE='TP010CT020B030_PTH',
 CDS_LIB='cls',
 CDS_PART_NAME='TP_PIONT-TP010CT020B030_PTH-TPA',
 BOM_IGNORE='TRUE',
 PRIM_FILE='./archive_libs/cls/tp_piont/chips/chips.prt';

PART_NAME
 TP137 'TP_PIONT-TP010CT020B030_PTH-TPA':;

SECTION_NUMBER 1
 '@TIMECARD_LIB.TIMECARD(SCH_1):PAGE16_I1019@CLS.TP_PIONT(CHIPS)':
 C_PATH='@timecard_lib.timecard(sch_1):page16_i1019@cls.tp_piont(chips)',
 P_PATH='@timecard_lib.timecard(sch_1):page25_i1019@cls.tp_piont(chips)',
 PATH='I1019',
 DRAWING='@TIMECARD_LIB.TIMECARD(SCH_1):PAGE16',
 PHYS_PAGE='25',
 XY='(-13300,7800)',
 ROT='2',
 VER='1',
 JEDEC_TYPE='TP010CT020B030_PTH',
 CDS_LIB='cls',
 CDS_PART_NAME='TP_PIONT-TP010CT020B030_PTH-TPA',
 BOM_IGNORE='TRUE',
 PRIM_FILE='./archive_libs/cls/tp_piont/chips/chips.prt';

PART_NAME
 TP138 'TP_PIONT-TP010CT020B030_PTH-TPA':;

SECTION_NUMBER 1
 '@TIMECARD_LIB.TIMECARD(SCH_1):PAGE16_I1020@CLS.TP_PIONT(CHIPS)':
 C_PATH='@timecard_lib.timecard(sch_1):page16_i1020@cls.tp_piont(chips)',
 P_PATH='@timecard_lib.timecard(sch_1):page25_i1020@cls.tp_piont(chips)',
 PATH='I1020',
 DRAWING='@TIMECARD_LIB.TIMECARD(SCH_1):PAGE16',
 PHYS_PAGE='25',
 XY='(-13300,7700)',
 ROT='2',
 VER='1',
 JEDEC_TYPE='TP010CT020B030_PTH',
 CDS_LIB='cls',
 CDS_PART_NAME='TP_PIONT-TP010CT020B030_PTH-TPA',
 BOM_IGNORE='TRUE',
 PRIM_FILE='./archive_libs/cls/tp_piont/chips/chips.prt';

PART_NAME
 TP139 'TP_PIONT-TP010CT020B030_PTH-TPA':;

SECTION_NUMBER 1
 '@TIMECARD_LIB.TIMECARD(SCH_1):PAGE16_I1021@CLS.TP_PIONT(CHIPS)':
 C_PATH='@timecard_lib.timecard(sch_1):page16_i1021@cls.tp_piont(chips)',
 P_PATH='@timecard_lib.timecard(sch_1):page25_i1021@cls.tp_piont(chips)',
 PATH='I1021',
 DRAWING='@TIMECARD_LIB.TIMECARD(SCH_1):PAGE16',
 PHYS_PAGE='25',
 XY='(-13300,7600)',
 ROT='2',
 VER='1',
 JEDEC_TYPE='TP010CT020B030_PTH',
 CDS_LIB='cls',
 CDS_PART_NAME='TP_PIONT-TP010CT020B030_PTH-TPA',
 BOM_IGNORE='TRUE',
 PRIM_FILE='./archive_libs/cls/tp_piont/chips/chips.prt';

PART_NAME
 TP140 'TP_PIONT-TP010CT020B030_PTH-TPA':;

SECTION_NUMBER 1
 '@TIMECARD_LIB.TIMECARD(SCH_1):PAGE16_I1022@CLS.TP_PIONT(CHIPS)':
 C_PATH='@timecard_lib.timecard(sch_1):page16_i1022@cls.tp_piont(chips)',
 P_PATH='@timecard_lib.timecard(sch_1):page25_i1022@cls.tp_piont(chips)',
 PATH='I1022',
 DRAWING='@TIMECARD_LIB.TIMECARD(SCH_1):PAGE16',
 PHYS_PAGE='25',
 XY='(-13300,7500)',
 ROT='2',
 VER='1',
 JEDEC_TYPE='TP010CT020B030_PTH',
 CDS_LIB='cls',
 CDS_PART_NAME='TP_PIONT-TP010CT020B030_PTH-TPA',
 BOM_IGNORE='TRUE',
 PRIM_FILE='./archive_libs/cls/tp_piont/chips/chips.prt';

PART_NAME
 TP141 'TP_PIONT-TP010CT020B030_PTH-TPA':;

SECTION_NUMBER 1
 '@TIMECARD_LIB.TIMECARD(SCH_1):PAGE16_I1023@CLS.TP_PIONT(CHIPS)':
 C_PATH='@timecard_lib.timecard(sch_1):page16_i1023@cls.tp_piont(chips)',
 P_PATH='@timecard_lib.timecard(sch_1):page25_i1023@cls.tp_piont(chips)',
 PATH='I1023',
 DRAWING='@TIMECARD_LIB.TIMECARD(SCH_1):PAGE16',
 PHYS_PAGE='25',
 XY='(-13300,7400)',
 ROT='2',
 VER='1',
 JEDEC_TYPE='TP010CT020B030_PTH',
 CDS_LIB='cls',
 CDS_PART_NAME='TP_PIONT-TP010CT020B030_PTH-TPA',
 BOM_IGNORE='TRUE',
 PRIM_FILE='./archive_libs/cls/tp_piont/chips/chips.prt';

PART_NAME
 TP180 'TP_PIONT-TP010CT020B030_PTH-TPA':;

SECTION_NUMBER 1
 '@TIMECARD_LIB.TIMECARD(SCH_1):PAGE16_I1511@CLS.TP_PIONT(CHIPS)':
 C_PATH='@timecard_lib.timecard(sch_1):page16_i1511@cls.tp_piont(chips)',
 P_PATH='@timecard_lib.timecard(sch_1):page25_i1511@cls.tp_piont(chips)',
 PATH='I1511',
 DRAWING='@TIMECARD_LIB.TIMECARD(SCH_1):PAGE16',
 PHYS_PAGE='25',
 XY='(-13300,9400)',
 ROT='2',
 VER='1',
 JEDEC_TYPE='TP010CT020B030_PTH',
 CDS_LIB='cls',
 CDS_PART_NAME='TP_PIONT-TP010CT020B030_PTH-TPA',
 BOM_IGNORE='TRUE',
 PRIM_FILE='./archive_libs/cls/tp_piont/chips/chips.prt';

PART_NAME
 TP181 'TP_PIONT-TP010CT020B030_PTH-TPA':;

SECTION_NUMBER 1
 '@TIMECARD_LIB.TIMECARD(SCH_1):PAGE16_I1512@CLS.TP_PIONT(CHIPS)':
 C_PATH='@timecard_lib.timecard(sch_1):page16_i1512@cls.tp_piont(chips)',
 P_PATH='@timecard_lib.timecard(sch_1):page25_i1512@cls.tp_piont(chips)',
 PATH='I1512',
 DRAWING='@TIMECARD_LIB.TIMECARD(SCH_1):PAGE16',
 PHYS_PAGE='25',
 XY='(-13300,9300)',
 ROT='2',
 VER='1',
 JEDEC_TYPE='TP010CT020B030_PTH',
 CDS_LIB='cls',
 CDS_PART_NAME='TP_PIONT-TP010CT020B030_PTH-TPA',
 BOM_IGNORE='TRUE',
 PRIM_FILE='./archive_libs/cls/tp_piont/chips/chips.prt';

PART_NAME
 TP182 'TP_PIONT-TP010CT020B030_PTH-TPA':;

SECTION_NUMBER 1
 '@TIMECARD_LIB.TIMECARD(SCH_1):PAGE16_I1513@CLS.TP_PIONT(CHIPS)':
 C_PATH='@timecard_lib.timecard(sch_1):page16_i1513@cls.tp_piont(chips)',
 P_PATH='@timecard_lib.timecard(sch_1):page25_i1513@cls.tp_piont(chips)',
 PATH='I1513',
 DRAWING='@TIMECARD_LIB.TIMECARD(SCH_1):PAGE16',
 PHYS_PAGE='25',
 XY='(-13300,9200)',
 ROT='2',
 VER='1',
 JEDEC_TYPE='TP010CT020B030_PTH',
 CDS_LIB='cls',
 CDS_PART_NAME='TP_PIONT-TP010CT020B030_PTH-TPA',
 BOM_IGNORE='TRUE',
 PRIM_FILE='./archive_libs/cls/tp_piont/chips/chips.prt';

PART_NAME
 TP183 'TP_PIONT-TP010CT020B030_PTH-TPA':;

SECTION_NUMBER 1
 '@TIMECARD_LIB.TIMECARD(SCH_1):PAGE16_I1505@CLS.TP_PIONT(CHIPS)':
 C_PATH='@timecard_lib.timecard(sch_1):page16_i1505@cls.tp_piont(chips)',
 P_PATH='@timecard_lib.timecard(sch_1):page25_i1505@cls.tp_piont(chips)',
 PATH='I1505',
 DRAWING='@TIMECARD_LIB.TIMECARD(SCH_1):PAGE16',
 PHYS_PAGE='25',
 XY='(-13300,9050)',
 ROT='2',
 VER='1',
 JEDEC_TYPE='TP010CT020B030_PTH',
 CDS_LIB='cls',
 CDS_PART_NAME='TP_PIONT-TP010CT020B030_PTH-TPA',
 BOM_IGNORE='TRUE',
 PRIM_FILE='./archive_libs/cls/tp_piont/chips/chips.prt';

PART_NAME
 TP184 'TP_PIONT-TP010CT020B030_PTH-TPA':;

SECTION_NUMBER 1
 '@TIMECARD_LIB.TIMECARD(SCH_1):PAGE16_I1506@CLS.TP_PIONT(CHIPS)':
 C_PATH='@timecard_lib.timecard(sch_1):page16_i1506@cls.tp_piont(chips)',
 P_PATH='@timecard_lib.timecard(sch_1):page25_i1506@cls.tp_piont(chips)',
 PATH='I1506',
 DRAWING='@TIMECARD_LIB.TIMECARD(SCH_1):PAGE16',
 PHYS_PAGE='25',
 XY='(-13300,8950)',
 ROT='2',
 VER='1',
 JEDEC_TYPE='TP010CT020B030_PTH',
 CDS_LIB='cls',
 CDS_PART_NAME='TP_PIONT-TP010CT020B030_PTH-TPA',
 BOM_IGNORE='TRUE',
 PRIM_FILE='./archive_libs/cls/tp_piont/chips/chips.prt';

PART_NAME
 TP185 'TP_PIONT-TP010CT020B030_PTH-TPA':;

SECTION_NUMBER 1
 '@TIMECARD_LIB.TIMECARD(SCH_1):PAGE16_I1507@CLS.TP_PIONT(CHIPS)':
 C_PATH='@timecard_lib.timecard(sch_1):page16_i1507@cls.tp_piont(chips)',
 P_PATH='@timecard_lib.timecard(sch_1):page25_i1507@cls.tp_piont(chips)',
 PATH='I1507',
 DRAWING='@TIMECARD_LIB.TIMECARD(SCH_1):PAGE16',
 PHYS_PAGE='25',
 XY='(-13300,8850)',
 ROT='2',
 VER='1',
 JEDEC_TYPE='TP010CT020B030_PTH',
 CDS_LIB='cls',
 CDS_PART_NAME='TP_PIONT-TP010CT020B030_PTH-TPA',
 BOM_IGNORE='TRUE',
 PRIM_FILE='./archive_libs/cls/tp_piont/chips/chips.prt';

PART_NAME
 TP186 'TP_PIONT-TP010CT020B030_PTH-TPA':;

SECTION_NUMBER 1
 '@TIMECARD_LIB.TIMECARD(SCH_1):PAGE16_I1508@CLS.TP_PIONT(CHIPS)':
 C_PATH='@timecard_lib.timecard(sch_1):page16_i1508@cls.tp_piont(chips)',
 P_PATH='@timecard_lib.timecard(sch_1):page25_i1508@cls.tp_piont(chips)',
 PATH='I1508',
 DRAWING='@TIMECARD_LIB.TIMECARD(SCH_1):PAGE16',
 PHYS_PAGE='25',
 XY='(-13300,8750)',
 ROT='2',
 VER='1',
 JEDEC_TYPE='TP010CT020B030_PTH',
 CDS_LIB='cls',
 CDS_PART_NAME='TP_PIONT-TP010CT020B030_PTH-TPA',
 BOM_IGNORE='TRUE',
 PRIM_FILE='./archive_libs/cls/tp_piont/chips/chips.prt';

PART_NAME
 TP187 'TP_PIONT-TP010CT020B030_PTH-TPA':;

SECTION_NUMBER 1
 '@TIMECARD_LIB.TIMECARD(SCH_1):PAGE16_I1509@CLS.TP_PIONT(CHIPS)':
 C_PATH='@timecard_lib.timecard(sch_1):page16_i1509@cls.tp_piont(chips)',
 P_PATH='@timecard_lib.timecard(sch_1):page25_i1509@cls.tp_piont(chips)',
 PATH='I1509',
 DRAWING='@TIMECARD_LIB.TIMECARD(SCH_1):PAGE16',
 PHYS_PAGE='25',
 XY='(-13300,8650)',
 ROT='2',
 VER='1',
 JEDEC_TYPE='TP010CT020B030_PTH',
 CDS_LIB='cls',
 CDS_PART_NAME='TP_PIONT-TP010CT020B030_PTH-TPA',
 BOM_IGNORE='TRUE',
 PRIM_FILE='./archive_libs/cls/tp_piont/chips/chips.prt';

PART_NAME
 TP188 'TP_PIONT-TP010CT020B030_PTH-TPA':;

SECTION_NUMBER 1
 '@TIMECARD_LIB.TIMECARD(SCH_1):PAGE16_I1510@CLS.TP_PIONT(CHIPS)':
 C_PATH='@timecard_lib.timecard(sch_1):page16_i1510@cls.tp_piont(chips)',
 P_PATH='@timecard_lib.timecard(sch_1):page25_i1510@cls.tp_piont(chips)',
 PATH='I1510',
 DRAWING='@TIMECARD_LIB.TIMECARD(SCH_1):PAGE16',
 PHYS_PAGE='25',
 XY='(-13300,8550)',
 ROT='2',
 VER='1',
 JEDEC_TYPE='TP010CT020B030_PTH',
 CDS_LIB='cls',
 CDS_PART_NAME='TP_PIONT-TP010CT020B030_PTH-TPA',
 BOM_IGNORE='TRUE',
 PRIM_FILE='./archive_libs/cls/tp_piont/chips/chips.prt';

PART_NAME
 TP193 'TP_PIONT-TP010CT020B030_PTH-TPA':;

SECTION_NUMBER 1
 '@TIMECARD_LIB.TIMECARD(SCH_1):PAGE16_I1487@CLS.TP_PIONT(CHIPS)':
 C_PATH='@timecard_lib.timecard(sch_1):page16_i1487@cls.tp_piont(chips)',
 P_PATH='@timecard_lib.timecard(sch_1):page25_i1487@cls.tp_piont(chips)',
 PATH='I1487',
 DRAWING='@TIMECARD_LIB.TIMECARD(SCH_1):PAGE16',
 PHYS_PAGE='25',
 XY='(-12350,6550)',
 ROT='0',
 VER='1',
 JEDEC_TYPE='TP010CT020B030_PTH',
 CDS_LIB='cls',
 CDS_PART_NAME='TP_PIONT-TP010CT020B030_PTH-TPA',
 BOM_IGNORE='TRUE',
 PRIM_FILE='./archive_libs/cls/tp_piont/chips/chips.prt';

PART_NAME
 TP194 'TP_PIONT-TP010CT020B030_PTH-TPA':;

SECTION_NUMBER 1
 '@TIMECARD_LIB.TIMECARD(SCH_1):PAGE16_I1488@CLS.TP_PIONT(CHIPS)':
 C_PATH='@timecard_lib.timecard(sch_1):page16_i1488@cls.tp_piont(chips)',
 P_PATH='@timecard_lib.timecard(sch_1):page25_i1488@cls.tp_piont(chips)',
 PATH='I1488',
 DRAWING='@TIMECARD_LIB.TIMECARD(SCH_1):PAGE16',
 PHYS_PAGE='25',
 XY='(-12350,6450)',
 ROT='0',
 VER='1',
 JEDEC_TYPE='TP010CT020B030_PTH',
 CDS_LIB='cls',
 CDS_PART_NAME='TP_PIONT-TP010CT020B030_PTH-TPA',
 BOM_IGNORE='TRUE',
 PRIM_FILE='./archive_libs/cls/tp_piont/chips/chips.prt';

PART_NAME
 TP195 'TP_PIONT-TP010CT020B030_PTH-TPA':;

SECTION_NUMBER 1
 '@TIMECARD_LIB.TIMECARD(SCH_1):PAGE16_I1489@CLS.TP_PIONT(CHIPS)':
 C_PATH='@timecard_lib.timecard(sch_1):page16_i1489@cls.tp_piont(chips)',
 P_PATH='@timecard_lib.timecard(sch_1):page25_i1489@cls.tp_piont(chips)',
 PATH='I1489',
 DRAWING='@TIMECARD_LIB.TIMECARD(SCH_1):PAGE16',
 PHYS_PAGE='25',
 XY='(-12350,6150)',
 ROT='0',
 VER='1',
 JEDEC_TYPE='TP010CT020B030_PTH',
 CDS_LIB='cls',
 CDS_PART_NAME='TP_PIONT-TP010CT020B030_PTH-TPA',
 BOM_IGNORE='TRUE',
 PRIM_FILE='./archive_libs/cls/tp_piont/chips/chips.prt';

PART_NAME
 TP196 'TP_PIONT-TP010CT020B030_PTH-TPA':;

SECTION_NUMBER 1
 '@TIMECARD_LIB.TIMECARD(SCH_1):PAGE16_I1490@CLS.TP_PIONT(CHIPS)':
 C_PATH='@timecard_lib.timecard(sch_1):page16_i1490@cls.tp_piont(chips)',
 P_PATH='@timecard_lib.timecard(sch_1):page25_i1490@cls.tp_piont(chips)',
 PATH='I1490',
 DRAWING='@TIMECARD_LIB.TIMECARD(SCH_1):PAGE16',
 PHYS_PAGE='25',
 XY='(-12350,6050)',
 ROT='0',
 VER='1',
 JEDEC_TYPE='TP010CT020B030_PTH',
 CDS_LIB='cls',
 CDS_PART_NAME='TP_PIONT-TP010CT020B030_PTH-TPA',
 BOM_IGNORE='TRUE',
 PRIM_FILE='./archive_libs/cls/tp_piont/chips/chips.prt';

PART_NAME
 TP199 'TP_PIONT-TP010CT020B030_PTH-TPA':;

SECTION_NUMBER 1
 '@TIMECARD_LIB.TIMECARD(SCH_1):PAGE16_I1527@CLS.TP_PIONT(CHIPS)':
 C_PATH='@timecard_lib.timecard(sch_1):page16_i1527@cls.tp_piont(chips)',
 P_PATH='@timecard_lib.timecard(sch_1):page25_i1527@cls.tp_piont(chips)',
 PATH='I1527',
 DRAWING='@TIMECARD_LIB.TIMECARD(SCH_1):PAGE16',
 PHYS_PAGE='25',
 XY='(-12350,6750)',
 ROT='0',
 VER='1',
 JEDEC_TYPE='TP010CT020B030_PTH',
 CDS_LIB='cls',
 CDS_PART_NAME='TP_PIONT-TP010CT020B030_PTH-TPA',
 BOM_IGNORE='TRUE',
 PRIM_FILE='./archive_libs/cls/tp_piont/chips/chips.prt';

PART_NAME
 TP200 'TP_PIONT-TP010CT020B030_PTH-TPA':;

SECTION_NUMBER 1
 '@TIMECARD_LIB.TIMECARD(SCH_1):PAGE16_I1528@CLS.TP_PIONT(CHIPS)':
 C_PATH='@timecard_lib.timecard(sch_1):page16_i1528@cls.tp_piont(chips)',
 P_PATH='@timecard_lib.timecard(sch_1):page25_i1528@cls.tp_piont(chips)',
 PATH='I1528',
 DRAWING='@TIMECARD_LIB.TIMECARD(SCH_1):PAGE16',
 PHYS_PAGE='25',
 XY='(-12350,6650)',
 ROT='0',
 VER='1',
 JEDEC_TYPE='TP010CT020B030_PTH',
 CDS_LIB='cls',
 CDS_PART_NAME='TP_PIONT-TP010CT020B030_PTH-TPA',
 BOM_IGNORE='TRUE',
 PRIM_FILE='./archive_libs/cls/tp_piont/chips/chips.prt';

PART_NAME
 TP201 'TP_PIONT-TP010CT020B030_PTH-TPA':;

SECTION_NUMBER 1
 '@TIMECARD_LIB.TIMECARD(SCH_1):PAGE16_I1529@CLS.TP_PIONT(CHIPS)':
 C_PATH='@timecard_lib.timecard(sch_1):page16_i1529@cls.tp_piont(chips)',
 P_PATH='@timecard_lib.timecard(sch_1):page25_i1529@cls.tp_piont(chips)',
 PATH='I1529',
 DRAWING='@TIMECARD_LIB.TIMECARD(SCH_1):PAGE16',
 PHYS_PAGE='25',
 XY='(-12350,6350)',
 ROT='0',
 VER='1',
 JEDEC_TYPE='TP010CT020B030_PTH',
 CDS_LIB='cls',
 CDS_PART_NAME='TP_PIONT-TP010CT020B030_PTH-TPA',
 BOM_IGNORE='TRUE',
 PRIM_FILE='./archive_libs/cls/tp_piont/chips/chips.prt';

PART_NAME
 TP202 'TP_PIONT-TP010CT020B030_PTH-TPA':;

SECTION_NUMBER 1
 '@TIMECARD_LIB.TIMECARD(SCH_1):PAGE16_I1530@CLS.TP_PIONT(CHIPS)':
 C_PATH='@timecard_lib.timecard(sch_1):page16_i1530@cls.tp_piont(chips)',
 P_PATH='@timecard_lib.timecard(sch_1):page25_i1530@cls.tp_piont(chips)',
 PATH='I1530',
 DRAWING='@TIMECARD_LIB.TIMECARD(SCH_1):PAGE16',
 PHYS_PAGE='25',
 XY='(-12350,6250)',
 ROT='0',
 VER='1',
 JEDEC_TYPE='TP010CT020B030_PTH',
 CDS_LIB='cls',
 CDS_PART_NAME='TP_PIONT-TP010CT020B030_PTH-TPA',
 BOM_IGNORE='TRUE',
 PRIM_FILE='./archive_libs/cls/tp_piont/chips/chips.prt';

PART_NAME
 TP203 'TP_PIONT-TP010CT020B030_PTH-TPA':;

SECTION_NUMBER 1
 '@TIMECARD_LIB.TIMECARD(SCH_1):PAGE16_I1523@CLS.TP_PIONT(CHIPS)':
 C_PATH='@timecard_lib.timecard(sch_1):page16_i1523@cls.tp_piont(chips)',
 P_PATH='@timecard_lib.timecard(sch_1):page25_i1523@cls.tp_piont(chips)',
 PATH='I1523',
 DRAWING='@TIMECARD_LIB.TIMECARD(SCH_1):PAGE16',
 PHYS_PAGE='25',
 XY='(-12350,5950)',
 ROT='0',
 VER='1',
 JEDEC_TYPE='TP010CT020B030_PTH',
 CDS_LIB='cls',
 CDS_PART_NAME='TP_PIONT-TP010CT020B030_PTH-TPA',
 BOM_IGNORE='TRUE',
 PRIM_FILE='./archive_libs/cls/tp_piont/chips/chips.prt';

PART_NAME
 TP204 'TP_PIONT-TP010CT020B030_PTH-TPA':;

SECTION_NUMBER 1
 '@TIMECARD_LIB.TIMECARD(SCH_1):PAGE16_I1524@CLS.TP_PIONT(CHIPS)':
 C_PATH='@timecard_lib.timecard(sch_1):page16_i1524@cls.tp_piont(chips)',
 P_PATH='@timecard_lib.timecard(sch_1):page25_i1524@cls.tp_piont(chips)',
 PATH='I1524',
 DRAWING='@TIMECARD_LIB.TIMECARD(SCH_1):PAGE16',
 PHYS_PAGE='25',
 XY='(-12350,5850)',
 ROT='0',
 VER='1',
 JEDEC_TYPE='TP010CT020B030_PTH',
 CDS_LIB='cls',
 CDS_PART_NAME='TP_PIONT-TP010CT020B030_PTH-TPA',
 BOM_IGNORE='TRUE',
 PRIM_FILE='./archive_libs/cls/tp_piont/chips/chips.prt';

PART_NAME
 U1 'MP5022CGQV_Z_QFN22-G220-10510-A':;

SECTION_NUMBER 1
 '@TIMECARD_LIB.TIMECARD(SCH_1):PAGE15_I212@STDLOGIC.MP5022CGQV_Z_QFN22(CHIPS)':
 C_PATH='@timecard_lib.timecard(sch_1):page15_i212@stdlogic.mp5022cgqv_z_qfn22(c~
hips)',
 P_PATH='@timecard_lib.timecard(sch_1):page27_i212@stdlogic.mp5022cgqv_z_qfn22(c~
hips)',
 PATH='I212',
 DRAWING='@TIMECARD_LIB.TIMECARD(SCH_1):PAGE15',
 PHYS_PAGE='27',
 XY='(-6650,9100)',
 ROT='0',
 VER='1',
 CDS_LIB='stdlogic',
 CDS_PART_NAME='MP5022CGQV_Z_QFN22-G220-10510-A',
 CLS_PN='G220-10510-01',
 PART_NUMBER='MP5022CGQV-Z',
 PRIM_FILE='./archive_libs/stdlogic/mp5022cgqv_z_qfn22/chips/chips.prt';

PART_NAME
 U2 'G220_10198_01-G223-10197-01':;

SECTION_NUMBER 1
 '@TIMECARD_LIB.TIMECARD(SCH_1):PAGE3_I100@STDLOGIC.G220_10198_01(CHIPS)':
 C_PATH='@timecard_lib.timecard(sch_1):page3_i100@stdlogic.g220_10198_01(chips)',
 P_PATH='@timecard_lib.timecard(sch_1):page9_i100@stdlogic.g220_10198_01(chips)',
 PATH='I100',
 DRAWING='@TIMECARD_LIB.TIMECARD(SCH_1):PAGE3',
 PHYS_PAGE='9',
 XY='(-6700,2400)',
 ROT='0',
 VER='1',
 CDS_LIB='stdlogic',
 CDS_PART_NAME='G220_10198_01-G223-10197-01',
 NO_ASSY='TRUE',
 CLS_PN='G223-10197-01',
 PART_NUMBER='PCA9510AD,118',
 PRIM_FILE='./archive_libs/stdlogic/g220_10198_01/chips/chips.prt';

PART_NAME
 U3 '74LVC1G07_SC70_5-G220-10017-01':;

SECTION_NUMBER 1
 '@TIMECARD_LIB.TIMECARD(SCH_1):PAGE3_I134@STDLOGIC.74LVC1G07_SC70_5(CHIPS)':
 C_PATH='@timecard_lib.timecard(sch_1):page3_i134@stdlogic.\74lvc1g07_sc70_5\(ch~
ips)',
 P_PATH='@timecard_lib.timecard(sch_1):page9_i134@stdlogic.\74lvc1g07_sc70_5\(ch~
ips)',
 PATH='I134',
 DRAWING='@TIMECARD_LIB.TIMECARD(SCH_1):PAGE3',
 PHYS_PAGE='9',
 XY='(-900,7300)',
 ROT='0',
 VER='1',
 LOCATION='U3',
 CDS_LIB='stdlogic',
 CDS_PART_NAME='74LVC1G07_SC70_5-G220-10017-01',
 CLS_PN='G220-10017-01',
 PART_NUMBER='SN74LVC1G07DCKRG4',
 PRIM_FILE='./archive_libs/stdlogic/74lvc1g07_sc70_5/chips/chips.prt';

SECTION_NUMBER 2
 '@TIMECARD_LIB.TIMECARD(SCH_1):PAGE3_I135@STDLOGIC.74LVC1G07_SC70_5(CHIPS)':
 C_PATH='@timecard_lib.timecard(sch_1):page3_i135@stdlogic.\74lvc1g07_sc70_5\(ch~
ips)',
 P_PATH='@timecard_lib.timecard(sch_1):page9_i135@stdlogic.\74lvc1g07_sc70_5\(ch~
ips)',
 PATH='I135',
 DRAWING='@TIMECARD_LIB.TIMECARD(SCH_1):PAGE3',
 PHYS_PAGE='9',
 XY='(-900,6000)',
 ROT='0',
 VER='2',
 LOCATION='U3',
 CDS_LIB='stdlogic',
 CDS_PART_NAME='74LVC1G07_SC70_5-G220-10017-01',
 CLS_PN='G220-10017-01',
 PART_NUMBER='SN74LVC1G07DCKRG4',
 PRIM_FILE='./archive_libs/stdlogic/74lvc1g07_sc70_5/chips/chips.prt';

PART_NAME
 U4 'PCA9546APW_TSSOP16-G223-10280-A':;

SECTION_NUMBER 1
 '@TIMECARD_LIB.TIMECARD(SCH_1):PAGE5_I33@INTERFACE.PCA9546APW_TSSOP16(CHIPS)':
 C_PATH='@timecard_lib.timecard(sch_1):page5_i33@interface.pca9546apw_tssop16(ch~
ips)',
 P_PATH='@timecard_lib.timecard(sch_1):page16_i33@interface.pca9546apw_tssop16(c~
hips)',
 PATH='I33',
 DRAWING='@TIMECARD_LIB.TIMECARD(SCH_1):PAGE5',
 PHYS_PAGE='16',
 XY='(-6550,10900)',
 ROT='0',
 VER='1',
 CDS_LIB='interface',
 CDS_PART_NAME='PCA9546APW_TSSOP16-G223-10280-A',
 CLS_PN='G223-10280-01',
 PART_NUMBER='TCA9546APWR',
 PRIM_FILE='./archive_libs/interface/pca9546apw_tssop16/chips/chips.prt';

SECTION_NUMBER 2
 '@TIMECARD_LIB.TIMECARD(SCH_1):PAGE5_I54@INTERFACE.PCA9546APW_TSSOP16(CHIPS)':
 C_PATH='@timecard_lib.timecard(sch_1):page5_i54@interface.pca9546apw_tssop16(ch~
ips)',
 P_PATH='@timecard_lib.timecard(sch_1):page16_i54@interface.pca9546apw_tssop16(c~
hips)',
 PATH='I54',
 DRAWING='@TIMECARD_LIB.TIMECARD(SCH_1):PAGE5',
 PHYS_PAGE='16',
 XY='(-6450,9150)',
 ROT='0',
 VER='2',
 CDS_LIB='interface',
 CDS_PART_NAME='PCA9546APW_TSSOP16-G223-10280-A',
 CLS_PN='G223-10280-01',
 PRIM_FILE='./archive_libs/interface/pca9546apw_tssop16/chips/chips.prt';

PART_NAME
 U5 'TPS54824RNVR_VQFN18-G220-10657A':;

SECTION_NUMBER 1
 '@TIMECARD_LIB.TIMECARD(SCH_1):PAGE516_I42@STDLOGIC.TPS54824RNVR_VQFN18(CHIPS)':
 C_PATH='@timecard_lib.timecard(sch_1):page516_i42@stdlogic.tps54824rnvr_vqfn18(~
chips)',
 P_PATH='@timecard_lib.timecard(sch_1):page32_i42@stdlogic.tps54824rnvr_vqfn18(c~
hips)',
 PATH='I42',
 DRAWING='@TIMECARD_LIB.TIMECARD(SCH_1):PAGE516',
 PHYS_PAGE='32',
 XY='(-9450,7400)',
 ROT='0',
 VER='1',
 CDS_LIB='stdlogic',
 CDS_PART_NAME='TPS54824RNVR_VQFN18-G220-10657A',
 CLS_PN='G220-10657-01',
 VALUE='TPS54424RNVT',
 PRIM_FILE='./archive_libs/stdlogic/tps54824rnvr_vqfn18/chips/chips.prt';

PART_NAME
 U6 'TPS54824RNVR_VQFN18-G220-10657A':;

SECTION_NUMBER 1
 '@TIMECARD_LIB.TIMECARD(SCH_1):PAGE517_I42@STDLOGIC.TPS54824RNVR_VQFN18(CHIPS)':
 C_PATH='@timecard_lib.timecard(sch_1):page517_i42@stdlogic.tps54824rnvr_vqfn18(~
chips)',
 P_PATH='@timecard_lib.timecard(sch_1):page28_i42@stdlogic.tps54824rnvr_vqfn18(c~
hips)',
 PATH='I42',
 DRAWING='@TIMECARD_LIB.TIMECARD(SCH_1):PAGE517',
 PHYS_PAGE='28',
 XY='(-9200,6600)',
 ROT='0',
 VER='1',
 CDS_LIB='stdlogic',
 CDS_PART_NAME='TPS54824RNVR_VQFN18-G220-10657A',
 CLS_PN='G220-10657-01',
 VALUE='TPS54424RNVT',
 PRIM_FILE='./archive_libs/stdlogic/tps54824rnvr_vqfn18/chips/chips.prt';

PART_NAME
 U7 'AT24MAC402_SOT23_5-A221-00002-A':;

SECTION_NUMBER 1
 '@TIMECARD_LIB.TIMECARD(SCH_1):PAGE5_I89@MEMORY.AT24MAC402_SOT23_5(CHIPS)':
 C_PATH='@timecard_lib.timecard(sch_1):page5_i89@memory.at24mac402_sot23_5(chips~
)',
 P_PATH='@timecard_lib.timecard(sch_1):page16_i89@memory.at24mac402_sot23_5(chip~
s)',
 PATH='I89',
 DRAWING='@TIMECARD_LIB.TIMECARD(SCH_1):PAGE5',
 PHYS_PAGE='16',
 XY='(-5950,6050)',
 ROT='0',
 VER='1',
 LOCATION='U7',
 CDS_LIB='memory',
 CDS_PART_NAME='AT24MAC402_SOT23_5-A221-00002-A',
 CLS_PN='A221-00002-FB',
 VALUE='AT24MAC602-STUM-T',
 PRIM_FILE='./archive_libs/memory/at24mac402_sot23_5/chips/chips.prt';

PART_NAME
 U8 'LM75BDP_TSSOP8-G220-10215-01':;

SECTION_NUMBER 1
 '@TIMECARD_LIB.TIMECARD(SCH_1):PAGE6_I34@INTERFACE.LM75BDP_TSSOP8(CHIPS)':
 C_PATH='@timecard_lib.timecard(sch_1):page6_i34@interface.lm75bdp_tssop8(chips)~
',
 P_PATH='@timecard_lib.timecard(sch_1):page17_i34@interface.lm75bdp_tssop8(chips~
)',
 PATH='I34',
 DRAWING='@TIMECARD_LIB.TIMECARD(SCH_1):PAGE6',
 PHYS_PAGE='17',
 XY='(-2700,7800)',
 ROT='0',
 VER='1',
 CDS_LIB='interface',
 CDS_PART_NAME='LM75BDP_TSSOP8-G220-10215-01',
 CLS_PN='G220-10215-01',
 PART_NUMBER='LM75BDP,118',
 PRIM_FILE='./archive_libs/interface/lm75bdp_tssop8/chips/chips.prt';

SECTION_NUMBER 2
 '@TIMECARD_LIB.TIMECARD(SCH_1):PAGE6_I38@INTERFACE.LM75BDP_TSSOP8(CHIPS)':
 C_PATH='@timecard_lib.timecard(sch_1):page6_i38@interface.lm75bdp_tssop8(chips)~
',
 P_PATH='@timecard_lib.timecard(sch_1):page17_i38@interface.lm75bdp_tssop8(chips~
)',
 PATH='I38',
 DRAWING='@TIMECARD_LIB.TIMECARD(SCH_1):PAGE6',
 PHYS_PAGE='17',
 XY='(-1050,7100)',
 ROT='5',
 VER='2',
 CDS_LIB='interface',
 CDS_PART_NAME='LM75BDP_TSSOP8-G220-10215-01',
 CLS_PN='G220-10215-01',
 PRIM_FILE='./archive_libs/interface/lm75bdp_tssop8/chips/chips.prt';

PART_NAME
 U9 'CL1001485A-G122-00019-01':;

SECTION_NUMBER 1
 '@TIMECARD_LIB.TIMECARD(SCH_1):PAGE527_I4@OTHER.CL1001485A(CHIPS)':
 C_PATH='@timecard_lib.timecard(sch_1):page527_i4@other.cl1001485a(chips)',
 P_PATH='@timecard_lib.timecard(sch_1):page21_i4@other.cl1001485a(chips)',
 PATH='I4',
 DRAWING='@TIMECARD_LIB.TIMECARD(SCH_1):PAGE527',
 PHYS_PAGE='21',
 XY='(-10300,-150)',
 ROT='7',
 VER='1',
 CDS_LIB='other',
 CDS_PART_NAME='CL1001485A-G122-00019-01',
 NO_ASSY='TRUE',
 CLS_PN='G122-00019-01',
 PART_NUMBER='SRV05-4ATCT',
 PRIM_FILE='./archive_libs/other/cl1001485a/chips/chips.prt';

PART_NAME
 U10 'CL5003148A-G220-10019-01':;

SECTION_NUMBER 1
 '@TIMECARD_LIB.TIMECARD(SCH_1):PAGE527_I147@STDLOGIC.CL5003148A(CHIPS)':
 C_PATH='@timecard_lib.timecard(sch_1):page527_i147@stdlogic.cl5003148a(chips)',
 P_PATH='@timecard_lib.timecard(sch_1):page21_i147@stdlogic.cl5003148a(chips)',
 PATH='I147',
 DRAWING='@TIMECARD_LIB.TIMECARD(SCH_1):PAGE527',
 PHYS_PAGE='21',
 XY='(-2100,4000)',
 ROT='0',
 VER='1',
 CDS_LIB='stdlogic',
 CDS_PART_NAME='CL5003148A-G220-10019-01',
 NO_ASSY='TRUE',
 CLS_PN='G220-10019-01',
 PRIM_FILE='./archive_libs/stdlogic/cl5003148a/chips/chips.prt';

SECTION_NUMBER 2
 '@TIMECARD_LIB.TIMECARD(SCH_1):PAGE527_I146@STDLOGIC.CL5003148A(CHIPS)':
 C_PATH='@timecard_lib.timecard(sch_1):page527_i146@stdlogic.cl5003148a(chips)',
 P_PATH='@timecard_lib.timecard(sch_1):page21_i146@stdlogic.cl5003148a(chips)',
 PATH='I146',
 DRAWING='@TIMECARD_LIB.TIMECARD(SCH_1):PAGE527',
 PHYS_PAGE='21',
 XY='(-1750,3200)',
 ROT='0',
 VER='2',
 CDS_LIB='stdlogic',
 CDS_PART_NAME='CL5003148A-G220-10019-01',
 NO_ASSY='TRUE',
 CLS_PN='G220-10019-01',
 PART_NUMBER='SN74LVC1G32DCKR',
 PRIM_FILE='./archive_libs/stdlogic/cl5003148a/chips/chips.prt';

PART_NAME
 U11 'TS3USB3031RMGR_WQFN12-G220-103A':;

SECTION_NUMBER 1
 '@TIMECARD_LIB.TIMECARD(SCH_1):PAGE527_I108@STDLOGIC.TS3USB3031RMGR_WQFN12(CHIPS)':
 C_PATH='@timecard_lib.timecard(sch_1):page527_i108@stdlogic.ts3usb3031rmgr_wqfn~
12(chips)',
 P_PATH='@timecard_lib.timecard(sch_1):page21_i108@stdlogic.ts3usb3031rmgr_wqfn1~
2(chips)',
 PATH='I108',
 DRAWING='@TIMECARD_LIB.TIMECARD(SCH_1):PAGE527',
 PHYS_PAGE='21',
 XY='(-3300,950)',
 ROT='0',
 VER='1',
 CDS_LIB='stdlogic',
 CDS_PART_NAME='TS3USB3031RMGR_WQFN12-G220-103A',
 NO_ASSY='TRUE',
 CLS_PN='G220-10368-01',
 VALUE='TS3USB3031RMGR',
 PRIM_FILE='./archive_libs/stdlogic/ts3usb3031rmgr_wqfn12/chips/chips.prt';

PART_NAME
 U12 'TPS2051BDBVT_SOT23_5-G220-1033A':;

SECTION_NUMBER 1
 '@TIMECARD_LIB.TIMECARD(SCH_1):PAGE527_I79@STDLOGIC.TPS2051BDBVT_SOT23_5(CHIPS)':
 C_PATH='@timecard_lib.timecard(sch_1):page527_i79@stdlogic.tps2051bdbvt_sot23_5~
(chips)',
 P_PATH='@timecard_lib.timecard(sch_1):page21_i79@stdlogic.tps2051bdbvt_sot23_5(~
chips)',
 PATH='I79',
 DRAWING='@TIMECARD_LIB.TIMECARD(SCH_1):PAGE527',
 VENDOR_PN='TPS2051BDBVT',
 PHYS_PAGE='21',
 XY='(225,4100)',
 ROT='0',
 VER='1',
 CDS_LIB='stdlogic',
 CDS_PART_NAME='TPS2051BDBVT_SOT23_5-G220-1033A',
 CLS_PN='G220-10338-01',
 PRIM_FILE='./archive_libs/stdlogic/tps2051bdbvt_sot23_5/chips/chips.prt';

SECTION_NUMBER 2
 '@TIMECARD_LIB.TIMECARD(SCH_1):PAGE527_I78@STDLOGIC.TPS2051BDBVT_SOT23_5(CHIPS)':
 C_PATH='@timecard_lib.timecard(sch_1):page527_i78@stdlogic.tps2051bdbvt_sot23_5~
(chips)',
 P_PATH='@timecard_lib.timecard(sch_1):page21_i78@stdlogic.tps2051bdbvt_sot23_5(~
chips)',
 PATH='I78',
 DRAWING='@TIMECARD_LIB.TIMECARD(SCH_1):PAGE527',
 VENDOR_PN='TPS2051BDBVT',
 PHYS_PAGE='21',
 XY='(250,3500)',
 ROT='0',
 VER='2',
 CDS_LIB='stdlogic',
 CDS_PART_NAME='TPS2051BDBVT_SOT23_5-G220-1033A',
 CLS_PN='G220-10338-01',
 PRIM_FILE='./archive_libs/stdlogic/tps2051bdbvt_sot23_5/chips/chips.prt';

PART_NAME
 U13 '74HCT2G125DP_TSSOP8-G220-00055A':;

SECTION_NUMBER 1
 '@TIMECARD_LIB.TIMECARD(SCH_1):PAGE12_I204@STDLOGIC.74HCT2G125DP_TSSOP8(CHIPS)':
 C_PATH='@timecard_lib.timecard(sch_1):page12_i204@stdlogic.\74hct2g125dp_tssop8~
\(chips)',
 P_PATH='@timecard_lib.timecard(sch_1):page23_i204@stdlogic.\74hct2g125dp_tssop8~
\(chips)',
 PATH='I204',
 DRAWING='@TIMECARD_LIB.TIMECARD(SCH_1):PAGE12',
 PHYS_PAGE='23',
 XY='(-9550,9250)',
 ROT='0',
 VER='1',
 LOCATION='U13',
 CDS_LIB='stdlogic',
 CDS_PART_NAME='74HCT2G125DP_TSSOP8-G220-00055A',
 CLS_PN='G220-00055-01',
 VALUE='NC7WV125K8X',
 PRIM_FILE='./archive_libs/stdlogic/74hct2g125dp_tssop8/chips/chips.prt';

PART_NAME
 U14 '74HCT2G125DP_TSSOP8-G220-00055A':;

SECTION_NUMBER 1
 '@TIMECARD_LIB.TIMECARD(SCH_1):PAGE12_I226@STDLOGIC.74HCT2G125DP_TSSOP8(CHIPS)':
 C_PATH='@timecard_lib.timecard(sch_1):page12_i226@stdlogic.\74hct2g125dp_tssop8~
\(chips)',
 P_PATH='@timecard_lib.timecard(sch_1):page23_i226@stdlogic.\74hct2g125dp_tssop8~
\(chips)',
 PATH='I226',
 DRAWING='@TIMECARD_LIB.TIMECARD(SCH_1):PAGE12',
 PHYS_PAGE='23',
 XY='(-9500,7100)',
 ROT='0',
 VER='1',
 LOCATION='U14',
 CDS_LIB='stdlogic',
 CDS_PART_NAME='74HCT2G125DP_TSSOP8-G220-00055A',
 CLS_PN='G220-00055-01',
 VALUE='NC7WV125K8X',
 PRIM_FILE='./archive_libs/stdlogic/74hct2g125dp_tssop8/chips/chips.prt';

PART_NAME
 U15 '74HCT2G125DP_TSSOP8-G220-00055A':;

SECTION_NUMBER 1
 '@TIMECARD_LIB.TIMECARD(SCH_1):PAGE12_I255@STDLOGIC.74HCT2G125DP_TSSOP8(CHIPS)':
 C_PATH='@timecard_lib.timecard(sch_1):page12_i255@stdlogic.\74hct2g125dp_tssop8~
\(chips)',
 P_PATH='@timecard_lib.timecard(sch_1):page23_i255@stdlogic.\74hct2g125dp_tssop8~
\(chips)',
 PATH='I255',
 DRAWING='@TIMECARD_LIB.TIMECARD(SCH_1):PAGE12',
 PHYS_PAGE='23',
 XY='(-9500,4950)',
 ROT='0',
 VER='1',
 LOCATION='U15',
 CDS_LIB='stdlogic',
 CDS_PART_NAME='74HCT2G125DP_TSSOP8-G220-00055A',
 CLS_PN='G220-00055-01',
 VALUE='NC7WV125K8X',
 PRIM_FILE='./archive_libs/stdlogic/74hct2g125dp_tssop8/chips/chips.prt';

PART_NAME
 U16 '74HCT2G125DP_TSSOP8-G220-00055A':;

SECTION_NUMBER 1
 '@TIMECARD_LIB.TIMECARD(SCH_1):PAGE12_I273@STDLOGIC.74HCT2G125DP_TSSOP8(CHIPS)':
 C_PATH='@timecard_lib.timecard(sch_1):page12_i273@stdlogic.\74hct2g125dp_tssop8~
\(chips)',
 P_PATH='@timecard_lib.timecard(sch_1):page23_i273@stdlogic.\74hct2g125dp_tssop8~
\(chips)',
 PATH='I273',
 DRAWING='@TIMECARD_LIB.TIMECARD(SCH_1):PAGE12',
 PHYS_PAGE='23',
 XY='(-9450,2800)',
 ROT='0',
 VER='1',
 LOCATION='U16',
 CDS_LIB='stdlogic',
 CDS_PART_NAME='74HCT2G125DP_TSSOP8-G220-00055A',
 CLS_PN='G220-00055-01',
 VALUE='NC7WV125K8X',
 PRIM_FILE='./archive_libs/stdlogic/74hct2g125dp_tssop8/chips/chips.prt';

PART_NAME
 U17 'CL1001485A-G122-00019-01':;

SECTION_NUMBER 1
 '@TIMECARD_LIB.TIMECARD(SCH_1):PAGE524_I3@OTHER.CL1001485A(CHIPS)':
 C_PATH='@timecard_lib.timecard(sch_1):page524_i3@other.cl1001485a(chips)',
 P_PATH='@timecard_lib.timecard(sch_1):page24_i3@other.cl1001485a(chips)',
 PATH='I3',
 DRAWING='@TIMECARD_LIB.TIMECARD(SCH_1):PAGE524',
 PHYS_PAGE='24',
 XY='(-11900,8900)',
 ROT='7',
 VER='1',
 CDS_LIB='other',
 CDS_PART_NAME='CL1001485A-G122-00019-01',
 CLS_PN='G122-00019-01',
 PART_NUMBER='SRV05-4ATCT',
 PRIM_FILE='./archive_libs/other/cl1001485a/chips/chips.prt';

PART_NAME
 U18 'FT4232HL_REEL_QFP64-G223-10282A':;

SECTION_NUMBER 1
 '@TIMECARD_LIB.TIMECARD(SCH_1):PAGE524_I64@INTERFACE.FT4232HL_REEL_QFP64(CHIPS)':
 C_PATH='@timecard_lib.timecard(sch_1):page524_i64@interface.ft4232hl_reel_qfp64~
(chips)',
 P_PATH='@timecard_lib.timecard(sch_1):page24_i64@interface.ft4232hl_reel_qfp64(~
chips)',
 PATH='I64',
 DRAWING='@TIMECARD_LIB.TIMECARD(SCH_1):PAGE524',
 PHYS_PAGE='24',
 XY='(-7900,11550)',
 ROT='0',
 VER='1',
 CDS_LIB='interface',
 CDS_PART_NAME='FT4232HL_REEL_QFP64-G223-10282A',
 CLS_PN='G223-10282-01',
 VALUE='FT4232HL-REEL',
 PRIM_FILE='./archive_libs/interface/ft4232hl_reel_qfp64/chips/chips.prt';

PART_NAME
 U19 '24LC16BT_I_ST_TSSOP8-G221-1017A':;

SECTION_NUMBER 1
 '@TIMECARD_LIB.TIMECARD(SCH_1):PAGE5_I151@MEMORY.24LC16BT_I_ST_TSSOP8(CHIPS)':
 C_PATH='@timecard_lib.timecard(sch_1):page5_i151@memory.\24lc16bt_i_st_tssop8\(~
chips)',
 P_PATH='@timecard_lib.timecard(sch_1):page16_i151@memory.\24lc16bt_i_st_tssop8\~
(chips)',
 PATH='I151',
 DRAWING='@TIMECARD_LIB.TIMECARD(SCH_1):PAGE5',
 PHYS_PAGE='16',
 XY='(-5950,4700)',
 ROT='0',
 VER='1',
 CDS_LIB='memory',
 CDS_PART_NAME='24LC16BT_I_ST_TSSOP8-G221-1017A',
 CLS_PN='G221-10176-01',
 PART_NUMBER='24LC64T',
 PRIM_FILE='./archive_libs/memory/24lc16bt_i_st_tssop8/chips/chips.prt';

SECTION_NUMBER 2
 '@TIMECARD_LIB.TIMECARD(SCH_1):PAGE5_I148@MEMORY.24LC16BT_I_ST_TSSOP8(CHIPS)':
 C_PATH='@timecard_lib.timecard(sch_1):page5_i148@memory.\24lc16bt_i_st_tssop8\(~
chips)',
 P_PATH='@timecard_lib.timecard(sch_1):page16_i148@memory.\24lc16bt_i_st_tssop8\~
(chips)',
 PATH='I148',
 DRAWING='@TIMECARD_LIB.TIMECARD(SCH_1):PAGE5',
 PHYS_PAGE='16',
 XY='(-2550,4450)',
 ROT='0',
 VER='2',
 CDS_LIB='memory',
 CDS_PART_NAME='24LC16BT_I_ST_TSSOP8-G221-1017A',
 CLS_PN='G221-10176-01',
 PRIM_FILE='./archive_libs/memory/24lc16bt_i_st_tssop8/chips/chips.prt';

PART_NAME
 U20 'ISL80101IRAJZ_DFN10-G222-10136A':;

SECTION_NUMBER 1
 '@TIMECARD_LIB.TIMECARD(SCH_1):PAGE68_I6@ANALOG.ISL80101IRAJZ_DFN10(CHIPS)':
 C_PATH='@timecard_lib.timecard(sch_1):page68_i6@analog.isl80101irajz_dfn10(chip~
s)',
 P_PATH='@timecard_lib.timecard(sch_1):page30_i6@analog.isl80101irajz_dfn10(chip~
s)',
 PATH='I6',
 DRAWING='@TIMECARD_LIB.TIMECARD(SCH_1):PAGE68',
 PHYS_PAGE='30',
 XY='(-9900,8350)',
 ROT='0',
 VER='1',
 CDS_LIB='analog',
 CDS_PART_NAME='ISL80101IRAJZ_DFN10-G222-10136A',
 CLS_PN='G222-10136-01',
 PART_NUMBER='ISL80101IRAJZ-T',
 PRIM_FILE='./archive_libs/analog/isl80101irajz_dfn10/chips/chips.prt';

PART_NAME
 U21 'ISL80101IRAJZ_DFN10-G222-10136A':;

SECTION_NUMBER 1
 '@TIMECARD_LIB.TIMECARD(SCH_1):PAGE68_I52@ANALOG.ISL80101IRAJZ_DFN10(CHIPS)':
 C_PATH='@timecard_lib.timecard(sch_1):page68_i52@analog.isl80101irajz_dfn10(chi~
ps)',
 P_PATH='@timecard_lib.timecard(sch_1):page30_i52@analog.isl80101irajz_dfn10(chi~
ps)',
 PATH='I52',
 DRAWING='@TIMECARD_LIB.TIMECARD(SCH_1):PAGE68',
 PHYS_PAGE='30',
 XY='(-9850,3450)',
 ROT='0',
 VER='1',
 CDS_LIB='analog',
 CDS_PART_NAME='ISL80101IRAJZ_DFN10-G222-10136A',
 CLS_PN='G222-10136-01',
 PART_NUMBER='ISL80101IRAJZ-T',
 PRIM_FILE='./archive_libs/analog/isl80101irajz_dfn10/chips/chips.prt';

PART_NAME
 U22 'NCP45560IMNTWG_H_DFN12-G222-10A':;

SECTION_NUMBER 1
 '@TIMECARD_LIB.TIMECARD(SCH_1):PAGE515_I82@ANALOG.NCP45560IMNTWG_H_DFN12(CHIPS)':
 C_PATH='@timecard_lib.timecard(sch_1):page515_i82@analog.ncp45560imntwg_h_dfn12~
(chips)',
 P_PATH='@timecard_lib.timecard(sch_1):page31_i82@analog.ncp45560imntwg_h_dfn12(~
chips)',
 PATH='I82',
 DRAWING='@TIMECARD_LIB.TIMECARD(SCH_1):PAGE515',
 PHYS_PAGE='31',
 XY='(-5850,6700)',
 ROT='0',
 VER='1',
 CDS_LIB='analog',
 CDS_PART_NAME='NCP45560IMNTWG_H_DFN12-G222-10A',
 CLS_PN='G222-10203-01',
 PART_NUMBER='NCP45560-H',
 PRIM_FILE='./archive_libs/analog/ncp45560imntwg_h_dfn12/chips/chips.prt';

SECTION_NUMBER 2
 '@TIMECARD_LIB.TIMECARD(SCH_1):PAGE515_I76@ANALOG.NCP45560IMNTWG_H_DFN12(CHIPS)':
 C_PATH='@timecard_lib.timecard(sch_1):page515_i76@analog.ncp45560imntwg_h_dfn12~
(chips)',
 P_PATH='@timecard_lib.timecard(sch_1):page31_i76@analog.ncp45560imntwg_h_dfn12(~
chips)',
 PATH='I76',
 DRAWING='@TIMECARD_LIB.TIMECARD(SCH_1):PAGE515',
 PHYS_PAGE='31',
 XY='(-5700,5050)',
 ROT='0',
 VER='2',
 CDS_LIB='analog',
 CDS_PART_NAME='NCP45560IMNTWG_H_DFN12-G222-10A',
 CLS_PN='G222-10203-01',
 PRIM_FILE='./archive_libs/analog/ncp45560imntwg_h_dfn12/chips/chips.prt';

PART_NAME
 U23 'MT25QL128ABA1ESE_SOP8-G221-102A':;

SECTION_NUMBER 1
 '@TIMECARD_LIB.TIMECARD(SCH_1):PAGE127_I456@MEMORY.MT25QL128ABA1ESE_SOP8(CHIPS)':
 C_PATH='@timecard_lib.timecard(sch_1):page127_i456@memory.mt25ql128aba1ese_sop8~
(chips)',
 P_PATH='@timecard_lib.timecard(sch_1):page10_i456@memory.mt25ql128aba1ese_sop8(~
chips)',
 PATH='I456',
 DRAWING='@TIMECARD_LIB.TIMECARD(SCH_1):PAGE127',
 PHYS_PAGE='10',
 XY='(-6100,550)',
 ROT='0',
 VER='1',
 CDS_LIB='memory',
 CDS_PART_NAME='MT25QL128ABA1ESE_SOP8-G221-102A',
 CLS_PN='G221-10224-01',
 VALUE='MT25QL128ABA1ESE-0SIT',
 PRIM_FILE='./archive_libs/memory/mt25ql128aba1ese_sop8/chips/chips.prt';

PART_NAME
 U24 'XC7A200T_2FBG484C_FBG484-G240-A':;

SECTION_NUMBER 1
 '@TIMECARD_LIB.TIMECARD(SCH_1):PAGE127_I232@PLD.XC7A200T_2FBG484C_FBG484(CHIPS)':
 C_PATH='@timecard_lib.timecard(sch_1):page127_i232@pld.xc7a200t_2fbg484c_fbg484~
(chips)',
 P_PATH='@timecard_lib.timecard(sch_1):page10_i232@pld.xc7a200t_2fbg484c_fbg484(~
chips)',
 PATH='I232',
 DRAWING='@TIMECARD_LIB.TIMECARD(SCH_1):PAGE127',
 PHYS_PAGE='10',
 XY='(-8550,7950)',
 ROT='0',
 VER='1',
 CDS_LIB='pld',
 CDS_PART_NAME='XC7A200T_2FBG484C_FBG484-G240-A',
 CLS_PN='G240-10069-01',
 VALUE='XC7A100T-1FGG484I',
 PRIM_FILE='./archive_libs/pld/xc7a200t_2fbg484c_fbg484/chips/chips.prt';

SECTION_NUMBER 2
 '@TIMECARD_LIB.TIMECARD(SCH_1):PAGE161_I2@PLD.XC7A200T_2FBG484C_FBG484(CHIPS)':
 C_PATH='@timecard_lib.timecard(sch_1):page161_i2@pld.xc7a200t_2fbg484c_fbg484(c~
hips)',
 P_PATH='@timecard_lib.timecard(sch_1):page11_i2@pld.xc7a200t_2fbg484c_fbg484(ch~
ips)',
 PATH='I2',
 DRAWING='@TIMECARD_LIB.TIMECARD(SCH_1):PAGE161',
 PHYS_PAGE='11',
 XY='(-9500,8650)',
 ROT='0',
 VER='2',
 CDS_LIB='pld',
 CDS_PART_NAME='XC7A200T_2FBG484C_FBG484-G240-A',
 CLS_PN='G240-10069-01',
 PRIM_FILE='./archive_libs/pld/xc7a200t_2fbg484c_fbg484/chips/chips.prt';

SECTION_NUMBER 3
 '@TIMECARD_LIB.TIMECARD(SCH_1):PAGE162_I228@PLD.XC7A200T_2FBG484C_FBG484(CHIPS)':
 C_PATH='@timecard_lib.timecard(sch_1):page162_i228@pld.xc7a200t_2fbg484c_fbg484~
(chips)',
 P_PATH='@timecard_lib.timecard(sch_1):page12_i228@pld.xc7a200t_2fbg484c_fbg484(~
chips)',
 PATH='I228',
 DRAWING='@TIMECARD_LIB.TIMECARD(SCH_1):PAGE162',
 PHYS_PAGE='12',
 XY='(-9150,7450)',
 ROT='0',
 VER='3',
 CDS_LIB='pld',
 CDS_PART_NAME='XC7A200T_2FBG484C_FBG484-G240-A',
 CLS_PN='G240-10069-01',
 VALUE='XC7A100T-1FGG484I',
 PRIM_FILE='./archive_libs/pld/xc7a200t_2fbg484c_fbg484/chips/chips.prt';

SECTION_NUMBER 4
 '@TIMECARD_LIB.TIMECARD(SCH_1):PAGE163_I1@PLD.XC7A200T_2FBG484C_FBG484(CHIPS)':
 C_PATH='@timecard_lib.timecard(sch_1):page163_i1@pld.xc7a200t_2fbg484c_fbg484(c~
hips)',
 P_PATH='@timecard_lib.timecard(sch_1):page13_i1@pld.xc7a200t_2fbg484c_fbg484(ch~
ips)',
 PATH='I1',
 DRAWING='@TIMECARD_LIB.TIMECARD(SCH_1):PAGE163',
 PHYS_PAGE='13',
 XY='(-9800,8050)',
 ROT='0',
 VER='4',
 CDS_LIB='pld',
 CDS_PART_NAME='XC7A200T_2FBG484C_FBG484-G240-A',
 CLS_PN='G240-10069-01',
 VALUE='XC7A100T-1FGG484I',
 PRIM_FILE='./archive_libs/pld/xc7a200t_2fbg484c_fbg484/chips/chips.prt';

SECTION_NUMBER 5
 '@TIMECARD_LIB.TIMECARD(SCH_1):PAGE164_I138@PLD.XC7A200T_2FBG484C_FBG484(CHIPS)':
 C_PATH='@timecard_lib.timecard(sch_1):page164_i138@pld.xc7a200t_2fbg484c_fbg484~
(chips)',
 P_PATH='@timecard_lib.timecard(sch_1):page14_i138@pld.xc7a200t_2fbg484c_fbg484(~
chips)',
 PATH='I138',
 DRAWING='@TIMECARD_LIB.TIMECARD(SCH_1):PAGE164',
 PHYS_PAGE='14',
 XY='(-12950,8100)',
 ROT='5',
 VER='5',
 CDS_LIB='pld',
 CDS_PART_NAME='XC7A200T_2FBG484C_FBG484-G240-A',
 CLS_PN='G240-10069-01',
 VALUE='XC7A100T-1FGG484I',
 PRIM_FILE='./archive_libs/pld/xc7a200t_2fbg484c_fbg484/chips/chips.prt';

PART_NAME
 U25 'ISL80101IRAJZ_DFN10-G222-10136A':;

SECTION_NUMBER 1
 '@TIMECARD_LIB.TIMECARD(SCH_1):PAGE515_I151@ANALOG.ISL80101IRAJZ_DFN10(CHIPS)':
 C_PATH='@timecard_lib.timecard(sch_1):page515_i151@analog.isl80101irajz_dfn10(c~
hips)',
 P_PATH='@timecard_lib.timecard(sch_1):page31_i151@analog.isl80101irajz_dfn10(ch~
ips)',
 PATH='I151',
 DRAWING='@TIMECARD_LIB.TIMECARD(SCH_1):PAGE515',
 PHYS_PAGE='31',
 XY='(-7950,1750)',
 ROT='0',
 VER='1',
 CDS_LIB='analog',
 CDS_PART_NAME='ISL80101IRAJZ_DFN10-G222-10136A',
 CLS_PN='G222-10136-01',
 PART_NUMBER='ISL80101IRAJZ-T',
 PRIM_FILE='./archive_libs/analog/isl80101irajz_dfn10/chips/chips.prt';

PART_NAME
 U26 'TPS54824RNVR_VQFN18-G220-10657A':;

SECTION_NUMBER 1
 '@TIMECARD_LIB.TIMECARD(SCH_1):PAGE523_I11@STDLOGIC.TPS54824RNVR_VQFN18(CHIPS)':
 C_PATH='@timecard_lib.timecard(sch_1):page523_i11@stdlogic.tps54824rnvr_vqfn18(~
chips)',
 P_PATH='@timecard_lib.timecard(sch_1):page29_i11@stdlogic.tps54824rnvr_vqfn18(c~
hips)',
 PATH='I11',
 DRAWING='@TIMECARD_LIB.TIMECARD(SCH_1):PAGE523',
 PHYS_PAGE='29',
 XY='(-8650,4650)',
 ROT='0',
 VER='1',
 CDS_LIB='stdlogic',
 CDS_PART_NAME='TPS54824RNVR_VQFN18-G220-10657A',
 CLS_PN='G220-10657-01',
 VALUE='TPS54424RNVT',
 PRIM_FILE='./archive_libs/stdlogic/tps54824rnvr_vqfn18/chips/chips.prt';

PART_NAME
 U27 'SHT31A_DIS_B10KS_DFN8-A222-000A':;

SECTION_NUMBER 1
 '@TIMECARD_LIB.TIMECARD(SCH_1):PAGE7_I44@ANALOG.SHT31A_DIS_B10KS_DFN8(CHIPS)':
 C_PATH='@timecard_lib.timecard(sch_1):page7_i44@analog.sht31a_dis_b10ks_dfn8(ch~
ips)',
 P_PATH='@timecard_lib.timecard(sch_1):page18_i44@analog.sht31a_dis_b10ks_dfn8(c~
hips)',
 PATH='I44',
 DRAWING='@TIMECARD_LIB.TIMECARD(SCH_1):PAGE7',
 PHYS_PAGE='18',
 XY='(-6650,9150)',
 ROT='2',
 VER='1',
 CDS_LIB='analog',
 CDS_PART_NAME='SHT31A_DIS_B10KS_DFN8-A222-000A',
 CLS_PN='A222-00001-FB',
 VALUE='SHT31A-DIS-B10KS',
 PRIM_FILE='./archive_libs/analog/sht31a_dis_b10ks_dfn8/chips/chips.prt';

PART_NAME
 U28 'ICP_10100_LGA10-A222-00002-FB,A':;

SECTION_NUMBER 1
 '@TIMECARD_LIB.TIMECARD(SCH_1):PAGE8_I24@ANALOG.ICP_10100_LGA10(CHIPS)':
 C_PATH='@timecard_lib.timecard(sch_1):page8_i24@analog.icp_10100_lga10(chips)',
 P_PATH='@timecard_lib.timecard(sch_1):page19_i24@analog.icp_10100_lga10(chips)',
 PATH='I24',
 DRAWING='@TIMECARD_LIB.TIMECARD(SCH_1):PAGE8',
 PHYS_PAGE='19',
 XY='(-5900,8950)',
 ROT='2',
 VER='1',
 CDS_LIB='analog',
 CDS_PART_NAME='ICP_10100_LGA10-A222-00002-FB,A',
 CLS_PN='A222-00002-FB',
 VALUE='ICP-10100',
 PRIM_FILE='./archive_libs/analog/icp_10100_lga10/chips/chips.prt';

PART_NAME
 U29 'BNO080_LGA_28-A246-00002-FB,BNA':;

SECTION_NUMBER 1
 '@TIMECARD_LIB.TIMECARD(SCH_1):PAGE9_I29@LSI.BNO080_LGA_28(CHIPS)':
 C_PATH='@timecard_lib.timecard(sch_1):page9_i29@lsi.bno080_lga_28(chips)',
 P_PATH='@timecard_lib.timecard(sch_1):page20_i29@lsi.bno080_lga_28(chips)',
 PATH='I29',
 DRAWING='@TIMECARD_LIB.TIMECARD(SCH_1):PAGE9',
 PHYS_PAGE='20',
 XY='(-7500,10500)',
 ROT='0',
 VER='1',
 CDS_LIB='lsi',
 CDS_PART_NAME='BNO080_LGA_28-A246-00002-FB,BNA',
 CLS_PN='A246-00002-FB',
 VALUE='BNO085',
 PRIM_FILE='./archive_libs/lsi/bno080_lga_28/chips/chips.prt';

PART_NAME
 U30 'TS3A5018PWR_TSSOP16-G220-10324A':;

SECTION_NUMBER 1
 '@TIMECARD_LIB.TIMECARD(SCH_1):PAGE524_I425@STDLOGIC.TS3A5018PWR_TSSOP16(CHIPS)':
 C_PATH='@timecard_lib.timecard(sch_1):page524_i425@stdlogic.ts3a5018pwr_tssop16~
(chips)',
 P_PATH='@timecard_lib.timecard(sch_1):page24_i425@stdlogic.ts3a5018pwr_tssop16(~
chips)',
 PATH='I425',
 DRAWING='@TIMECARD_LIB.TIMECARD(SCH_1):PAGE524',
 PHYS_PAGE='24',
 XY='(-12650,6000)',
 ROT='2',
 VER='1',
 CDS_LIB='stdlogic',
 CDS_PART_NAME='TS3A5018PWR_TSSOP16-G220-10324A',
 CLS_PN='G220-10324-01',
 PART_NUMBER='TS3A5018PWR',
 PRIM_FILE='./archive_libs/stdlogic/ts3a5018pwr_tssop16/chips/chips.prt';

SECTION_NUMBER 2
 '@TIMECARD_LIB.TIMECARD(SCH_1):PAGE524_I473@STDLOGIC.TS3A5018PWR_TSSOP16(CHIPS)':
 C_PATH='@timecard_lib.timecard(sch_1):page524_i473@stdlogic.ts3a5018pwr_tssop16~
(chips)',
 P_PATH='@timecard_lib.timecard(sch_1):page24_i473@stdlogic.ts3a5018pwr_tssop16(~
chips)',
 PATH='I473',
 DRAWING='@TIMECARD_LIB.TIMECARD(SCH_1):PAGE524',
 PHYS_PAGE='24',
 XY='(-13850,2750)',
 ROT='0',
 VER='2',
 CDS_LIB='stdlogic',
 CDS_PART_NAME='TS3A5018PWR_TSSOP16-G220-10324A',
 CLS_PN='G220-10324-01',
 PRIM_FILE='./archive_libs/stdlogic/ts3a5018pwr_tssop16/chips/chips.prt';

PART_NAME
 U31 'CAT93C46VI_GT3_SOIC8-G221-1007A':;

SECTION_NUMBER 1
 '@TIMECARD_LIB.TIMECARD(SCH_1):PAGE524_I200@MEMORY.CAT93C46VI_GT3_SOIC8(CHIPS)':
 C_PATH='@timecard_lib.timecard(sch_1):page524_i200@memory.cat93c46vi_gt3_soic8(~
chips)',
 P_PATH='@timecard_lib.timecard(sch_1):page24_i200@memory.cat93c46vi_gt3_soic8(c~
hips)',
 PATH='I200',
 DRAWING='@TIMECARD_LIB.TIMECARD(SCH_1):PAGE524',
 PHYS_PAGE='24',
 XY='(-12050,7550)',
 ROT='2',
 VER='1',
 CDS_LIB='memory',
 CDS_PART_NAME='CAT93C46VI_GT3_SOIC8-G221-1007A',
 CLS_PN='G221-10075-01',
 PRIM_FILE='./archive_libs/memory/cat93c46vi_gt3_soic8/chips/chips.prt';

SECTION_NUMBER 2
 '@TIMECARD_LIB.TIMECARD(SCH_1):PAGE524_I201@MEMORY.CAT93C46VI_GT3_SOIC8(CHIPS)':
 C_PATH='@timecard_lib.timecard(sch_1):page524_i201@memory.cat93c46vi_gt3_soic8(~
chips)',
 P_PATH='@timecard_lib.timecard(sch_1):page24_i201@memory.cat93c46vi_gt3_soic8(c~
hips)',
 PATH='I201',
 DRAWING='@TIMECARD_LIB.TIMECARD(SCH_1):PAGE524',
 PHYS_PAGE='24',
 XY='(-13700,7700)',
 ROT='0',
 VER='2',
 CDS_LIB='memory',
 CDS_PART_NAME='CAT93C46VI_GT3_SOIC8-G221-1007A',
 CLS_PN='G221-10075-01',
 PRIM_FILE='./archive_libs/memory/cat93c46vi_gt3_soic8/chips/chips.prt';

PART_NAME
 U32 'PCA9508DP_TSSOP8-G223-10278-01':;

SECTION_NUMBER 1
 '@TIMECARD_LIB.TIMECARD(SCH_1):PAGE8_I51@STDLOGIC.PCA9508DP_TSSOP8(CHIPS)':
 C_PATH='@timecard_lib.timecard(sch_1):page8_i51@stdlogic.pca9508dp_tssop8(chips~
)',
 P_PATH='@timecard_lib.timecard(sch_1):page19_i51@stdlogic.pca9508dp_tssop8(chip~
s)',
 PATH='I51',
 DRAWING='@TIMECARD_LIB.TIMECARD(SCH_1):PAGE8',
 PHYS_PAGE='19',
 XY='(-8600,6250)',
 ROT='0',
 VER='1',
 CDS_LIB='stdlogic',
 CDS_PART_NAME='PCA9508DP_TSSOP8-G223-10278-01',
 CLS_PN='G223-10278-01',
 PRIM_FILE='./archive_libs/stdlogic/pca9508dp_tssop8/chips/chips.prt';

SECTION_NUMBER 2
 '@TIMECARD_LIB.TIMECARD(SCH_1):PAGE8_I52@STDLOGIC.PCA9508DP_TSSOP8(CHIPS)':
 C_PATH='@timecard_lib.timecard(sch_1):page8_i52@stdlogic.pca9508dp_tssop8(chips~
)',
 P_PATH='@timecard_lib.timecard(sch_1):page19_i52@stdlogic.pca9508dp_tssop8(chip~
s)',
 PATH='I52',
 DRAWING='@TIMECARD_LIB.TIMECARD(SCH_1):PAGE8',
 PHYS_PAGE='19',
 XY='(-3400,5850)',
 ROT='1',
 VER='2',
 CDS_LIB='stdlogic',
 CDS_PART_NAME='PCA9508DP_TSSOP8-G223-10278-01',
 CLS_PN='G223-10278-01',
 PRIM_FILE='./archive_libs/stdlogic/pca9508dp_tssop8/chips/chips.prt';

PART_NAME
 U33 'IS32FL3207_QWLA3_TR_QFN29-A223A':;

SECTION_NUMBER 1
 '@TIMECARD_LIB.TIMECARD(SCH_1):PAGE14_I219@INTERFACE.IS32FL3207_QWLA3_TR_QFN29(CHIPS)':
 C_PATH='@timecard_lib.timecard(sch_1):page14_i219@interface.is32fl3207_qwla3_tr~
_qfn29(chips)',
 P_PATH='@timecard_lib.timecard(sch_1):page26_i219@interface.is32fl3207_qwla3_tr~
_qfn29(chips)',
 PATH='I219',
 DRAWING='@TIMECARD_LIB.TIMECARD(SCH_1):PAGE14',
 PHYS_PAGE='26',
 XY='(-9200,5700)',
 ROT='0',
 VER='1',
 CDS_LIB='interface',
 CDS_PART_NAME='IS32FL3207_QWLA3_TR_QFN29-A223A',
 CLS_PN='A223-00002-FB',
 VALUE='IS32FL3207-QWLA3-TR',
 PRIM_FILE='./archive_libs/interface/is32fl3207_qwla3_tr_qfn29/chips/chips.prt';

PART_NAME
 U34 'TPS3808G18DBVR_SOT23_6-G222-00A':;

SECTION_NUMBER 1
 '@TIMECARD_LIB.TIMECARD(SCH_1):PAGE3_I139@ANALOG.TPS3808G18DBVR_SOT23_6(CHIPS)':
 C_PATH='@timecard_lib.timecard(sch_1):page3_i139@analog.tps3808g18dbvr_sot23_6(~
chips)',
 P_PATH='@timecard_lib.timecard(sch_1):page9_i139@analog.tps3808g18dbvr_sot23_6(~
chips)',
 PATH='I139',
 DRAWING='@TIMECARD_LIB.TIMECARD(SCH_1):PAGE3',
 PHYS_PAGE='9',
 XY='(-450,3750)',
 ROT='0',
 VER='1',
 CDS_LIB='analog',
 CDS_PART_NAME='TPS3808G18DBVR_SOT23_6-G222-00A',
 CLS_PN='G222-00082-01',
 PART_NUMBER='TPS3808G33DBVRG4',
 PRIM_FILE='./archive_libs/analog/tps3808g18dbvr_sot23_6/chips/chips.prt';

PART_NAME
 U35 'LM75BDP_TSSOP8-G220-10215-01':;

SECTION_NUMBER 1
 '@TIMECARD_LIB.TIMECARD(SCH_1):PAGE6_I59@INTERFACE.LM75BDP_TSSOP8(CHIPS)':
 C_PATH='@timecard_lib.timecard(sch_1):page6_i59@interface.lm75bdp_tssop8(chips)~
',
 P_PATH='@timecard_lib.timecard(sch_1):page17_i59@interface.lm75bdp_tssop8(chips~
)',
 PATH='I59',
 DRAWING='@TIMECARD_LIB.TIMECARD(SCH_1):PAGE6',
 PHYS_PAGE='17',
 XY='(-2700,4650)',
 ROT='0',
 VER='1',
 CDS_LIB='interface',
 CDS_PART_NAME='LM75BDP_TSSOP8-G220-10215-01',
 CLS_PN='G220-10215-01',
 PART_NUMBER='LM75BDP,118',
 PRIM_FILE='./archive_libs/interface/lm75bdp_tssop8/chips/chips.prt';

SECTION_NUMBER 2
 '@TIMECARD_LIB.TIMECARD(SCH_1):PAGE6_I90@INTERFACE.LM75BDP_TSSOP8(CHIPS)':
 C_PATH='@timecard_lib.timecard(sch_1):page6_i90@interface.lm75bdp_tssop8(chips)~
',
 P_PATH='@timecard_lib.timecard(sch_1):page17_i90@interface.lm75bdp_tssop8(chips~
)',
 PATH='I90',
 DRAWING='@TIMECARD_LIB.TIMECARD(SCH_1):PAGE6',
 PHYS_PAGE='17',
 XY='(-1050,1100)',
 ROT='5',
 VER='2',
 CDS_LIB='interface',
 CDS_PART_NAME='LM75BDP_TSSOP8-G220-10215-01',
 CLS_PN='G220-10215-01',
 PRIM_FILE='./archive_libs/interface/lm75bdp_tssop8/chips/chips.prt';

PART_NAME
 U36 'LM75BDP_TSSOP8-G220-10215-01':;

SECTION_NUMBER 1
 '@TIMECARD_LIB.TIMECARD(SCH_1):PAGE6_I81@INTERFACE.LM75BDP_TSSOP8(CHIPS)':
 C_PATH='@timecard_lib.timecard(sch_1):page6_i81@interface.lm75bdp_tssop8(chips)~
',
 P_PATH='@timecard_lib.timecard(sch_1):page17_i81@interface.lm75bdp_tssop8(chips~
)',
 PATH='I81',
 DRAWING='@TIMECARD_LIB.TIMECARD(SCH_1):PAGE6',
 PHYS_PAGE='17',
 XY='(-2700,1800)',
 ROT='0',
 VER='1',
 CDS_LIB='interface',
 CDS_PART_NAME='LM75BDP_TSSOP8-G220-10215-01',
 CLS_PN='G220-10215-01',
 PART_NUMBER='LM75BDP,118',
 PRIM_FILE='./archive_libs/interface/lm75bdp_tssop8/chips/chips.prt';

SECTION_NUMBER 2
 '@TIMECARD_LIB.TIMECARD(SCH_1):PAGE6_I66@INTERFACE.LM75BDP_TSSOP8(CHIPS)':
 C_PATH='@timecard_lib.timecard(sch_1):page6_i66@interface.lm75bdp_tssop8(chips)~
',
 P_PATH='@timecard_lib.timecard(sch_1):page17_i66@interface.lm75bdp_tssop8(chips~
)',
 PATH='I66',
 DRAWING='@TIMECARD_LIB.TIMECARD(SCH_1):PAGE6',
 PHYS_PAGE='17',
 XY='(-1050,3950)',
 ROT='5',
 VER='2',
 CDS_LIB='interface',
 CDS_PART_NAME='LM75BDP_TSSOP8-G220-10215-01',
 CLS_PN='G220-10215-01',
 PRIM_FILE='./archive_libs/interface/lm75bdp_tssop8/chips/chips.prt';

PART_NAME
 U37 'TS3A5018PWR_TSSOP16-G220-10324A':;

SECTION_NUMBER 1
 '@TIMECARD_LIB.TIMECARD(SCH_1):PAGE524_I448@STDLOGIC.TS3A5018PWR_TSSOP16(CHIPS)':
 C_PATH='@timecard_lib.timecard(sch_1):page524_i448@stdlogic.ts3a5018pwr_tssop16~
(chips)',
 P_PATH='@timecard_lib.timecard(sch_1):page24_i448@stdlogic.ts3a5018pwr_tssop16(~
chips)',
 PATH='I448',
 DRAWING='@TIMECARD_LIB.TIMECARD(SCH_1):PAGE524',
 PHYS_PAGE='24',
 XY='(-2100,5700)',
 ROT='0',
 VER='1',
 CDS_LIB='stdlogic',
 CDS_PART_NAME='TS3A5018PWR_TSSOP16-G220-10324A',
 CLS_PN='G220-10324-01',
 PART_NUMBER='TS3A5018PWR',
 PRIM_FILE='./archive_libs/stdlogic/ts3a5018pwr_tssop16/chips/chips.prt';

SECTION_NUMBER 2
 '@TIMECARD_LIB.TIMECARD(SCH_1):PAGE524_I478@STDLOGIC.TS3A5018PWR_TSSOP16(CHIPS)':
 C_PATH='@timecard_lib.timecard(sch_1):page524_i478@stdlogic.ts3a5018pwr_tssop16~
(chips)',
 P_PATH='@timecard_lib.timecard(sch_1):page24_i478@stdlogic.ts3a5018pwr_tssop16(~
chips)',
 PATH='I478',
 DRAWING='@TIMECARD_LIB.TIMECARD(SCH_1):PAGE524',
 PHYS_PAGE='24',
 XY='(-12550,2750)',
 ROT='0',
 VER='2',
 CDS_LIB='stdlogic',
 CDS_PART_NAME='TS3A5018PWR_TSSOP16-G220-10324A',
 CLS_PN='G220-10324-01',
 PRIM_FILE='./archive_libs/stdlogic/ts3a5018pwr_tssop16/chips/chips.prt';

PART_NAME
 U38 'TS3A5018PWR_TSSOP16-G220-10324A':;

SECTION_NUMBER 1
 '@TIMECARD_LIB.TIMECARD(SCH_1):PAGE524_I400@STDLOGIC.TS3A5018PWR_TSSOP16(CHIPS)':
 C_PATH='@timecard_lib.timecard(sch_1):page524_i400@stdlogic.ts3a5018pwr_tssop16~
(chips)',
 P_PATH='@timecard_lib.timecard(sch_1):page24_i400@stdlogic.ts3a5018pwr_tssop16(~
chips)',
 PATH='I400',
 DRAWING='@TIMECARD_LIB.TIMECARD(SCH_1):PAGE524',
 PHYS_PAGE='24',
 XY='(-7700,6000)',
 ROT='0',
 VER='1',
 CDS_LIB='stdlogic',
 CDS_PART_NAME='TS3A5018PWR_TSSOP16-G220-10324A',
 CLS_PN='G220-10324-01',
 PART_NUMBER='TS3A5018PWR',
 PRIM_FILE='./archive_libs/stdlogic/ts3a5018pwr_tssop16/chips/chips.prt';

SECTION_NUMBER 2
 '@TIMECARD_LIB.TIMECARD(SCH_1):PAGE524_I481@STDLOGIC.TS3A5018PWR_TSSOP16(CHIPS)':
 C_PATH='@timecard_lib.timecard(sch_1):page524_i481@stdlogic.ts3a5018pwr_tssop16~
(chips)',
 P_PATH='@timecard_lib.timecard(sch_1):page24_i481@stdlogic.ts3a5018pwr_tssop16(~
chips)',
 PATH='I481',
 DRAWING='@TIMECARD_LIB.TIMECARD(SCH_1):PAGE524',
 PHYS_PAGE='24',
 XY='(-11300,2750)',
 ROT='0',
 VER='2',
 CDS_LIB='stdlogic',
 CDS_PART_NAME='TS3A5018PWR_TSSOP16-G220-10324A',
 CLS_PN='G220-10324-01',
 PRIM_FILE='./archive_libs/stdlogic/ts3a5018pwr_tssop16/chips/chips.prt';

PART_NAME
 U39 'NLASB3157DFT2G_SC88-G223-10187A':;

SECTION_NUMBER 1
 '@TIMECARD_LIB.TIMECARD(SCH_1):PAGE524_I407@INTERFACE.NLASB3157DFT2G_SC88(CHIPS)':
 C_PATH='@timecard_lib.timecard(sch_1):page524_i407@interface.nlasb3157dft2g_sc8~
8(chips)',
 P_PATH='@timecard_lib.timecard(sch_1):page24_i407@interface.nlasb3157dft2g_sc88~
(chips)',
 PATH='I407',
 DRAWING='@TIMECARD_LIB.TIMECARD(SCH_1):PAGE524',
 PHYS_PAGE='24',
 XY='(-7100,4000)',
 ROT='2',
 VER='1',
 CDS_LIB='interface',
 CDS_PART_NAME='NLASB3157DFT2G_SC88-G223-10187A',
 CLS_PN='G223-10187-01',
 PRIM_FILE='./archive_libs/interface/nlasb3157dft2g_sc88/chips/chips.prt';

SECTION_NUMBER 2
 '@TIMECARD_LIB.TIMECARD(SCH_1):PAGE524_I485@INTERFACE.NLASB3157DFT2G_SC88(CHIPS)':
 C_PATH='@timecard_lib.timecard(sch_1):page524_i485@interface.nlasb3157dft2g_sc8~
8(chips)',
 P_PATH='@timecard_lib.timecard(sch_1):page24_i485@interface.nlasb3157dft2g_sc88~
(chips)',
 PATH='I485',
 DRAWING='@TIMECARD_LIB.TIMECARD(SCH_1):PAGE524',
 PHYS_PAGE='24',
 XY='(-3650,2750)',
 ROT='0',
 VER='2',
 CDS_LIB='interface',
 CDS_PART_NAME='NLASB3157DFT2G_SC88-G223-10187A',
 CLS_PN='G223-10187-01',
 PRIM_FILE='./archive_libs/interface/nlasb3157dft2g_sc88/chips/chips.prt';

PART_NAME
 U40 'NLASB3157DFT2G_SC88-G223-10187A':;

SECTION_NUMBER 1
 '@TIMECARD_LIB.TIMECARD(SCH_1):PAGE524_I408@INTERFACE.NLASB3157DFT2G_SC88(CHIPS)':
 C_PATH='@timecard_lib.timecard(sch_1):page524_i408@interface.nlasb3157dft2g_sc8~
8(chips)',
 P_PATH='@timecard_lib.timecard(sch_1):page24_i408@interface.nlasb3157dft2g_sc88~
(chips)',
 PATH='I408',
 DRAWING='@TIMECARD_LIB.TIMECARD(SCH_1):PAGE524',
 PHYS_PAGE='24',
 XY='(-7100,3350)',
 ROT='2',
 VER='1',
 CDS_LIB='interface',
 CDS_PART_NAME='NLASB3157DFT2G_SC88-G223-10187A',
 CLS_PN='G223-10187-01',
 PRIM_FILE='./archive_libs/interface/nlasb3157dft2g_sc88/chips/chips.prt';

SECTION_NUMBER 2
 '@TIMECARD_LIB.TIMECARD(SCH_1):PAGE524_I491@INTERFACE.NLASB3157DFT2G_SC88(CHIPS)':
 C_PATH='@timecard_lib.timecard(sch_1):page524_i491@interface.nlasb3157dft2g_sc8~
8(chips)',
 P_PATH='@timecard_lib.timecard(sch_1):page24_i491@interface.nlasb3157dft2g_sc88~
(chips)',
 PATH='I491',
 DRAWING='@TIMECARD_LIB.TIMECARD(SCH_1):PAGE524',
 PHYS_PAGE='24',
 XY='(-5000,2750)',
 ROT='0',
 VER='2',
 CDS_LIB='interface',
 CDS_PART_NAME='NLASB3157DFT2G_SC88-G223-10187A',
 CLS_PN='G223-10187-01',
 PRIM_FILE='./archive_libs/interface/nlasb3157dft2g_sc88/chips/chips.prt';

PART_NAME
 U41 'ISL80101IRAJZ_DFN10-G222-10136A':;

SECTION_NUMBER 1
 '@TIMECARD_LIB.TIMECARD(SCH_1):PAGE525_I29@ANALOG.ISL80101IRAJZ_DFN10(CHIPS)':
 C_PATH='@timecard_lib.timecard(sch_1):page525_i29@analog.isl80101irajz_dfn10(ch~
ips)',
 P_PATH='@timecard_lib.timecard(sch_1):page33_i29@analog.isl80101irajz_dfn10(chi~
ps)',
 PATH='I29',
 DRAWING='@TIMECARD_LIB.TIMECARD(SCH_1):PAGE525',
 PHYS_PAGE='33',
 XY='(2150,2950)',
 ROT='0',
 VER='1',
 CDS_LIB='analog',
 CDS_PART_NAME='ISL80101IRAJZ_DFN10-G222-10136A',
 CLS_PN='G222-10136-01',
 PART_NUMBER='ISL80101IRAJZ-T',
 PRIM_FILE='./archive_libs/analog/isl80101irajz_dfn10/chips/chips.prt';

PART_NAME
 Y1 'XTAL_2-G131-10075-01':;

SECTION_NUMBER 1
 '@TIMECARD_LIB.TIMECARD(SCH_1):PAGE9_I16@CLOCK.XTAL_2(CHIPS)':
 C_PATH='@timecard_lib.timecard(sch_1):page9_i16@clock.xtal_2(chips)',
 P_PATH='@timecard_lib.timecard(sch_1):page20_i16@clock.xtal_2(chips)',
 PATH='I16',
 DRAWING='@TIMECARD_LIB.TIMECARD(SCH_1):PAGE9',
 PHYS_PAGE='20',
 XY='(-4700,10100)',
 ROT='1',
 VER='1',
 CDS_LIB='clock',
 CDS_PART_NAME='XTAL_2-G131-10075-01',
 CLS_PN='G131-10075-01',
 PART_NUMBER='9H03200012',
 PRIM_FILE='./archive_libs/clock/xtal_2/chips/chips.prt';

PART_NAME
 Y2 'XTAL_4-G131-10038-02':;

SECTION_NUMBER 1
 '@TIMECARD_LIB.TIMECARD(SCH_1):PAGE524_I8@CLOCK.XTAL_4(CHIPS)':
 C_PATH='@timecard_lib.timecard(sch_1):page524_i8@clock.xtal_4(chips)',
 P_PATH='@timecard_lib.timecard(sch_1):page24_i8@clock.xtal_4(chips)',
 PATH='I8',
 DRAWING='@TIMECARD_LIB.TIMECARD(SCH_1):PAGE524',
 PHYS_PAGE='24',
 XY='(-10500,8050)',
 ROT='0',
 VER='1',
 CDS_LIB='clock',
 CDS_PART_NAME='XTAL_4-G131-10038-02',
 CLS_PN='G131-10038-02',
 PART_NUMBER='7M12000031',
 PRIM_FILE='./archive_libs/clock/xtal_4/chips/chips.prt';

PART_NAME
 Y3 'OSC6P_V2-A130-00003-AW':;

SECTION_NUMBER 1
 '@TIMECARD_LIB.TIMECARD(SCH_1):PAGE522_I144@CLOCK.OSC6P_V2(CHIPS)':
 C_PATH='@timecard_lib.timecard(sch_1):page522_i144@clock.osc6p_v2(chips)',
 P_PATH='@timecard_lib.timecard(sch_1):page15_i144@clock.osc6p_v2(chips)',
 PATH='I144',
 DRAWING='@TIMECARD_LIB.TIMECARD(SCH_1):PAGE522',
 PHYS_PAGE='15',
 XY='(-8750,6750)',
 ROT='0',
 VER='1',
 CDS_LIB='clock',
 CDS_PART_NAME='OSC6P_V2-A130-00003-AW',
 CLS_PN='A130-00003-AW',
 PART_NUMBER='LMK62A2-200M00SIAR',
 PRIM_FILE='./archive_libs/clock/osc6p_v2/chips/chips.prt';

PART_NAME
 Y4 'OSC6P_V2-A130-00004-AW':;

SECTION_NUMBER 1
 '@TIMECARD_LIB.TIMECARD(SCH_1):PAGE522_I145@CLOCK.OSC6P_V2(CHIPS)':
 C_PATH='@timecard_lib.timecard(sch_1):page522_i145@clock.osc6p_v2(chips)',
 P_PATH='@timecard_lib.timecard(sch_1):page15_i145@clock.osc6p_v2(chips)',
 PATH='I145',
 DRAWING='@TIMECARD_LIB.TIMECARD(SCH_1):PAGE522',
 PHYS_PAGE='15',
 XY='(-8750,3200)',
 ROT='0',
 VER='1',
 CDS_LIB='clock',
 CDS_PART_NAME='OSC6P_V2-A130-00004-AW',
 CLS_PN='A130-00004-AW',
 PART_NUMBER='LMK61A2-125M00SIAR',
 PRIM_FILE='./archive_libs/clock/osc6p_v2/chips/chips.prt';

END.
